G04 ================== begin FILE IDENTIFICATION RECORD ==================*
G04 Layout Name:  15126-1b.brd*
G04 Film Name:    L10*
G04 File Format:  Gerber RS274X*
G04 File Origin:  Cadence Allegro 16.6-2015-S079*
G04 Origin Date:  Fri Feb 10 17:22:58 2017*
G04 *
G04 Layer:  VIA CLASS/L10*
G04 Layer:  PIN/L10*
G04 Layer:  ETCH/L10*
G04 Layer:  DRAWING FORMAT/LAYER_PCB_STORY*
G04 Layer:  DRAWING FORMAT/LAYER_L10*
G04 *
G04 Offset:    (0.00 0.00)*
G04 Mirror:    No*
G04 Mode:      Positive*
G04 Rotation:  0*
G04 FullContactRelief:  No*
G04 UndefLineWidth:     6.00*
G04 ================== end FILE IDENTIFICATION RECORD ====================*
%FSLAX35Y35*MOIN*%
%IR0*IPPOS*OFA0.00000B0.00000*MIA0B0*SFA1.00000B1.00000*%
%ADD12C,.02*%
%ADD21C,.031*%
%ADD10C,.022*%
%ADD11C,.032*%
%ADD22C,.06*%
%ADD16C,.044*%
%ADD13C,.071*%
%ADD23C,.045*%
%ADD19C,.018*%
%ADD20C,.064*%
%ADD18C,.028*%
%ADD14C,.046*%
%ADD17C,.057*%
%ADD15C,.14*%
%ADD24C,.01*%
%ADD25C,.012*%
%ADD26C,.014*%
%ADD27C,.015*%
%ADD28C,.025*%
%ADD29C,.016*%
%ADD30C,.006*%
%ADD31C,.005*%
%ADD32C,.008*%
%ADD33C,.0035*%
%ADD34C,.00351*%
%ADD35C,.009*%
%ADD36C,.0045*%
%ADD37C,.00352*%
%ADD38C,.0056*%
%ADD39C,.00399*%
%ADD45O,.07202X.12102*%
%ADD46C,.03004*%
%ADD44C,.03204*%
%ADD47C,.06004*%
%ADD51C,.06104*%
%ADD49C,.02604*%
%ADD48C,.06204*%
%ADD43C,.02804*%
%ADD41C,.05604*%
%ADD50C,.05506*%
%ADD42C,.11204*%
%ADD40C,.11404*%
G75*
%LPD*%
G75*
G36*
G01X1973300Y-60000D02*
X-19810D01*
Y-34500D01*
X1973300D01*
Y-60000D01*
G37*
G36*
G01X-16400Y171200D02*
X-21000Y175800D01*
Y192483D01*
G02X-20317Y192766I400J0D01*
G01X-13366Y185814D01*
X-5580D01*
G02X-5397Y185059I-1J-400D01*
G03X-5813Y171943I3428J-6673D01*
G02X-6018Y171200I-205J-343D01*
G01X-16400D01*
G37*
G36*
G01X-10800Y191812D02*
X-15512Y196524D01*
Y235484D01*
X-1316Y249681D01*
Y273204D01*
X-551Y273968D01*
X-30D01*
X997Y272942D01*
X1011Y272913D01*
G03X3671Y273567I1258J619D01*
G01X3670Y273570D01*
Y274233D01*
X3588Y274315D01*
G02X3729Y274656I141J141D01*
G01X5085D01*
G03Y277460I35J1402D01*
G01X4878D01*
X2277Y280060D01*
X-3487D01*
X-7284Y276263D01*
Y252067D01*
X-20317Y239034D01*
G02X-21000Y239317I-283J283D01*
G01Y339000D01*
X-17400Y342600D01*
X4900D01*
X5876Y341624D01*
Y310081D01*
X4014Y308219D01*
Y307716D01*
X2355Y306056D01*
Y301158D01*
X8800Y294713D01*
Y271800D01*
X2000Y265000D01*
Y235000D01*
X7000Y230000D01*
Y195900D01*
X10406Y192494D01*
G02X10123Y191812I-283J-282D01*
G01X-10800D01*
G37*
G36*
G01X-20621Y661811D02*
G02X-19685Y662747I936J0D01*
G01X1972600D01*
Y637600D01*
X-20412D01*
G02X-20621Y638189I726J589D01*
G01Y661811D01*
G37*
G36*
G01X-13743Y22500D02*
Y61839D01*
X-15558Y63654D01*
Y71051D01*
X-13743Y72866D01*
Y72957D01*
X-11875Y74825D01*
X-8000D01*
X-2431Y80394D01*
G02X-1893Y80419I283J-283D01*
G03X400Y81422I893J1081D01*
G02X799Y81800I399J-22D01*
G01X17000D01*
X19800Y79000D01*
Y60100D01*
X21200Y58700D01*
Y57475D01*
G03Y55325I900J-1075D01*
G01Y48500D01*
X19900Y47200D01*
Y30200D01*
X18300Y28600D01*
X11353D01*
G03X5967I-2693J-1326D01*
G01X5433D01*
X5373Y28683D01*
G03X3538Y29874I-2440J-1750D01*
G03X-2Y27561I-2936J628D01*
G03X127Y25870I2936J-626D01*
G03X-298Y25145I941J-1039D01*
G01X-311Y25089D01*
X-2900Y22500D01*
X-13743D01*
G37*
G36*
G01X1875Y171943D02*
G03X1459Y185059I-3844J6443D01*
G02X1642Y185814I184J355D01*
G01X14617D01*
G02X14800Y185059I-1J-400D01*
G03X14384Y171943I3428J-6673D01*
G02X14179Y171200I-205J-343D01*
G01X2080D01*
G02X1875Y171943I0J400D01*
G37*
G36*
G01X22072D02*
G03X21656Y185059I-3844J6443D01*
G02X21839Y185814I184J355D01*
G01X40680D01*
G02X40863Y185059I-1J-400D01*
G03X38322Y173842I3428J-6673D01*
G02X38003Y173200I-319J-242D01*
G01X37500D01*
X35500Y171200D01*
X22277D01*
G02X22072Y171943I0J400D01*
G37*
G36*
G01X13300Y197000D02*
X12100Y198200D01*
Y232800D01*
X9100Y235800D01*
Y264400D01*
X13900Y269200D01*
Y336948D01*
X16252Y339300D01*
X38757D01*
X39733Y338324D01*
Y275249D01*
X39716Y275210D01*
G03Y274084I1284J-563D01*
G01X39733Y274045D01*
Y266559D01*
G03X39248Y265350I1267J-1210D01*
G01Y261986D01*
X39733Y261501D01*
Y199503D01*
X37230Y197000D01*
X13300D01*
G37*
G36*
G01X53088Y512400D02*
X45300Y520188D01*
Y526600D01*
X47400Y528700D01*
X66900D01*
X68200Y527400D01*
Y516200D01*
X64400Y512400D01*
X53088D01*
G37*
G36*
G01X53000Y223300D02*
X51800Y224500D01*
Y252710D01*
X56435D01*
G03X58738Y255338I1065J1390D01*
G01X58271Y255806D01*
X58682Y256218D01*
G03X56224Y258712I-1238J1238D01*
G01X52578D01*
G02X52295Y259395I0J400D01*
G01X59984Y267084D01*
X72912D01*
X74529Y265467D01*
Y265408D01*
X74988Y264949D01*
Y224634D01*
X73654Y223300D01*
X53000D01*
G37*
G36*
G01X165981Y206500D02*
X162342D01*
X161542Y205700D01*
X156242D01*
X154942Y204400D01*
X139589D01*
X136200Y207789D01*
Y365298D01*
X137100Y366198D01*
X169243D01*
X170259Y365182D01*
Y210778D01*
X165981Y206500D01*
G37*
G36*
G01X151678Y399398D02*
X162278D01*
X168742Y392935D01*
Y369100D01*
X167844Y368202D01*
X136998D01*
X136200Y369000D01*
Y390900D01*
X135032Y392069D01*
Y395752D01*
X133060Y397723D01*
X131500Y399283D01*
Y403000D01*
X132500Y404000D01*
X147077D01*
X149109Y401967D01*
X151678Y399398D01*
G37*
G36*
G01X378886Y24770D02*
X376568Y27088D01*
X366288D01*
G02X365906Y27604I0J400D01*
G03X363224I-1341J410D01*
G02X362842Y27088I-382J-116D01*
G01X362446D01*
Y27335D01*
X362468Y27378D01*
G03X359877Y27604I-1250J636D01*
G02X359495Y27088I-382J-116D01*
G01X356246D01*
G02X355864Y27606I0J400D01*
G03X353186I-1339J416D01*
G02X352804Y27088I-382J-118D01*
G01X352403D01*
Y27336D01*
X352425Y27379D01*
G03X349840Y27606I-1246J643D01*
G02X349458Y27088I-382J-118D01*
G01X346207D01*
G02X345825Y27606I0J400D01*
G03X343147I-1339J416D01*
G02X342765Y27088I-382J-118D01*
G01X342364D01*
Y27336D01*
X342386Y27379D01*
G03X339801Y27606I-1246J643D01*
G02X339419Y27088I-382J-118D01*
G01X336169D01*
G02X335787Y27604I0J400D01*
G03X333105I-1341J410D01*
G02X332723Y27088I-382J-116D01*
G01X332328D01*
Y27335D01*
X332350Y27378D01*
G03X329759Y27604I-1250J636D01*
G02X329377Y27088I-382J-116D01*
G01X326130D01*
G02X325748Y27604I0J400D01*
G03X323066I-1341J410D01*
G02X322684Y27088I-382J-116D01*
G01X322289D01*
Y27335D01*
X322311Y27378D01*
G03X319720Y27604I-1250J636D01*
G02X319338Y27088I-382J-116D01*
G01X316091D01*
G02X315709Y27604I0J400D01*
G03X313027I-1341J410D01*
G02X312645Y27088I-382J-116D01*
G01X309398D01*
G02X309016Y27604I0J400D01*
G03X307671Y29416I-1341J410D01*
G02X307470Y29616I-1J200D01*
G01Y30312D01*
G02X307919Y30709I400J0D01*
G03Y33491I173J1391D01*
G02X307470Y33888I-49J397D01*
G01Y34355D01*
G02X307671Y34555I200J0D01*
G03Y37359I4J1402D01*
G02X307470Y37559I-1J200D01*
G01Y48929D01*
G02X307888Y49328I400J0D01*
G03Y52130I62J1401D01*
G02X307470Y52529I-18J399D01*
G01Y53255D01*
G02X307671Y53455I200J0D01*
G03Y56259I4J1402D01*
G02X307470Y56459I-1J200D01*
G01Y66001D01*
G02X307883Y66401I400J0D01*
G03X308924Y68789I45J1401D01*
G02X308938Y69365I284J281D01*
G03X307897Y71799I-946J1035D01*
G02X307470Y72198I-27J399D01*
G01Y72200D01*
G02X307660Y72400I200J0D01*
G03Y75200I-68J1400D01*
G02X307470Y75400I10J200D01*
G01Y85617D01*
G02X307936Y86011I400J0D01*
G03Y88777I230J1383D01*
G02X307470Y89171I-66J394D01*
G01Y91055D01*
G02X307671Y91255I200J0D01*
G03Y94059I4J1402D01*
G02X307470Y94259I-1J200D01*
G01Y100820D01*
X336100Y129450D01*
Y215663D01*
G03Y218155I-642J1246D01*
G01Y219563D01*
G03Y222055I-642J1246D01*
G01Y223463D01*
G03Y225955I-642J1246D01*
G01Y227364D01*
G03Y229856I-642J1246D01*
G01Y231264D01*
G03X336475Y233475I-642J1246D01*
G01X336941Y233941D01*
G02X337582Y233836I283J-283D01*
G03X339462Y235716I1256J624D01*
G02X339357Y236357I178J358D01*
G01X341933Y238933D01*
X342031Y238920D01*
G03X343607Y240496I187J1389D01*
G01X343594Y240594D01*
X344160Y241160D01*
G02X344699Y241184I283J-283D01*
G03X346674Y243159I899J1076D01*
G02X346698Y243698I307J256D01*
G01X351777Y248777D01*
X351896Y248736D01*
G03X353681Y250521I461J1324D01*
G01X353640Y250640D01*
X354101Y251101D01*
G02X354684Y251083I283J-282D01*
G03X356663Y253062I1053J926D01*
G02X356645Y253645I264J300D01*
G01X357043Y254043D01*
G02X357724Y253805I283J-282D01*
G03X359272Y255353I1393J155D01*
G02X359034Y256034I44J398D01*
G01X359515Y256515D01*
X359560Y256530D01*
G03X360447Y257417I-443J1330D01*
G01X360462Y257462D01*
X361668Y258668D01*
X361801Y258592D01*
G03X363792Y260347I696J1217D01*
G02X363894Y260606I184J77D01*
G03X365445Y262009I-1397J3103D01*
G01X365840Y262696D01*
X365912Y262720D01*
G03X366885Y263291I-881J2616D01*
G02X367158Y263287I134J-148D01*
G03X369011Y265388I970J1012D01*
G02X368981Y265981I253J310D01*
G01X369900Y266900D01*
X417500D01*
X417506Y266894D01*
X426701D01*
X427704Y265891D01*
Y263700D01*
X426804Y262800D01*
X423700D01*
X423200Y262300D01*
Y258441D01*
X422500Y257741D01*
X419212D01*
X418900Y257429D01*
Y255299D01*
G02X418408Y254910I-400J0D01*
G03X417001Y252656I-324J-1364D01*
G01X417116Y252516D01*
X410400Y245800D01*
Y135090D01*
X423840Y121650D01*
X424990D01*
X451704Y94936D01*
G02X451453Y94254I-283J-283D01*
G03X453070Y92637I120J-1497D01*
G02X453752Y92888I399J-32D01*
G01X454420Y92220D01*
Y91717D01*
X454264Y91682D01*
G03X453562Y89338I305J-1368D01*
G02X453558Y88777I-287J-278D01*
G03X454267Y86254I1061J-1063D01*
G01X454420Y86217D01*
Y73007D01*
X454257Y72976D01*
G03Y70024I276J-1476D01*
G01X454420Y69993D01*
Y69156D01*
X454259Y69124D01*
G03Y66374I274J-1375D01*
G01X454420Y66342D01*
Y53917D01*
X454264Y53882D01*
G03X453717Y51400I305J-1368D01*
G02X453715Y50763I-243J-318D01*
G03X454267Y48104I904J-1199D01*
G01X454420Y48067D01*
Y35207D01*
X454257Y35176D01*
G03X453034Y33601I276J-1476D01*
G01X453040Y33510D01*
X448878Y29348D01*
X448755Y29398D01*
G03X446928Y27571I-529J-1298D01*
G01X446978Y27448D01*
X444300Y24770D01*
X392995D01*
X392539Y25226D01*
X383217D01*
X382761Y24770D01*
X382198D01*
X382194Y24965D01*
G03X381635Y26053I-1402J-33D01*
G02Y26692I241J320D01*
G03X379949I-843J1120D01*
G02Y26053I-241J-320D01*
G03X379390Y24965I843J-1121D01*
G01X379386Y24770D01*
X378886D01*
G37*
G36*
G01X350136Y334700D02*
G03X348808Y335301I-1158J-791D01*
G01X348711Y335289D01*
X346130Y337870D01*
G02X346232Y338510I283J283D01*
G03X344348Y340394I-634J1250D01*
G02X343708Y340292I-357J181D01*
G01X343245Y340755D01*
G03X341264Y342736I-1027J954D01*
G01X340238Y343762D01*
X340230Y343830D01*
G03X339008Y345052I-1392J-170D01*
G01X338940Y345060D01*
X338525Y345475D01*
G02X338814Y346158I282J283D01*
G03X338108Y348757I24J1402D01*
G02X337500Y349099I-208J342D01*
G01Y349921D01*
G02X338108Y350263I400J0D01*
G03Y352657I730J1197D01*
G02X337500Y352999I-208J342D01*
G01Y353821D01*
G02X338108Y354163I400J0D01*
G03Y356557I730J1197D01*
G02X337500Y356899I-208J342D01*
G01Y357721D01*
G02X338108Y358063I400J0D01*
G03Y360457I730J1197D01*
G02X337500Y360799I-208J342D01*
G01Y361621D01*
G02X338108Y361963I400J0D01*
G03Y364357I730J1197D01*
G02X337500Y364699I-208J342D01*
G01Y369420D01*
G02X338108Y369762I400J0D01*
G03Y372156I730J1197D01*
G02X337500Y372498I-208J342D01*
G01Y373321D01*
G02X338108Y373663I400J0D01*
G03Y376057I730J1197D01*
G02X337500Y376399I-208J342D01*
G01Y377221D01*
G02X338108Y377563I400J0D01*
G03Y379957I730J1197D01*
G02X337500Y380299I-208J342D01*
G01Y386000D01*
X340140Y388640D01*
G02X340821Y388391I282J-283D01*
G03X342336Y389906I1397J118D01*
G02X342087Y390587I34J399D01*
G01X350650Y399150D01*
X402256D01*
X402296Y399131D01*
G03X403488I596J1269D01*
G01X403528Y399150D01*
X404950D01*
X408600Y395500D01*
Y373900D01*
X404656Y369956D01*
G02X404081Y369966I-283J283D01*
G03X402100Y367985I-1025J-956D01*
G02X402110Y367410I-273J-292D01*
G01X401741Y367041D01*
G02X401063Y367266I-282J283D01*
G03X399470Y365673I-1387J-206D01*
G02X399695Y364995I-58J-396D01*
G01X399167Y364467D01*
X399131Y364452D01*
G03X398384Y363705I545J-1292D01*
G01X398369Y363669D01*
X398100Y363400D01*
X394306D01*
X394264Y363545D01*
G03X391568I-1348J-385D01*
G01X391526Y363400D01*
X387547D01*
X387505Y363545D01*
G03X385200Y362135I-1348J-385D01*
G01Y360285D01*
G03X386159Y357858I957J-1025D01*
G01X386242D01*
X388874Y355226D01*
G02X388801Y354602I-283J-283D01*
G03X390730Y352673I736J-1193D01*
G02X391354Y352746I341J-210D01*
G01X391796Y352304D01*
G03X393760Y350340I1120J-844D01*
G01X394600Y349500D01*
X415600D01*
X421100Y344000D01*
X429941D01*
X431998Y341943D01*
Y335723D01*
X430975Y334700D01*
X373282D01*
G02X372888Y335169I0J400D01*
G03X370126I-1381J240D01*
G02X369732Y334700I-394J-69D01*
G01X368783D01*
X368741Y334720D01*
G03X367513I-614J-1260D01*
G01X367471Y334700D01*
X360751D01*
G02X360388Y335269I0J400D01*
G03X357846I-1271J591D01*
G02X357483Y334700I-363J-169D01*
G01X356895D01*
G03X354579I-1158J-791D01*
G01X353991D01*
G02X353628Y335269I0J400D01*
G03X351086I-1271J591D01*
G02X350723Y334700I-363J-169D01*
G01X350136D01*
G37*
G36*
G01X344702Y330880D02*
X344755Y330840D01*
G03X346442Y330841I843J1120D01*
G01X346496Y330881D01*
X347239Y330882D01*
G02X347625Y330377I0J-400D01*
G03X350330Y330378I1353J-368D01*
G02X350716Y330884I386J106D01*
G01X351064D01*
X351254Y331074D01*
X351395Y330940D01*
G03X353749Y332130I962J1020D01*
G02X354146Y332579I397J49D01*
G01X355292D01*
X355321Y332570D01*
G03X356153I416J1339D01*
G01X356182Y332579D01*
X363074D01*
G02X363446Y332030I1J-400D01*
G03X366147Y331592I1302J-521D01*
G02X366778Y331941I399J23D01*
G01X369248D01*
X369548Y332241D01*
Y332279D01*
X369848Y332579D01*
X379941D01*
X382050Y330470D01*
Y323440D01*
X379448Y320841D01*
X365648D01*
X364746Y319938D01*
X364037D01*
X360464Y316365D01*
X359148D01*
X359123Y316340D01*
G02X358444Y316564I-283J282D01*
G03X355658Y316267I-1387J-204D01*
G02X355259Y315841I-399J-26D01*
G01X355172D01*
X354648Y316365D01*
X347011D01*
X346988Y316539D01*
G03X344281Y315878I-1390J-179D01*
G02X343906Y315341I-376J-137D01*
G01X343265D01*
G03X341226Y315400I-1047J-932D01*
G01X341167Y315341D01*
X341148D01*
X339648Y313841D01*
X339080D01*
X339064Y313844D01*
G03X337457Y312701I-226J-1384D01*
G01X337446Y312639D01*
X336648Y311841D01*
X335896D01*
X335868Y311850D01*
G03X335048I-410J-1341D01*
G01X335020Y311841D01*
X333867D01*
G02X333470Y312290I0J400D01*
G03X330686I-1392J170D01*
G02X330289Y311841I-397J-49D01*
G01X329136D01*
X329108Y311850D01*
G03X328288I-410J-1341D01*
G01X328260Y311841D01*
X327107D01*
G02X326710Y312290I0J400D01*
G03X323926I-1392J170D01*
G02X323529Y311841I-397J-49D01*
G01X322376D01*
X322348Y311850D01*
G03X321528I-410J-1341D01*
G01X321500Y311841D01*
X320347D01*
G02X319950Y312290I0J400D01*
G03X317953Y313725I-1392J170D01*
G01X317825Y313664D01*
X316410Y315079D01*
X316396Y315103D01*
G03X315849Y315640I-1218J-694D01*
G01X315148Y316341D01*
X313211D01*
X313191Y316518D01*
G03X310405I-1393J-158D01*
G01X310385Y316341D01*
X306452D01*
X306432Y316518D01*
G03X303646I-1393J-158D01*
G01X303626Y316341D01*
X300199D01*
X299670Y316870D01*
Y320084D01*
X299671Y320096D01*
G03Y320424I-1392J164D01*
G01X299670Y320436D01*
Y323984D01*
X299671Y323996D01*
G03Y324324I-1392J164D01*
G01X299670Y324336D01*
Y327884D01*
X299671Y327896D01*
G03Y328224I-1392J164D01*
G01X299670Y328236D01*
Y329743D01*
X300064Y330137D01*
X300257Y329945D01*
X300264Y329874D01*
G03X303017Y330356I1395J135D01*
G02X303405Y330855I388J99D01*
G01X304174D01*
X304226Y330818D01*
G03X305854Y330819I813J1142D01*
G01X305906Y330856D01*
X306672Y330857D01*
G02X307060Y330357I1J-400D01*
G03X309776Y330359I1358J-348D01*
G02X310163Y330859I387J100D01*
G01X310927D01*
X310980Y330822D01*
G03X312618Y330823I818J1138D01*
G01X312670Y330860D01*
X313433Y330861D01*
G02X313821Y330360I1J-400D01*
G03X316535Y330362I1357J-351D01*
G02X316922Y330863I387J101D01*
G01X317682D01*
X317735Y330825D01*
G03X319383Y330826I823J1135D01*
G01X319435Y330864D01*
X320194Y330865D01*
G02X320582Y330364I1J-400D01*
G03X323294Y330365I1356J-355D01*
G02X323681Y330867I387J102D01*
G01X324437D01*
X324490Y330829D01*
G03X326207Y330876I828J1131D01*
G01X326958D01*
G02X327344Y330372I0J-400D01*
G03X330052I1354J-363D01*
G02X330438Y330876I386J104D01*
G01X331189D01*
G03X332967I889J1084D01*
G01X333718D01*
G02X334104Y330372I0J-400D01*
G03X336812I1354J-363D01*
G02X337198Y330876I386J104D01*
G01X337949D01*
G03X339677Y330837I889J1084D01*
G01X339731Y330877D01*
X340478D01*
G02X340864Y330373I0J-400D01*
G03X343571Y330375I1354J-364D01*
G02X343957Y330879I386J104D01*
G01X344702Y330880D01*
G37*
G36*
G01X374080Y512730D02*
X371670Y515140D01*
Y542530D01*
X374580Y545440D01*
X375724D01*
G03X377934I1105J863D01*
G01X379340D01*
X381640Y543140D01*
Y514420D01*
X379950Y512730D01*
X374080D01*
G37*
G36*
G01X474803Y273000D02*
X473302Y274502D01*
X470582D01*
G02X470183Y274923I0J400D01*
G03X467383I-1400J74D01*
G02X466984Y274502I-399J-21D01*
G01X447798D01*
X445000Y277300D01*
Y291011D01*
G02X445562Y291377I400J0D01*
G03X447385Y291754I647J1465D01*
G02X447972Y291753I293J-272D01*
G03X449695Y291335I1176J1088D01*
G02X450200Y291115I137J-376D01*
G03X453085Y290978I1475J624D01*
G02X453794Y290967I352J-190D01*
G03X455207Y293288I1432J719D01*
G02X454802Y293687I-5J400D01*
G03X454796Y293819I-1402J2D01*
G02X455139Y294254I398J39D01*
G03X453700Y296877I-217J1587D01*
G02X453079Y296889I-306J258D01*
G03X451653Y294310I-1263J-985D01*
G02X452009Y293862I-41J-398D01*
G03X451999Y293728I1391J-171D01*
G02X451614Y293340I-400J12D01*
G03X451128Y293245I61J-1601D01*
G02X450623Y293465I-137J376D01*
G03X447972Y293929I-1475J-624D01*
G02X447385Y293930I-293J272D01*
G03X447336Y293981I-1180J-1084D01*
G02X447371Y294580I281J284D01*
G03X445596Y297237I-987J1262D01*
G02X445000Y297585I-196J348D01*
G01Y311200D01*
X462800Y329000D01*
Y329872D01*
X468494Y335566D01*
X472399D01*
X472898Y336064D01*
G02X473454Y336073I283J-283D01*
G03X475567Y336300I959J1023D01*
G01X476155D01*
G02X476518Y335733I0J-400D01*
G03X479066I1274J-586D01*
G02X479429Y336300I363J167D01*
G01X480018D01*
G03X482326I1154J796D01*
G01X482915D01*
G02X483278Y335733I0J-400D01*
G03X485826I1274J-586D01*
G02X486189Y336300I363J167D01*
G01X486778D01*
G03X489086I1154J796D01*
G01X489675D01*
G02X490038Y335733I0J-400D01*
G03X492586I1274J-586D01*
G02X492949Y336300I363J167D01*
G01X493538D01*
G03X495846I1154J796D01*
G01X496435D01*
G02X496798Y335733I0J-400D01*
G03X499346I1274J-586D01*
G02X499709Y336300I363J167D01*
G01X500298D01*
G03X500856Y335827I1154J796D01*
G01X500888Y335812D01*
X501443Y335257D01*
G02X501225Y334579I-283J-283D01*
G03X502835Y332969I227J-1383D01*
G02X503513Y333187I395J-65D01*
G01X503869Y332831D01*
G02X503862Y332260I-283J-282D01*
G03X505845Y330277I970J-1013D01*
G02X506416Y330284I289J-276D01*
G01X506899Y329801D01*
X506866Y329688D01*
G03X507764Y327968I1346J-392D01*
G01X507900Y327922D01*
Y326770D01*
X507764Y326724D01*
G03Y324068I448J-1328D01*
G01X507900Y324022D01*
Y322973D01*
X507760Y322928D01*
G03Y320064I452J-1432D01*
G01X507900Y320019D01*
Y318970D01*
X507764Y318924D01*
G03Y316268I448J-1328D01*
G01X507900Y316222D01*
Y315070D01*
X507764Y315024D01*
G03Y312368I448J-1328D01*
G01X507900Y312322D01*
Y311171D01*
X507764Y311125D01*
G03Y308469I448J-1328D01*
G01X507900Y308423D01*
Y307270D01*
X507764Y307224D01*
G03Y304568I448J-1328D01*
G01X507900Y304522D01*
Y303370D01*
X507764Y303324D01*
G03Y300668I448J-1328D01*
G01X507900Y300622D01*
Y299470D01*
X507764Y299424D01*
G03Y296768I448J-1328D01*
G01X507900Y296722D01*
Y295570D01*
X507764Y295524D01*
G03X506822Y294380I448J-1328D01*
G01X506813Y294313D01*
X505787Y293287D01*
X505649Y293386D01*
G03X503799Y291299I-817J-1139D01*
G01X503337Y290837D01*
G02X502699Y290937I-282J283D01*
G03X500811Y289049I-1247J-641D01*
G02X500911Y288411I-183J-356D01*
G01X498329Y285829D01*
X498233Y285840D01*
G03X496679Y284286I-161J-1393D01*
G01X496690Y284190D01*
X495977Y283477D01*
G02X495693Y283478I-142J141D01*
G03X493710Y281495I-1001J-982D01*
G01X493711D01*
X493853Y281353D01*
X493312Y280812D01*
G02X492648Y280973I-283J282D01*
G03X490886Y279211I-1336J-426D01*
G02X491047Y278547I-121J-381D01*
G01X488489Y275989D01*
X488372Y276027D01*
G03X486601Y274256I-440J-1331D01*
G01X486639Y274139D01*
X486260Y273760D01*
X486237Y273747D01*
G03X485942Y273557I1693J-2952D01*
G02X485666Y273598I-117J162D01*
G03X483207Y273143I-1114J-851D01*
G01X483165Y273000D01*
X482424D01*
G02X482146Y273688I0J400D01*
G03X480198I-974J1008D01*
G02X479920Y273000I-278J-288D01*
G01X479179D01*
X479137Y273143D01*
G03X476447I-1345J-396D01*
G01X476405Y273000D01*
X474803D01*
G37*
G36*
G01X808911Y207972D02*
X797673D01*
X794350Y204650D01*
X792600Y206400D01*
X785536D01*
X784970Y206966D01*
Y365766D01*
X785496Y366292D01*
X817482D01*
X818300Y365474D01*
Y212113D01*
X816856Y210668D01*
X811607D01*
X808911Y207972D01*
G37*
G36*
G01X762400Y208200D02*
X754273Y216327D01*
X738223D01*
X736850Y217700D01*
Y226200D01*
X739740Y229090D01*
Y243450D01*
X742400Y246110D01*
Y246724D01*
X742406Y246748D01*
G03Y248252I-2906J752D01*
G01X742400Y248276D01*
Y253294D01*
G03Y253506I-3000J106D01*
G01Y296083D01*
G03X743754Y300512I-1150J2773D01*
G02X744030Y301129I333J221D01*
G03X742894Y307018I-431J2971D01*
G02X742400Y307407I-94J389D01*
G01Y312667D01*
X742532Y312715D01*
G03Y318361I-1020J2823D01*
G01X742400Y318409D01*
Y374988D01*
G03Y377938I-626J1475D01*
G01Y387140D01*
X749230Y393970D01*
X762170D01*
X765316Y397116D01*
X770308D01*
X770637Y397446D01*
X782526D01*
X783984Y395987D01*
Y373151D01*
X783963Y373109D01*
G03Y371691I1437J-709D01*
G01X783984Y371649D01*
Y366196D01*
X783968Y366181D01*
Y220520D01*
X783944Y220496D01*
Y213184D01*
X778960Y208200D01*
X772002D01*
G02X771602Y208600I0J400D01*
G03X768798I-1402J0D01*
G02X768398Y208200I-400J0D01*
G01X762400D01*
G37*
G36*
G01X817880Y393820D02*
Y369436D01*
X816740Y368296D01*
X785861D01*
X785138Y369019D01*
Y400249D01*
X785389Y400500D01*
X795400D01*
X796300Y399600D01*
X812100D01*
X817880Y393820D01*
G37*
G36*
G01X983711Y330370D02*
G03X986420Y330372I1355J-361D01*
G02X986806Y330875I386J103D01*
G01X987554Y330876D01*
X987608Y330836D01*
G03X989286Y330837I838J1124D01*
G01X989339Y330877D01*
X990086D01*
G02X990472Y330374I0J-400D01*
G03X993179Y330375I1354J-365D01*
G02X993565Y330880I386J105D01*
G01X994309D01*
X994363Y330840D01*
G03X996050Y330841I843J1120D01*
G01X996104Y330881D01*
X996847Y330882D01*
G02X997233Y330377I0J-400D01*
G03X999938Y330378I1353J-368D01*
G02X1000324Y330884I386J106D01*
G01X1000672D01*
X1000862Y331074D01*
X1001003Y330940D01*
G03X1003357Y332130I962J1020D01*
G02X1003754Y332579I397J49D01*
G01X1004900D01*
X1004929Y332570D01*
G03X1005761I416J1339D01*
G01X1005790Y332579D01*
X1012682D01*
G02X1013054Y332030I1J-400D01*
G03X1015755Y331592I1302J-521D01*
G02X1016386Y331941I399J23D01*
G01X1018856D01*
X1019156Y332241D01*
Y332279D01*
X1019456Y332579D01*
X1029000D01*
X1031000Y330579D01*
Y326100D01*
X1025741Y320841D01*
X1015256D01*
X1010780Y316365D01*
X1008756D01*
X1008731Y316340D01*
G02X1008052Y316564I-283J282D01*
G03X1005266Y316267I-1387J-204D01*
G02X1004867Y315841I-399J-26D01*
G01X1004780D01*
X1004256Y316365D01*
X996619D01*
X996596Y316539D01*
G03X993889Y315878I-1390J-179D01*
G02X993514Y315341I-376J-137D01*
G01X992873D01*
G03X990834Y315400I-1047J-932D01*
G01X990775Y315341D01*
X990756D01*
X989256Y313841D01*
X988688D01*
X988672Y313844D01*
G03X987065Y312701I-226J-1384D01*
G01X987054Y312639D01*
X986256Y311841D01*
X985504D01*
X985476Y311850D01*
G03X984656I-410J-1341D01*
G01X984628Y311841D01*
X983475D01*
G02X983078Y312290I0J400D01*
G03X980294I-1392J170D01*
G02X979897Y311841I-397J-49D01*
G01X978744D01*
X978716Y311850D01*
G03X977896I-410J-1341D01*
G01X977868Y311841D01*
X976715D01*
G02X976318Y312290I0J400D01*
G03X973534I-1392J170D01*
G02X973137Y311841I-397J-49D01*
G01X971984D01*
X971956Y311850D01*
G03X971136I-410J-1341D01*
G01X971108Y311841D01*
X969955D01*
G02X969558Y312290I0J400D01*
G03X967561Y313725I-1392J170D01*
G01X967433Y313664D01*
X966018Y315079D01*
X966004Y315103D01*
G03X965457Y315640I-1218J-694D01*
G01X964756Y316341D01*
X962819D01*
X962799Y316518D01*
G03X960013I-1393J-158D01*
G01X959993Y316341D01*
X956060D01*
X956040Y316518D01*
G03X953254I-1393J-158D01*
G01X953234Y316341D01*
X949300D01*
X949280Y316518D01*
G03X946494I-1393J-158D01*
G01X946474Y316341D01*
X942540D01*
X942520Y316518D01*
G03X939734I-1393J-158D01*
G01X939714Y316341D01*
X938256D01*
X920756Y306341D01*
X905159D01*
X849900Y361600D01*
Y364000D01*
X848300Y365600D01*
X821400D01*
X818920Y368080D01*
Y390420D01*
X822700Y394200D01*
X844575D01*
X874418Y364356D01*
X874444D01*
X880450Y358350D01*
X887450D01*
X909200Y336600D01*
Y335200D01*
X912384Y332016D01*
X912385Y331935D01*
G03X914632Y330841I1402J25D01*
G01X915718D01*
G02X916106Y330345I0J-400D01*
G03X918828I1361J-336D01*
G02X919216Y330841I388J96D01*
G01X920002D01*
G03X921692I845J1119D01*
G01X922478D01*
G02X922866Y330345I0J-400D01*
G03X925588I1361J-336D01*
G02X925976Y330841I388J96D01*
G01X926762D01*
G03X928452I845J1119D01*
G01X929238D01*
G02X929626Y330345I0J-400D01*
G03X932348Y330346I1361J-336D01*
G02X932736Y330842I388J96D01*
G01X933518Y330843D01*
X933569Y330807D01*
G03X935166Y330808I798J1153D01*
G01X935218Y330844D01*
X935998D01*
G02X936387Y330348I1J-400D01*
G03X939107Y330349I1360J-339D01*
G02X939495Y330846I388J97D01*
G01X940272Y330847D01*
X940324Y330811D01*
G03X941931Y330812I803J1149D01*
G01X941983Y330848D01*
X942759D01*
G02X943147Y330351I0J-400D01*
G03X945866Y330353I1360J-342D01*
G02X946254Y330851I388J98D01*
G01X947027D01*
X947079Y330814D01*
G03X948697Y330815I808J1146D01*
G01X948748Y330852D01*
X949520Y330853D01*
G02X949908Y330354I0J-400D01*
G03X952625Y330356I1359J-345D01*
G02X953013Y330855I388J99D01*
G01X953782D01*
X953834Y330818D01*
G03X955462Y330819I813J1142D01*
G01X955514Y330856D01*
X956280Y330857D01*
G02X956668Y330357I1J-400D01*
G03X959384Y330359I1358J-348D01*
G02X959771Y330859I387J100D01*
G01X960535D01*
X960588Y330822D01*
G03X962226Y330823I818J1138D01*
G01X962278Y330860D01*
X963041Y330861D01*
G02X963429Y330361I1J-400D01*
G03X966143Y330362I1357J-352D01*
G02X966530Y330863I387J101D01*
G01X967290D01*
X967343Y330825D01*
G03X968991Y330826I823J1135D01*
G01X969043Y330865D01*
X969802D01*
G02X970190Y330364I1J-400D01*
G03X972902Y330365I1356J-355D01*
G02X973288Y330867I387J102D01*
G01X974045Y330868D01*
X974098Y330829D01*
G03X975756Y330830I828J1131D01*
G01X975809Y330869D01*
X976564D01*
G02X976950Y330367I0J-400D01*
G03X979661Y330369I1356J-358D01*
G02X980047Y330871I387J102D01*
G01X980800Y330872D01*
X980853Y330833D01*
G03X982521Y330834I833J1127D01*
G01X982574Y330873D01*
X983325D01*
G02X983711Y330370I0J-400D01*
G37*
G36*
G01X990740Y207550D02*
X989071Y209219D01*
G02X989153Y209847I283J282D01*
G03X987445Y212040I-708J1211D01*
G02X986760Y212320I-285J280D01*
G01Y213698D01*
G02X987445Y213978I400J0D01*
G03Y215942I1001J982D01*
G02X986760Y216222I-285J280D01*
G01Y221498D01*
G02X987445Y221778I400J0D01*
G03Y223742I1001J982D01*
G02X986760Y224022I-285J280D01*
G01Y229298D01*
G02X987445Y229578I400J0D01*
G03Y231542I1001J982D01*
G02X986760Y231822I-285J280D01*
G01Y233198D01*
G02X987445Y233478I400J0D01*
G03Y235442I1001J982D01*
G02X986760Y235722I-285J280D01*
G01Y236260D01*
X987678Y237178D01*
X987808Y237112D01*
G03X989694Y238998I638J1248D01*
G01X989628Y239128D01*
X990063Y239563D01*
G02X990675Y239509I283J-282D01*
G03X992626Y241460I1151J800D01*
G02X992572Y242072I228J329D01*
G01X993123Y242623D01*
G02X993805Y242322I283J-283D01*
G03X995144Y243661I1401J-62D01*
G02X994843Y244343I-18J399D01*
G01X995257Y244757D01*
X995329Y244763D01*
G03X996603Y246037I-123J1397D01*
G01X996609Y246109D01*
X997300Y246800D01*
X998083D01*
X998115Y246788D01*
G03X999057I471J1321D01*
G01X999089Y246800D01*
X1000179D01*
G02X1000575Y246347I0J-400D01*
G03X1003355I1390J-187D01*
G02X1003751Y246800I396J53D01*
G01X1004842D01*
X1004874Y246788D01*
G03X1005816I471J1321D01*
G01X1005848Y246800D01*
X1006939D01*
G02X1007335Y246347I0J-400D01*
G03X1010115I1390J-187D01*
G02X1010511Y246800I396J53D01*
G01X1011602D01*
X1011634Y246788D01*
G03X1012576I471J1321D01*
G01X1012608Y246800D01*
X1013699D01*
G02X1014095Y246347I0J-400D01*
G03X1016875I1390J-187D01*
G02X1017271Y246800I396J53D01*
G01X1018362D01*
X1018394Y246788D01*
G03X1020195Y247665I471J1321D01*
G01X1020210Y247710D01*
X1021418Y248918D01*
X1021550Y248842D01*
G03X1023463Y250755I695J1218D01*
G01X1023387Y250887D01*
X1023823Y251323D01*
G02X1024443Y251255I283J-283D01*
G03X1026379Y253191I1182J754D01*
G02X1026311Y253811I215J337D01*
G01X1029170Y256670D01*
G02X1029853Y256390I283J-283D01*
G03X1031265Y257802I1402J10D01*
G02X1030985Y258485I3J400D01*
G01X1039600Y267100D01*
X1076794D01*
X1077644Y266250D01*
Y264644D01*
X1068279Y255279D01*
X1068160Y255321D01*
G03X1066371Y253532I-468J-1321D01*
G01X1066413Y253413D01*
X1062650Y249650D01*
Y235350D01*
X1061140Y233840D01*
X1050710Y227005D01*
X1049204Y226162D01*
X1049027D01*
G03X1048908Y226155I4J-1077D01*
G03X1047289Y225527I374J-3366D01*
G02X1047013Y225566I-118J162D01*
G03X1044609Y224171I-1109J-857D01*
G02X1044507Y223912I-185J-77D01*
G03X1043914Y223570I1395J-3104D01*
G02X1043638Y223611I-117J162D01*
G03X1041229Y222222I-1114J-851D01*
G02X1041127Y221963I-184J-77D01*
G03X1040534Y221620I1399J-3102D01*
G02X1040259Y221661I-116J162D01*
G03X1037850Y220271I-1114J-851D01*
G02X1037748Y220012I-185J-77D01*
G03X1037155Y219670I1395J-3104D01*
G02X1036879Y219711I-117J162D01*
G03X1034470Y218322I-1114J-851D01*
G02X1034368Y218063I-184J-77D01*
G03X1033775Y217720I1399J-3102D01*
G02X1033499Y217760I-117J162D01*
G03X1031090Y216371I-1114J-851D01*
G02X1030988Y216112I-185J-77D01*
G03X1029958Y215395I1396J-3104D01*
G01X1029938Y215374D01*
X1028082Y214335D01*
X1028060Y214329D01*
G03X1027015Y213820I946J-3269D01*
G02X1026739Y213860I-117J162D01*
G03X1024330Y212471I-1114J-851D01*
G02X1024228Y212212I-185J-77D01*
G03X1023635Y211870I1395J-3104D01*
G02X1023359Y211911I-117J162D01*
G03X1020944Y210538I-1114J-851D01*
G01X1021009Y210375D01*
X1015964Y207550D01*
X1013485D01*
G02X1013179Y208207I0J400D01*
G03X1011031I-1074J902D01*
G02X1010725Y207550I-306J-257D01*
G01X1006725D01*
G02X1006419Y208207I0J400D01*
G03X1004271I-1074J902D01*
G02X1003965Y207550I-306J-257D01*
G01X999966D01*
G02X999660Y208207I0J400D01*
G03X997512I-1074J902D01*
G02X997206Y207550I-306J-257D01*
G01X996559D01*
X996509Y207676D01*
G03X993903I-1303J-517D01*
G01X993853Y207550D01*
X993206D01*
G02X992900Y208207I0J400D01*
G03X991084Y207920I-1073J902D01*
G01X991178Y207861D01*
Y207550D01*
X990740D01*
G37*
G36*
G01X1031095Y331900D02*
X1029415Y333580D01*
X1019141D01*
X1019109Y333740D01*
G03X1016475Y334075I-1374J-280D01*
G02X1015833Y333967I-360J175D01*
G01X1013046Y336754D01*
X1013167Y336894D01*
G03X1011190Y338871I-1062J915D01*
G02X1010918Y338882I-130J152D01*
G01X1010127Y339673D01*
Y339756D01*
G03X1008721Y341162I-1402J4D01*
G01X1008638D01*
X1006008Y343792D01*
G02X1006081Y344416I283J283D01*
G03X1004152Y346345I-736J1193D01*
G02X1003528Y346272I-341J210D01*
G01X1003084Y346716D01*
G03X1001248Y348765I-1119J844D01*
G01X1001115Y348685D01*
X999946Y349854D01*
X999931Y349903D01*
G03X998980Y350854I-1345J-394D01*
G01X998931Y350869D01*
X996093Y353707D01*
G02X996116Y354294I283J283D01*
G03X994140Y356270I-910J1066D01*
G02X993553Y356247I-304J260D01*
G01X993097Y356703D01*
X993141Y356823D01*
G03X991340Y358624I-1315J486D01*
G01X991220Y358580D01*
X988656Y361144D01*
G02X988829Y361811I283J283D01*
G03X987097Y363543I-383J1349D01*
G02X986430Y363370I-384J110D01*
G01X986149Y363651D01*
G02X986129Y364195I283J283D01*
G03X985800Y366304I-1063J914D01*
G01Y367815D01*
G03Y370205I-734J1195D01*
G01Y371714D01*
G03Y374104I-734J1195D01*
G01Y375614D01*
G03Y378004I-734J1195D01*
G01Y379514D01*
G03Y381904I-734J1195D01*
G01Y383414D01*
G03X986339Y384022I-735J1194D01*
G01X986354Y384054D01*
X990063Y387763D01*
G02X990675Y387709I283J-282D01*
G03X992626Y389660I1151J800D01*
G02X992572Y390272I228J329D01*
G01X993123Y390823D01*
G02X993805Y390522I283J-283D01*
G03X995144Y391861I1401J-62D01*
G02X994843Y392543I-18J399D01*
G01X997900Y395600D01*
X1051454D01*
G03X1052704Y394908I1209J709D01*
G01X1052790Y394910D01*
X1055100Y392600D01*
Y371400D01*
X1053814Y370114D01*
G02X1053546Y370100I-142J141D01*
G03X1051574Y368128I-882J-1090D01*
G01X1051688Y367988D01*
X1051212Y367512D01*
G02X1050564Y367632I-283J283D01*
G03X1048712Y365780I-1280J-572D01*
G02X1048832Y365132I-163J-365D01*
G01X1046267Y362567D01*
X1046163Y362587D01*
G03X1044633Y361800I-259J-1378D01*
G01X1044049D01*
G02X1043710Y362413I0J400D01*
G03X1041338I-1186J747D01*
G02X1040999Y361800I-339J-213D01*
G01X1040416D01*
G03X1038024Y360367I-1271J-591D01*
G01X1038128Y360228D01*
X1037667Y359767D01*
G02X1037025Y359875I-282J283D01*
G03X1036726Y358239I-1260J-615D01*
G02X1037400Y357948I274J-291D01*
G01Y356700D01*
X1038742Y355358D01*
G02X1038611Y354705I-283J-283D01*
G03X1040441Y352875I534J-1296D01*
G02X1041094Y353006I370J-152D01*
G01X1041584Y352516D01*
X1041462Y352376D01*
G03X1043440Y350398I1062J-916D01*
G01X1043580Y350520D01*
X1046550Y347550D01*
X1046770D01*
Y347335D01*
X1046768Y347320D01*
G03X1049556Y347141I1386J-210D01*
G02X1049956Y347550I400J9D01*
G01X1053118D01*
G02X1053517Y347117I0J-400D01*
G03X1056311I1397J-117D01*
G02X1056710Y347550I399J33D01*
G01X1069150D01*
X1072600Y344100D01*
Y342183D01*
X1073720Y341063D01*
X1080061D01*
X1081367Y339757D01*
Y333785D01*
X1079516Y331934D01*
X1068434D01*
X1068400Y331900D01*
X1031095D01*
G37*
G36*
G01X1357101Y558400D02*
X1355863D01*
X1347192Y549730D01*
X1333869D01*
X1331978Y551621D01*
Y613046D01*
X1331800Y613224D01*
Y615068D01*
X1332971Y616239D01*
X1366433D01*
X1366900Y615772D01*
Y598900D01*
X1363700Y595700D01*
Y590700D01*
X1366700Y587700D01*
Y568200D01*
X1362150Y563650D01*
Y562350D01*
X1359300Y559500D01*
X1358200D01*
X1357101Y558400D01*
G37*
G36*
G01X1363641Y-15025D02*
X1363000Y-14384D01*
Y500D01*
X1361500Y2000D01*
Y9731D01*
G03Y11469I-1100J869D01*
G01Y27739D01*
X1368721Y34960D01*
X1368835Y34925D01*
G03X1372300Y36300I865J2875D01*
G01X1376780D01*
X1377239Y36759D01*
X1377310Y36766D01*
G03X1379470Y41472I-301J2987D01*
G02X1379717Y42093I328J229D01*
G03X1382111Y45113I-607J2940D01*
G03X1382822Y47461I-294J1371D01*
G01X1386100Y50739D01*
Y56891D01*
X1386105Y56912D01*
G03Y58186I-2934J637D01*
G01X1386100Y58207D01*
Y73707D01*
X1386678Y74284D01*
Y78527D01*
X1386983Y78833D01*
G02X1387666Y78552I283J-283D01*
G03X1388552Y79860I1402J4D01*
G01X1388430Y79811D01*
X1388196Y80046D01*
X1388801Y80651D01*
X1395667D01*
X1396223Y80094D01*
X1397606D01*
X1404000Y73700D01*
Y52661D01*
G02X1403400Y52315I-400J0D01*
G03Y49885I-700J-1215D01*
G02X1404000Y49539I200J-346D01*
G01Y48551D01*
G03X1406306Y37119I2546J-5435D01*
G01X1406384Y37116D01*
X1410496Y33004D01*
Y25668D01*
X1407392Y22564D01*
X1405697D01*
G02X1405308Y23058I0J400D01*
G03X1397724I-3792J918D01*
G02X1397335Y22564I-389J-94D01*
G01X1396341D01*
X1390222Y16445D01*
Y7175D01*
X1389413Y6365D01*
X1389346Y6357D01*
G03X1388132Y5143I177J-1391D01*
G01X1388124Y5076D01*
X1386204Y3157D01*
Y-13704D01*
X1384884Y-15025D01*
X1363641D01*
G37*
G36*
G01X1364980Y362520D02*
X1361500Y366000D01*
X1359475D01*
X1358432Y367044D01*
Y370194D01*
G02X1358617Y370394I200J1D01*
G03X1359490Y372797I-105J1398D01*
G02X1359502Y373381I279J286D01*
G03X1359778Y375290I-1002J1119D01*
G02X1360135Y375899I340J210D01*
G03X1360480Y378876I65J1501D01*
G02X1360156Y379286I75J393D01*
G03Y379393I-1501J53D01*
G02X1360350Y379599I200J6D01*
G03X1360302Y382602I-50J1501D01*
G02X1360102Y382802I0J200D01*
G01Y382817D01*
G02X1360438Y383217I400J5D01*
G03X1360513Y386169I-238J1483D01*
G02X1360198Y386590I84J391D01*
G03X1360163Y387040I-1498J110D01*
G02X1360478Y387524I389J91D01*
G03X1361702Y388987I-278J1476D01*
G02X1362095Y389383I400J-4D01*
G03X1363200Y391872I-27J1502D01*
G02Y392398I302J263D01*
G03X1362906Y394632I-1132J987D01*
G02X1362846Y395246I223J332D01*
G01X1367150Y399550D01*
Y407500D01*
X1368550Y408900D01*
X1388100D01*
X1389000Y408000D01*
Y391500D01*
X1388226Y390726D01*
X1388172Y390712D01*
G03X1385988Y388528I728J-2912D01*
G01X1385974Y388474D01*
X1384500Y387000D01*
X1379000D01*
X1377000Y385000D01*
Y378000D01*
X1381300Y373700D01*
Y369800D01*
X1374020Y362520D01*
X1364980D01*
G37*
G36*
G01X1378100Y560300D02*
X1377200Y561200D01*
X1374900D01*
X1373650Y562450D01*
X1370950D01*
X1367700Y565700D01*
Y567784D01*
X1367702Y567785D01*
Y588115D01*
X1367700Y588116D01*
Y596000D01*
X1374808Y603108D01*
X1374949Y602994D01*
G03X1377176Y603363I952J1162D01*
G01X1381578D01*
X1381598Y603359D01*
G03X1382841Y603367I603J2941D01*
G03X1383614Y602908I1902J2323D01*
G03X1386036Y601755I1386J-208D01*
G02X1386614Y601768I295J-270D01*
G01X1398559Y589822D01*
X1406856D01*
X1409231Y587448D01*
X1429008D01*
X1443002Y601441D01*
Y604996D01*
X1451273Y613268D01*
X1464290D01*
X1467080Y616058D01*
X1467187Y616034D01*
G03X1468138Y615977I653J2930D01*
G03X1472710Y616137I2218J2023D01*
G03X1474484Y616561I222J2994D01*
G03X1477277Y616558I1399J2656D01*
G03X1480570Y617125I1223J2742D01*
G03X1481812Y617217I404J2975D01*
G01X1481839Y617225D01*
X1488355D01*
X1488850Y617720D01*
X1536880D01*
X1537200Y617400D01*
Y614708D01*
X1537089Y614653D01*
G03X1536605Y614259I621J-1257D01*
G02X1535992Y614238I-315J246D01*
G03X1534043Y612231I-1043J-937D01*
G02X1534039Y611616I-258J-306D01*
G03X1535833Y611603I889J-1084D01*
G02X1535837Y612218I258J306D01*
G03X1536054Y612440I-888J1085D01*
G02X1536667Y612461I315J-246D01*
G03X1537089Y612141I1043J937D01*
G01X1537200Y612086D01*
Y603700D01*
X1533178Y599678D01*
G03X1532558Y599058I1790J-2410D01*
G01X1527149Y593648D01*
X1503955D01*
X1498675Y588368D01*
X1463277D01*
X1463226Y588492D01*
G03X1463017Y588841I-1295J-538D01*
G02X1463041Y589374I310J253D01*
G03X1463125Y591240I-1002J980D01*
G02X1463151Y591774I310J253D01*
G03X1461069Y591875I-996J987D01*
G02X1461043Y591341I-310J-253D01*
G03X1460952Y589469I996J-987D01*
G02X1460928Y588936I-310J-253D01*
G03X1460634Y588492I1001J-982D01*
G01X1460583Y588368D01*
X1457578D01*
X1445610Y576400D01*
X1437700D01*
X1435800Y578300D01*
X1423927D01*
G02X1423610Y578944I0J400D01*
G03X1421390I-1110J856D01*
G02X1421073Y578300I-317J-244D01*
G01X1416227D01*
G02X1415910Y578944I0J400D01*
G03X1413690I-1110J856D01*
G02X1413373Y578300I-317J-244D01*
G01X1403240D01*
X1397022Y572082D01*
X1396198D01*
X1385517Y561400D01*
X1382654D01*
X1382615Y561418D01*
G03X1381449I-583J-1275D01*
G01X1381410Y561400D01*
X1381100D01*
X1380000Y560300D01*
X1378100D01*
G37*
G36*
G01X1443700Y378900D02*
Y397300D01*
X1449300D01*
Y396803D01*
X1449296Y396800D01*
Y378900D01*
X1443700D01*
G37*
G36*
G01X1437000Y417100D02*
Y429286D01*
X1437414Y429700D01*
X1447350D01*
Y417100D01*
X1437000D01*
G37*
G36*
G01X1510024Y409200D02*
X1509796Y409428D01*
X1509059D01*
X1506670Y411816D01*
X1501313D01*
X1501185Y411689D01*
G02X1500530Y411826I-283J283D01*
G03X1499385Y412707I-1305J-512D01*
G02X1499147Y413387I45J397D01*
G01X1499522Y413762D01*
Y415345D01*
G02X1500210Y415622I400J-1D01*
G03X1499909Y417096I1009J974D01*
G01X1499860Y416968D01*
X1499522D01*
Y417615D01*
X1497794Y419343D01*
G02X1497882Y419975I283J283D01*
G03X1497229Y422602I-682J1225D01*
G02X1496955Y423284I9J400D01*
G01X1497572Y423902D01*
Y424358D01*
X1497900D01*
X1497954Y424243D01*
G03X1498250Y425842I1271J592D01*
G02X1497572Y426129I-278J288D01*
G01Y426836D01*
X1497710Y426881D01*
G03X1496892Y429563I-435J1333D01*
G02X1496382Y429947I-110J385D01*
G01Y431284D01*
X1497572Y432474D01*
Y435408D01*
X1497710Y435453D01*
G03X1497435Y438179I-435J1333D01*
G02X1497197Y438859I45J397D01*
G01X1497572Y439234D01*
Y439690D01*
X1497900D01*
X1497954Y439575D01*
G03X1498250Y441174I1271J592D01*
G02X1497572Y441461I-278J288D01*
G01Y441487D01*
X1497519Y441540D01*
G02X1497685Y442205I283J283D01*
G03X1496148Y444380I-410J1341D01*
G01X1496088Y444299D01*
X1495788D01*
Y444887D01*
X1496577Y445677D01*
X1498587D01*
X1498627Y445658D01*
G03X1499823I598J1268D01*
G01X1499863Y445677D01*
X1502291D01*
G03X1502470Y445574I837J1247D01*
G01X1502500Y445560D01*
X1502789Y445271D01*
X1503924D01*
G02X1504261Y444655I0J-400D01*
G03X1504562Y442809I1181J-755D01*
G02X1504622Y442247I-251J-311D01*
G03X1504347Y441676I1093J-878D01*
G02X1503772Y441410I-390J88D01*
G03X1504493Y439858I-647J-1244D01*
G02X1505068Y440124I390J-88D01*
G03X1506595Y442459I647J1244D01*
G02X1506535Y443021I251J311D01*
G03X1505361Y445300I-1093J879D01*
G02X1505055Y445982I-23J399D01*
G01X1505472Y446398D01*
X1507638D01*
G02X1507985Y445799I0J-400D01*
G03X1508519Y443875I1215J-699D01*
G02Y443175I-194J-350D01*
G03Y440725I681J-1225D01*
G02Y440025I-194J-350D01*
G03Y437575I681J-1225D01*
G02Y436875I-194J-350D01*
G03X1510425Y434969I681J-1225D01*
G02X1511125I350J-194D01*
G03X1513575I1225J681D01*
G02X1514275I350J-194D01*
G03X1516725I1225J681D01*
G02X1517425I350J-194D01*
G03X1519331Y436875I1225J681D01*
G02Y437575I194J350D01*
G03X1517425Y439481I-681J1225D01*
G02X1516725I-350J194D01*
G03X1516181Y440025I-1225J-681D01*
G02Y440725I194J350D01*
G03Y443175I-681J1225D01*
G02Y443875I194J350D01*
G03X1516792Y445643I-681J1225D01*
G02X1517161Y446198I369J155D01*
G01X1521415D01*
X1522095Y446878D01*
X1522148Y446892D01*
G03X1523127Y447798I-348J1358D01*
G01X1523142Y447842D01*
X1523200Y447900D01*
Y447984D01*
X1523802Y448585D01*
Y452715D01*
X1521294Y455223D01*
G02X1521376Y455852I282J283D01*
G03X1519461Y457767I-701J1214D01*
G02X1518832Y457685I-346J200D01*
G01X1516222Y460295D01*
X1516226Y460383D01*
G03X1514762Y461847I-1401J63D01*
G01X1514674Y461843D01*
X1513779Y462737D01*
X1513908Y462879D01*
G03X1511928Y464859I-1033J947D01*
G01X1511786Y464730D01*
X1511279Y465237D01*
G02X1511420Y465894I283J283D01*
G03X1509613Y467701I-495J1312D01*
G02X1508956Y467560I-374J142D01*
G01X1506401Y470116D01*
X1506430Y470227D01*
G03X1505188Y471983I-1355J359D01*
G01X1505084Y471992D01*
X1504340Y473258D01*
X1504387Y473354D01*
G03X1503204Y475366I-1262J612D01*
G01X1503097Y475372D01*
X1502371Y476606D01*
X1502421Y476704D01*
G03X1501220Y478747I-1246J642D01*
G01X1501110Y478751D01*
X1500401Y479955D01*
X1500456Y480055D01*
G03X1499236Y482128I-1231J671D01*
G01X1499123Y482129D01*
X1498432Y483305D01*
X1498490Y483406D01*
G03X1497254Y485508I-1215J700D01*
G01X1497137Y485506D01*
X1496461Y486656D01*
X1496523Y486758D01*
G03X1495271Y488887I-1198J728D01*
G01X1495152Y488882D01*
X1489696Y498160D01*
X1489746Y498258D01*
G03X1488883Y500249I-1246J642D01*
G01X1488791Y500275D01*
X1486279Y506171D01*
X1486199Y506252D01*
X1486301Y506498D01*
X1488293D01*
G03X1489073Y506717I-1J1502D01*
G02X1489647Y506537I208J-342D01*
G03X1490258Y508335I1282J567D01*
G02X1489693Y508542I-192J351D01*
G03X1488293Y509502I-1400J-541D01*
G01X1485693D01*
G03X1485624Y509500I9J-1502D01*
G02X1485206Y509906I-18J399D01*
G03X1482403Y509888I-1402J22D01*
G02X1481997Y509476I-400J-12D01*
G01X1479375D01*
G03X1478728Y509330I-1J-1501D01*
G01X1478601Y509269D01*
X1478100Y509770D01*
Y518800D01*
X1476150Y520750D01*
X1463250D01*
X1462022Y521978D01*
G02X1462038Y522558I283J282D01*
G03X1460058Y524538I-938J1042D01*
G02X1459478Y524522I-298J267D01*
G01X1458600Y525400D01*
Y539950D01*
X1463567Y544917D01*
Y555443D01*
X1466957Y558833D01*
X1474933D01*
X1483200Y567100D01*
X1528316D01*
X1532738Y571522D01*
X1549454D01*
X1550504Y570472D01*
Y553304D01*
X1539258Y542058D01*
X1531298D01*
X1509850Y520610D01*
Y519656D01*
X1507444D01*
X1507441Y519657D01*
G03X1505916Y517958I-36J-1502D01*
G02X1505569Y517508I-396J-53D01*
G03X1507113Y516413I174J-1391D01*
G02X1507320Y516655I195J42D01*
G03X1507441Y516653I85J1500D01*
G01X1507444Y516654D01*
X1509850D01*
Y512346D01*
G02X1509642Y512146I-200J0D01*
G03X1509549Y512147I-63J-1501D01*
G01X1509546Y512146D01*
X1506985D01*
G03X1505638Y509981I0J-1501D01*
G02X1505453Y509444I-359J-177D01*
G03X1505280Y507015I607J-1264D01*
G02X1505340Y506400I-223J-332D01*
G01X1503490Y504550D01*
Y496670D01*
X1506605Y493555D01*
Y488830D01*
X1506482Y488779D01*
G03X1507157Y486090I542J-1293D01*
G01X1507251Y486099D01*
X1508117Y485233D01*
X1507978Y485091D01*
G03X1509513Y482811I997J-985D01*
G02X1509772Y482709I77J-185D01*
G03X1510115Y482116I3102J1399D01*
G02X1510074Y481840I-162J-117D01*
G03X1510879Y479325I851J-1114D01*
G01X1510958Y479322D01*
X1511905Y478375D01*
X1511791Y478235D01*
G03X1513722Y476229I1084J-889D01*
G01X1513776Y476270D01*
X1513918D01*
G03X1513927I5J1771D01*
G01X1514010D01*
X1514382Y475898D01*
G02X1514260Y475249I-283J-283D01*
G03X1516108Y473401I565J-1283D01*
G02X1516757Y473523I366J-161D01*
G01X1517480Y472800D01*
X1517944D01*
X1517993Y472771D01*
G03X1519503Y472800I732J1195D01*
G01X1521847D01*
G03X1523403I778J1166D01*
G01X1525747D01*
G03X1527303I778J1166D01*
G01X1528100D01*
X1528291Y472609D01*
G02X1528112Y471940I-283J-283D01*
G03X1529039Y469302I364J-1354D01*
G02X1529600Y468936I161J-366D01*
G01Y468340D01*
G03Y466072I825J-1134D01*
G01Y465476D01*
G02X1529039Y465110I-400J0D01*
G03Y462542I-564J-1284D01*
G02X1529600Y462176I161J-366D01*
G01Y461580D01*
G03Y459312I825J-1134D01*
G01Y458716D01*
G02X1529039Y458350I-400J0D01*
G03Y455782I-564J-1284D01*
G02X1529600Y455416I161J-366D01*
G01Y450800D01*
X1530500Y449900D01*
X1549000D01*
X1549098Y449998D01*
X1549255D01*
X1549791Y450535D01*
G02X1550474Y450264I283J-283D01*
G03X1551917Y451707I1401J42D01*
G02X1551646Y452390I12J400D01*
G01X1554156Y454900D01*
X1555022D01*
Y448542D01*
G02X1554446Y448183I-400J0D01*
G03X1554698Y445829I-621J-1257D01*
G01X1554753Y445872D01*
X1555022D01*
Y445654D01*
X1555241Y445435D01*
G02X1555140Y444796I-283J-283D01*
G03X1554982Y442390I635J-1250D01*
G02X1555010Y442084I-113J-165D01*
G01X1554922Y441996D01*
Y441827D01*
G02X1554368Y441459I-400J1D01*
G03X1553276Y438876I-543J-1293D01*
G02X1553402Y438225I-157J-368D01*
G01X1552917Y437741D01*
X1552777Y437859D01*
G03X1550882Y435796I-902J-1073D01*
G02X1550881Y435231I-284J-282D01*
G01X1550850Y435200D01*
Y431504D01*
X1549202Y429856D01*
Y426704D01*
X1549323Y426583D01*
G02X1549245Y425957I-283J-283D01*
G03X1548906Y423833I719J-1204D01*
G02X1548887Y423287I-301J-263D01*
G01X1548681Y423081D01*
Y422657D01*
X1548248Y422223D01*
Y420933D01*
X1547642Y420328D01*
Y418536D01*
G02X1547189Y418139I-400J-1D01*
G03X1545775Y417431I-189J-1389D01*
G02X1545075I-350J194D01*
G03X1542625I-1225J-681D01*
G02X1541925I-350J194D01*
G03X1541381Y417975I-1225J-681D01*
G02Y418675I194J350D01*
G03Y421125I-681J1225D01*
G02Y421825I194J350D01*
G03Y424275I-681J1225D01*
G02Y424975I194J350D01*
G03X1541925Y425519I-681J1225D01*
G02X1542625I350J-194D01*
G03X1544531Y427425I1225J681D01*
G02Y428125I194J350D01*
G03X1542625Y430031I-681J1225D01*
G02X1541925I-350J194D01*
G03X1539475I-1225J-681D01*
G02X1538775I-350J194D01*
G03X1536325I-1225J-681D01*
G02X1535625I-350J194D01*
G03X1533175I-1225J-681D01*
G02X1532475I-350J194D01*
G03X1530569Y428125I-1225J-681D01*
G02Y427425I-194J-350D01*
G03Y424975I681J-1225D01*
G02Y424275I-194J-350D01*
G03Y421825I681J-1225D01*
G02Y421125I-194J-350D01*
G03X1532475Y419219I681J-1225D01*
G02X1533175I350J-194D01*
G03X1533719Y418675I1225J681D01*
G02Y417975I-194J-350D01*
G03X1533328Y415847I681J-1225D01*
G01X1533446Y415706D01*
X1530922Y413182D01*
X1529210D01*
X1529196Y413196D01*
X1527221D01*
X1526219Y414198D01*
X1526204Y414227D01*
G03X1525577Y414854I-1254J-627D01*
G01X1525548Y414869D01*
X1525195Y415221D01*
X1525371Y415397D01*
X1525418Y415412D01*
G03X1525661Y417986I-418J1338D01*
G02X1525650Y418685I189J353D01*
G03X1525631Y421125I-700J1215D01*
G02Y421825I194J350D01*
G03Y424275I-681J1225D01*
G02Y424975I194J350D01*
G03Y427425I-681J1225D01*
G02Y428125I194J350D01*
G03X1524269I-681J1225D01*
G02Y427425I-194J-350D01*
G03Y424975I681J-1225D01*
G02Y424275I-194J-350D01*
G03Y421825I681J-1225D01*
G02Y421125I-194J-350D01*
G03X1524289Y418664I681J-1225D01*
G02X1524300Y417965I-189J-353D01*
G03X1523611Y416557I700J-1215D01*
G02X1523215Y416102I-396J-55D01*
G01X1520435D01*
G02X1520039Y416557I0J400D01*
G03X1519331Y417975I-1389J192D01*
G02Y418675I194J350D01*
G03Y421125I-681J1225D01*
G02Y421825I194J350D01*
G03Y424275I-681J1225D01*
G02Y424975I194J350D01*
G03Y427425I-681J1225D01*
G02Y428125I194J350D01*
G03X1517425Y430031I-681J1225D01*
G02X1516725I-350J194D01*
G03X1514275I-1225J-681D01*
G02X1513575I-350J194D01*
G03X1511125I-1225J-681D01*
G02X1510425I-350J194D01*
G03X1507956Y429997I-1225J-681D01*
G02X1507259Y429974I-355J184D01*
G03X1507303Y428602I-1200J-725D01*
G02X1508000Y428625I355J-184D01*
G03X1508519Y428125I1199J726D01*
G02Y427425I-194J-350D01*
G03Y424975I681J-1225D01*
G02Y424275I-194J-350D01*
G03Y421825I681J-1225D01*
G02Y421125I-194J-350D01*
G03Y418675I681J-1225D01*
G02Y417975I-194J-350D01*
G03Y415525I681J-1225D01*
G02Y414825I-194J-350D01*
G03X1509881I681J-1225D01*
G02Y415525I194J350D01*
G03X1510425Y416069I-681J1225D01*
G02X1511125I350J-194D01*
G03X1513575I1225J681D01*
G02X1514275I350J-194D01*
G03X1514742Y415570I1226J680D01*
G02X1514731Y414890I-216J-337D01*
G03X1514001Y413688I769J-1290D01*
G01X1513996Y413612D01*
X1513498Y413115D01*
Y410199D01*
X1512500Y409200D01*
X1510024D01*
G37*
G36*
G01X1520046Y406894D02*
G03X1519896Y407232I-1346J-395D01*
G01X1519814Y407366D01*
X1523402Y410954D01*
X1526298D01*
G02X1526698Y410554I0J-400D01*
G03X1528706Y409286I1402J-4D01*
G02X1529279Y408925I173J-361D01*
G01Y407798D01*
X1528296Y406816D01*
X1526330D01*
G02X1525940Y407306I0J400D01*
G03X1523212Y407294I-1365J318D01*
G02X1522824Y406800I-388J-94D01*
G01X1520789D01*
X1520712Y406723D01*
G02X1520046Y406894I-282J283D01*
G37*
G36*
G01X1515033Y412278D02*
G03X1516568Y414508I467J1322D01*
G01X1516449Y414649D01*
X1516900Y415100D01*
X1523900D01*
X1524187Y414813D01*
X1524040Y414667D01*
X1524034Y414662D01*
G03X1523550Y413528I916J-1061D01*
G02X1523150Y413108I-399J-20D01*
G01X1522510D01*
X1518692Y409290D01*
X1516735D01*
X1515183Y407737D01*
G02X1514500Y408020I-283J283D01*
G01Y411901D01*
G02X1515033Y412278I400J0D01*
G37*
G36*
G01X1513400Y447200D02*
X1513200Y447400D01*
X1507483D01*
G02X1507090Y447877I0J400D01*
G03X1504344Y448442I-1376J268D01*
G02X1503769Y448171I-391J84D01*
G03X1501853Y447516I-644J-1245D01*
G01X1501799Y447400D01*
X1500551D01*
X1500497Y447516D01*
G03X1498794Y448260I-1272J-590D01*
G01X1498678Y448222D01*
X1498207Y448693D01*
G02X1498220Y449271I283J283D01*
G03X1496240Y451251I-945J1035D01*
G02X1495662Y451238I-295J270D01*
G01X1495283Y451617D01*
G02X1495512Y452297I282J283D01*
G03X1493936Y453873I-187J1389D01*
G02X1493256Y453644I-397J53D01*
G01X1492748Y454152D01*
X1492733Y454191D01*
G03X1491930Y454994I-1308J-505D01*
G01X1491891Y455009D01*
X1491499Y455401D01*
X1491722Y455624D01*
Y455771D01*
G02X1492400Y456058I400J-1D01*
G03X1492104Y457657I975J1007D01*
G01X1492050Y457542D01*
X1491722D01*
Y457998D01*
X1491347Y458373D01*
G02X1491585Y459053I283J283D01*
G03X1490076Y460063I-160J1393D01*
G02X1489692Y459554I-384J-109D01*
G01X1489258D01*
G02X1488874Y460063I0J400D01*
G03X1488207Y461671I-1349J383D01*
G02X1488119Y462303I195J349D01*
G01X1488284Y462467D01*
Y462568D01*
G02X1488607Y462725I200J0D01*
G03X1488859Y465086I868J1101D01*
G02X1488284Y465445I-175J359D01*
G01Y468967D01*
G02X1488859Y469326I400J0D01*
G03X1488607Y471687I616J1260D01*
G02X1488284Y471844I-123J157D01*
G01Y471945D01*
X1488119Y472109D01*
G02X1488207Y472741I283J283D01*
G03X1487142Y475315I-682J1225D01*
G02X1486632Y475699I-110J385D01*
G01Y478993D01*
G02X1487142Y479377I400J-1D01*
G03X1487717Y482115I382J1349D01*
G01X1487651Y482124D01*
X1484239Y485535D01*
X1484281Y485654D01*
G03X1481559Y486032I-1323J464D01*
G02X1481159Y485608I-399J-24D01*
G01X1476616D01*
X1472384Y489840D01*
X1472295D01*
X1471884Y490250D01*
Y490251D01*
X1470516Y491620D01*
Y493699D01*
G02X1470706Y493898I200J0D01*
G03X1471973Y494854I-63J1401D01*
G02X1472673Y494966I379J-127D01*
G03X1472470Y496245I1127J834D01*
G02X1471770Y496133I-379J127D01*
G03X1469754Y496383I-1127J-834D01*
G02X1469100Y496692I-254J309D01*
G01Y501500D01*
X1468268Y502332D01*
Y514056D01*
X1466500Y515824D01*
Y517600D01*
X1467700Y518800D01*
X1475800D01*
X1476800Y517800D01*
Y508713D01*
X1476625Y508691D01*
G03X1478003Y506581I175J-1391D01*
G02X1478563Y506712I343J-205D01*
G03X1479374Y506474I811J1263D01*
G01X1481975D01*
G03X1483298Y507265I0J1501D01*
G01X1483769D01*
X1485434Y505600D01*
X1487773Y500109D01*
X1487649Y500014D01*
G03X1487268Y499568I852J-1113D01*
G02X1486557Y499582I-352J191D01*
G03X1484117Y499714I-1257J-620D01*
G02X1483451Y499700I-338J215D01*
G03X1483483Y498148I-1151J-800D01*
G02X1484149Y498162I338J-215D01*
G03X1486532Y498294I1151J800D01*
G02X1487243Y498280I352J-191D01*
G03X1488756Y497522I1257J620D01*
G01X1488894Y497547D01*
X1494266Y488414D01*
X1494189Y488308D01*
G03X1495491Y486094I1136J-822D01*
G01X1495621Y486109D01*
X1496238Y485059D01*
X1496157Y484952D01*
G03X1497471Y482718I1118J-846D01*
G01X1497604Y482737D01*
X1498211Y481704D01*
X1498126Y481597D01*
G03X1499452Y479342I1099J-871D01*
G01X1499587Y479365D01*
X1500185Y478348D01*
X1500095Y478240D01*
G03X1501432Y475968I1080J-894D01*
G01X1501569Y475993D01*
X1502158Y474992D01*
X1502065Y474883D01*
G03X1503411Y472593I1060J-917D01*
G01X1503551Y472623D01*
X1504133Y471634D01*
X1504034Y471526D01*
G03X1505626Y469297I1041J-940D01*
G01X1505750Y469350D01*
X1506194Y468906D01*
G02X1506159Y468308I-282J-283D01*
G03X1508127Y466340I866J-1102D01*
G02X1508725Y466375I315J-247D01*
G01X1509190Y465910D01*
G02X1508923Y465227I-282J-283D01*
G03X1510376Y463774I52J-1401D01*
G02X1511059Y464041I400J-15D01*
G01X1511488Y463612D01*
X1511500Y463552D01*
G03X1512601Y462451I1375J274D01*
G01X1512661Y462439D01*
X1513745Y461355D01*
X1513655Y461219D01*
G03X1515598Y459276I1170J-773D01*
G01X1515734Y459366D01*
X1516178Y458922D01*
G02X1516091Y458290I-282J-283D01*
G03X1517999Y456382I684J-1224D01*
G02X1518631Y456469I349J-195D01*
G01X1522800Y452300D01*
Y449949D01*
G02X1522267Y449572I-400J0D01*
G03X1520492Y447744I-467J-1322D01*
G02X1520119Y447200I-373J-144D01*
G01X1517181D01*
G02X1516808Y447744I0J400D01*
G03X1514192I-1308J506D01*
G02X1513819Y447200I-373J-144D01*
G01X1513400D01*
G37*
G36*
G01X1545652Y451000D02*
G02X1545252Y451400I0J400D01*
G03X1542625Y452081I-1402J0D01*
G02X1541925I-350J194D01*
G03X1539475I-1225J-681D01*
G02X1538775I-350J194D01*
G03X1536325I-1225J-681D01*
G02X1535625I-350J194D01*
G03X1533175I-1225J-681D01*
G02X1532475I-350J194D01*
G03X1531277Y452802I-1226J-681D01*
G01X1531197Y452803D01*
X1531000Y453000D01*
Y459162D01*
X1531103Y459219D01*
G03Y461673I-678J1227D01*
G01X1531000Y461730D01*
Y462300D01*
X1531455Y462755D01*
X1531592Y462663D01*
G03X1533770Y463961I783J1163D01*
G02X1534169Y464400I398J39D01*
G01X1534481D01*
G02X1534880Y463961I1J-400D01*
G03X1537670I1395J-135D01*
G02X1538069Y464400I398J39D01*
G01X1538381D01*
G02X1538780Y463961I1J-400D01*
G03X1541570I1395J-135D01*
G02X1541969Y464400I398J39D01*
G01X1542281D01*
G02X1542680Y463961I1J-400D01*
G03X1544534Y465151I1395J-135D01*
G01X1544400Y465197D01*
Y465884D01*
G02X1545072Y466178I400J1D01*
G03Y468234I953J1028D01*
G02X1544400Y468528I-272J293D01*
G01Y469215D01*
X1544534Y469261D01*
G03Y471911I-459J1325D01*
G01X1544400Y471957D01*
Y472644D01*
G02X1545072Y472938I400J1D01*
G03Y474994I953J1028D01*
G02X1544400Y475288I-272J293D01*
G01Y475975D01*
X1544534Y476021D01*
G03X1545310Y478009I-459J1325D01*
G01X1545240Y478140D01*
X1546510Y479410D01*
X1546548Y479425D01*
G03X1547133Y481585I-523J1301D01*
G01X1547025Y481725D01*
X1548002Y482702D01*
X1548077Y482708D01*
G03X1549373Y484004I-102J1398D01*
G01X1549379Y484079D01*
X1549793Y484493D01*
G02X1550475Y484187I283J-283D01*
G03X1551794Y485506I1400J-81D01*
G02X1551488Y486188I-23J399D01*
G01X1552053Y486753D01*
G02X1552667Y486696I283J-282D01*
G03X1555121Y486951I1158J790D01*
G01X1555172Y487075D01*
X1556378D01*
X1556429Y486951D01*
G03X1559021I1296J535D01*
G01X1559072Y487075D01*
X1560278D01*
X1560329Y486951D01*
G03X1562921I1296J535D01*
G01X1562972Y487075D01*
X1564178D01*
X1564229Y486951D01*
G03X1566821I1296J535D01*
G01X1566872Y487075D01*
X1568649D01*
X1568667Y486895D01*
G03X1571459Y486917I1395J143D01*
G01X1571475Y487100D01*
X1575700D01*
X1578100Y484700D01*
X1601500D01*
X1603500Y482700D01*
Y479000D01*
X1602700Y478200D01*
X1597800D01*
X1596400Y479600D01*
X1583700D01*
X1576200Y472100D01*
X1562900D01*
X1561669Y470869D01*
G02X1561006Y471026I-283J283D01*
G03X1559235Y469255I-1331J-440D01*
G02X1559392Y468592I-126J-380D01*
G01X1559200Y468400D01*
Y467976D01*
X1558901D01*
X1558841Y468055D01*
G03X1557326Y465862I-1116J-849D01*
G02X1557496Y465196I-113J-384D01*
G01X1557220Y464920D01*
G02X1556679Y464897I-283J283D01*
G03X1554704Y462922I-904J-1071D01*
G02X1554681Y462381I-306J-258D01*
G01X1554120Y461820D01*
X1554021Y461834D01*
G03X1553867Y459045I-197J-1388D01*
G01X1553953Y459047D01*
X1554500Y458500D01*
Y457650D01*
X1554484Y457613D01*
G03X1554417Y456716I1291J-547D01*
G01X1554446Y456606D01*
X1551907Y454067D01*
G02X1551250Y454209I-283J283D01*
G03X1549443Y452402I-1312J-495D01*
G02X1549585Y451745I-141J-374D01*
G01X1548840Y451000D01*
X1545652D01*
G37*
G36*
G01X1668350Y158197D02*
X1669859D01*
X1671115Y156941D01*
Y128475D01*
X1669830Y127190D01*
X1668911D01*
G02X1668529Y127707I0J400D01*
G03X1666034Y127724I-1245J382D01*
G02X1665650Y127212I-384J-112D01*
G01X1665276D01*
Y127459D01*
X1665297Y127502D01*
G03X1662885Y127724I-1162J587D01*
G02X1662501Y127212I-384J-112D01*
G01X1662126D01*
Y127459D01*
X1662147Y127502D01*
G03X1659735Y127724I-1162J587D01*
G02X1659351Y127212I-384J-112D01*
G01X1653170D01*
G02X1652786Y127724I0J400D01*
G03X1650950Y129252I-1250J365D01*
G02X1650370Y129609I-180J357D01*
G01Y129719D01*
G02X1650950Y130076I400J0D01*
G03X1650699Y132236I586J1163D01*
G02X1650370Y132389I-129J153D01*
G01Y132656D01*
X1649302Y133724D01*
Y144384D01*
X1649711Y144792D01*
X1649927D01*
G02X1650305Y144262I0J-400D01*
G03X1652767I1231J-425D01*
G02X1653145Y144792I378J130D01*
G01X1653387D01*
G02X1653560Y144492I0J-200D01*
G03X1655916Y144262I1125J-655D01*
G02X1656294Y144792I378J130D01*
G01X1656537D01*
G02X1656710Y144492I0J-200D01*
G03X1658868Y144630I1125J-655D01*
G01X1659858Y145620D01*
X1662218D01*
X1662419Y145821D01*
Y156687D01*
X1663929Y158197D01*
X1666346D01*
Y157332D01*
G03X1668350I1002J-832D01*
G01Y158197D01*
G37*
G36*
G01X1597406Y396491D02*
X1609558D01*
G03X1609570Y396489I236J1381D01*
G01Y386957D01*
X1597406D01*
Y396491D01*
G37*
G36*
G01X1846824Y500400D02*
X1845770Y501454D01*
X1829246D01*
X1823800Y506900D01*
Y515345D01*
X1826377Y517922D01*
X1827303D01*
G03X1828272Y520400I897J1078D01*
G01X1828196Y520404D01*
X1828000Y520600D01*
X1828300Y520900D01*
X1832979D01*
G02X1833325Y520300I0J-400D01*
G03X1835932Y519770I1215J-700D01*
G02X1836389Y520214I397J49D01*
G03X1837815Y520900I211J1386D01*
G01X1838200D01*
X1839900Y522600D01*
X1843400D01*
X1843450Y522650D01*
X1857674D01*
G03X1859126Y521894I2179J2413D01*
G02X1859312Y521214I-90J-390D01*
G03X1861057Y521367I968J-1014D01*
G02X1861122Y522069I221J334D01*
G03X1862034Y522650I-1267J2995D01*
G01X1901150D01*
X1902100Y521700D01*
Y520172D01*
G03Y516484I2432J-1844D01*
G01Y510124D01*
X1897454Y505478D01*
X1875984D01*
X1875706Y505200D01*
X1866300D01*
X1863552Y502452D01*
G02X1862895Y502593I-283J283D01*
G03X1856652Y500870I-3041J-1151D01*
G02X1856259Y500400I-394J-70D01*
G01X1846824D01*
G37*
G36*
G01X1872100Y170500D02*
Y157700D01*
X1861700D01*
Y170500D01*
X1872100D01*
G37*
G36*
G01X1897600Y443900D02*
X1895627Y445873D01*
G02X1895783Y446535I283J283D01*
G03X1896598Y447151I-508J1519D01*
G02X1897261Y447149I331J-225D01*
G03X1899650Y447248I1164J781D01*
G02X1900349I349J-194D01*
G03Y448612I1225J682D01*
G02X1899650I-350J194D01*
G03X1897326Y448800I-1225J-682D01*
G02X1896665Y448850I-314J249D01*
G03X1894015Y449043I-1390J-796D01*
G02X1893386I-314J247D01*
G03X1891958Y449647I-1260J-989D01*
G01X1891863Y449637D01*
X1889304Y452196D01*
G02X1889463Y452859I283J283D01*
G03X1890228Y453394I-496J1523D01*
G02X1890858I315J-247D01*
G03X1893488Y453553I1260J989D01*
G02X1894151Y453584I342J-208D01*
G03X1896500Y453741I1124J838D01*
G02X1897200I350J-194D01*
G03Y455103I1225J681D01*
G02X1896500I-350J194D01*
G03X1894130Y455232I-1226J-681D01*
G02X1893467Y455247I-326J231D01*
G03X1890858Y455372I-1349J-864D01*
G02X1890228I-315J247D01*
G03X1889074Y455982I-1261J-989D01*
G02X1888700Y456381I26J399D01*
G01Y492100D01*
X1889915Y493315D01*
G02X1890598Y493029I283J-282D01*
G03X1894071Y496502I3502J-29D01*
G02X1893785Y497185I-4J400D01*
G01X1894322Y497722D01*
X1897854D01*
X1900980Y494596D01*
X1900921Y494470D01*
G03X1902630Y496179I3179J-1470D01*
G01X1902504Y496120D01*
X1898746Y499878D01*
X1897443D01*
G02X1897160Y500560I0J400D01*
G01X1900798Y504198D01*
X1901315D01*
X1901866Y504750D01*
X1929700D01*
X1935790Y510840D01*
X1938950D01*
X1940740Y509050D01*
Y480605D01*
G02X1940043Y480337I-400J0D01*
G03X1938117Y478311I-1043J-937D01*
G02Y477689I-252J-311D01*
G03X1940043Y475663I883J-1089D01*
G02X1940740Y475395I297J-268D01*
G01Y470040D01*
X1936650Y465950D01*
X1936635Y465940D01*
G03X1936275Y465580I795J-1155D01*
G01X1936265Y465565D01*
X1925475Y454775D01*
Y443900D01*
X1897600D01*
G37*
G36*
G01X1929587Y69229D02*
X1928490Y70326D01*
Y79900D01*
X1930734Y82144D01*
X1947316D01*
G02X1947572Y81437I0J-400D01*
G03X1949372I900J-1075D01*
G02X1949628Y82144I256J307D01*
G01X1954344D01*
X1955565Y80923D01*
Y78204D01*
X1946590Y69229D01*
X1929587D01*
G37*
G36*
G01X1903300Y88900D02*
X1902224Y89976D01*
Y101535D01*
X1902927Y102238D01*
X1908888D01*
X1909214Y101913D01*
Y89314D01*
X1908800Y88900D01*
X1903300D01*
G37*
%LPC*%
G75*
G36*
G01X746700Y-37400D02*
X783207D01*
Y-57100D01*
X746700D01*
Y-57200D01*
X521727D01*
Y-37300D01*
X746700D01*
Y-37400D01*
G37*
G36*
G01X397000Y-39100D02*
X450380D01*
Y-57500D01*
X394400D01*
Y-57530D01*
X95400D01*
Y-37300D01*
X145500D01*
Y-39050D01*
X397000D01*
Y-39100D01*
G37*
G36*
G01X853976Y-37100D02*
X1115285D01*
Y-57100D01*
X853976D01*
Y-37100D01*
G37*
G36*
G01X1407322Y-37300D02*
X1670408D01*
Y-57200D01*
X1407322D01*
Y-37300D01*
G37*
G36*
G01X427600Y659600D02*
X587400D01*
Y639900D01*
X427600D01*
Y659600D01*
G37*
G36*
G01X1245000D02*
X1529900D01*
Y639900D01*
X1245000D01*
Y659600D01*
G37*
G36*
G01X1733Y66210D02*
G03X1351Y66698I-390J88D01*
G02X2749Y67790I31J1402D01*
G03X3131Y67302I390J-88D01*
G02X1733Y66210I-31J-1402D01*
G37*
G36*
G01X15325Y53505D02*
G02X11358Y54833I-1300J2706D01*
G02X9772Y55369I-433J1334D01*
G02X11892Y59029I-784J2898D01*
G03X12484Y58787I387J101D01*
G02X15325Y58917I1541J-2576D01*
G02Y53505I1300J-2706D01*
G37*
G36*
G01X2743Y39077D02*
G02X758Y37166I857J-2877D01*
G02X2743Y39077I813J1142D01*
G37*
G36*
G01X12702Y32923D02*
G03X12689Y32394I293J-272D01*
G02X10437Y32448I-1150J-967D01*
G03X10450Y32977I-293J272D01*
G02X10468Y34931I1150J966D01*
G03Y35457I-302J263D01*
G02X12732I1132J987D01*
G03Y34931I302J-263D01*
G02X12702Y32923I-1132J-987D01*
G37*
G36*
G01X13886Y63423D02*
G02X13771Y61874I1225J-870D01*
G03X13089Y61924I-356J-182D01*
G02X10762Y63815I-1225J870D01*
G03X10775Y64344I-293J272D01*
G02X10793Y66298I1150J966D01*
G03Y66824I-302J263D01*
G02X13057I1132J987D01*
G03Y66298I302J-263D01*
G02X13027Y64290I-1132J-987D01*
G03X13014Y63761I293J-272D01*
G02X13204Y63473I-1151J-966D01*
G03X13886Y63423I356J182D01*
G37*
G36*
G01X2629Y57596D02*
G02X1052Y57616I-803J-1149D01*
G03X1060Y58277I-221J333D01*
G02X2637Y58257I803J1149D01*
G03X2629Y57596I221J-333D01*
G37*
G36*
G01X27596Y259124D02*
X32418Y263946D01*
Y266495D01*
X32252Y266662D01*
G02X34728Y269138I1238J1238D01*
G01X35922Y267945D01*
Y267392D01*
G03X36448Y267012I400J-1D01*
G02X38752Y265350I553J-1662D01*
G01Y261790D01*
X30082Y253120D01*
X21339D01*
X21142Y252924D01*
G02X18666Y255400I-1238J1238D01*
G01X19244Y255979D01*
X18562Y256662D01*
G02X21053Y259124I1238J1238D01*
G01X27596D01*
G37*
G36*
G01X58748Y517276D02*
G02X57124I-812J-1264D01*
G03Y517948I-216J336D01*
G02X56933Y518094I814J1263D01*
G03X56420Y518113I-268J-297D01*
G02X54397Y518281I-920J1187D01*
G03X54103I-147J-136D01*
G02X54037Y518214I-1102J1020D01*
G03X54036Y517925I138J-145D01*
G02X51848Y517819I-1044J-1079D01*
G03X51849Y518335I-305J259D01*
G02X51868Y520287I1151J965D01*
G03Y520813I-302J263D01*
G02Y522787I1132J987D01*
G03Y523313I-302J263D01*
G02X51736Y523488I1130J990D01*
G03X51064I-336J-216D01*
G02Y525112I-1264J812D01*
G03X51736I336J216D01*
G02X53987Y525432I1264J-812D01*
G03X54513I263J302D01*
G02X56487I987J-1132D01*
G03X57013I263J302D01*
G02X58096Y525799I987J-1132D01*
G03X58517Y526262I26J399D01*
G02X59904Y525001I1483J238D01*
G03X59483Y524538I-26J-399D01*
G02X59132Y523313I-1483J-238D01*
G03Y522787I302J-263D01*
G02X59158Y522757I-1122J-999D01*
G03X59475Y522769I154J128D01*
G02X59673Y520804I1225J-869D01*
G03X59105Y520783I-274J-292D01*
G02X59075Y520751I-1111J1011D01*
G03X59061Y520207I286J-280D01*
G02X58748Y517948I-1125J-995D01*
G03Y517276I216J-336D01*
G37*
G36*
G01X325676Y104251D02*
G03X326253Y104144I338J214D01*
G02X325908Y102270I839J-1123D01*
G03X325331Y102377I-338J-214D01*
G02X325676Y104251I-839J1123D01*
G37*
G36*
G01X364495Y91490D02*
G03X363904I-295J-269D01*
G02Y93510I-1112J1010D01*
G03X364495I296J269D01*
G02Y91490I1112J-1010D01*
G37*
G36*
G01X364129Y86483D02*
G03X363540I-295J-271D01*
G02Y88517I-1105J1017D01*
G03X364129I294J271D01*
G02Y86483I1105J-1017D01*
G37*
G36*
G01X428560Y108040D02*
X445159Y91441D01*
X445215Y91428D01*
G02X446150Y89162I-335J-1464D01*
G01Y85516D01*
G02Y83912I-1270J-802D01*
G01Y66417D01*
X446166Y66379D01*
G02Y65265I-1286J-557D01*
G01X446150Y65227D01*
Y63030D01*
X445390Y62270D01*
X397810D01*
X395510Y64570D01*
Y66742D01*
G03X395015Y67130I-400J0D01*
G02Y69854I-333J1362D01*
G03X395510Y70242I95J388D01*
G01Y85539D01*
G03X395020Y85929I-400J0D01*
G02Y88855I-338J1463D01*
G03X395510Y89245I90J390D01*
G01Y90940D01*
X397800Y93230D01*
Y105930D01*
X399910Y108040D01*
X428560D01*
G37*
G36*
G01X449900Y55935D02*
G03X450461Y55966I265J300D01*
G02X450520Y53886I1112J-1009D01*
G03X449958I-281J-285D01*
G02X449900Y55935I-985J997D01*
G37*
G36*
G01X358702Y51293D02*
G03Y50699I268J-297D01*
G02X356822I-940J-1040D01*
G03Y51293I-268J297D01*
G02X358702I940J1040D01*
G37*
G36*
G01X363196Y46006D02*
G03X362587I-305J-258D01*
G02Y47822I-1069J908D01*
G03X363196I305J258D01*
G02Y46006I1069J-908D01*
G37*
G36*
G01X383740Y36910D02*
X381940Y35110D01*
X371680D01*
X370260Y36530D01*
Y45736D01*
G02Y48064I782J1164D01*
G01Y59630D01*
X369430Y60460D01*
Y86920D01*
X369140Y87210D01*
X371050Y89120D01*
X381750D01*
X383903Y86967D01*
G03X384586Y87250I283J283D01*
G01Y91128D01*
G02X391788I3601J0D01*
G01Y86228D01*
G02X387920Y82636I-3602J0D01*
G03X387490Y82238I-30J-399D01*
G01Y76218D01*
G03X387920Y75820I400J1D01*
G02X391788Y72228I266J-3592D01*
G01Y67328D01*
G02X387920Y63736I-3602J0D01*
G03X387490Y63338I-30J-399D01*
G01Y62510D01*
X387530Y62470D01*
Y60580D01*
X383740Y56790D01*
Y36910D01*
G37*
G36*
G01X359577Y32318D02*
G03X359571Y31740I273J-292D01*
G02X357634Y31760I-979J-1004D01*
G03X357640Y32338I-273J292D01*
G02X359577Y32318I979J1004D01*
G37*
G36*
G01X450568Y85691D02*
G02X450273Y84189I1005J-977D01*
G03X449615Y84319I-371J-149D01*
G02X449910Y85821I-1005J977D01*
G03X450568Y85691I371J149D01*
G37*
G36*
G01X449516Y69174D02*
G02X447757Y69189I-889J-1084D01*
G03X447762Y69812I-249J314D01*
G02X447699Y71926I889J1084D01*
G03X447688Y72523I-271J294D01*
G02X449700Y74456I910J1066D01*
G03X450361Y74503I315J248D01*
G02X450472Y72932I1212J-704D01*
G03X449811Y72885I-315J-248D01*
G02X449551Y72559I-1214J702D01*
G03X449562Y71962I271J-294D01*
G02X449521Y69797I-911J-1066D01*
G03X449516Y69174I249J-314D01*
G37*
G36*
G01X352990Y62080D02*
X319170D01*
X317260Y63990D01*
Y64376D01*
X317137Y64427D01*
G02Y67201I577J1387D01*
G01X317260Y67252D01*
Y72424D01*
X317142Y72477D01*
G02Y75037I572J1280D01*
G01X317260Y75090D01*
Y83381D01*
X317142Y83434D01*
G02Y85994I572J1280D01*
G01X317260Y86047D01*
Y88526D01*
X317137Y88577D01*
G02X317315Y91412I577J1387D01*
G01X317366Y91426D01*
X320890Y94950D01*
X355290D01*
X356340Y93900D01*
Y72412D01*
G03X356969Y72084I400J0D01*
G02X358743Y69924I802J-1150D01*
G03Y69346I277J-289D01*
G02X356969Y67186I-972J-1010D01*
G03X356340Y66858I-229J-328D01*
G01Y65430D01*
X352990Y62080D01*
G37*
G36*
G01X362540Y54128D02*
G02Y55556I-1322J714D01*
G03X363243I352J190D01*
G02Y54128I1322J-714D01*
G03X362540I-351J-190D01*
G37*
G36*
G01X450402Y47672D02*
G02X450366Y46187I1171J-771D01*
G03X449688Y46203I-344J-204D01*
G02X449724Y47688I-1171J771D01*
G03X450402Y47672I344J204D01*
G37*
G36*
G01X362540Y35228D02*
G02Y36656I-1322J714D01*
G03X363243I352J190D01*
G02Y35228I1322J-714D01*
G03X362540I-351J-190D01*
G37*
G36*
G01X449693Y35187D02*
G02X449593Y36520I-1279J574D01*
G03X450294Y36573I336J217D01*
G02X450394Y35240I1279J-574D01*
G03X449693Y35187I-336J-217D01*
G37*
G36*
G01X463914Y314235D02*
G03X463891Y313677I275J-291D01*
G02X461882Y313757I-1043J-936D01*
G03X461905Y314315I-275J291D01*
G02X463914Y314235I1043J936D01*
G37*
G36*
G01X459399Y277949D02*
G03X459398Y277385I283J-283D01*
G02X457409Y277391I-997J-985D01*
G03X457410Y277955I-283J283D01*
G02X459399Y277949I997J985D01*
G37*
G36*
G01X465845Y293836D02*
G02X464680Y292661I221J-1384D01*
G03X464221Y293116I-396J60D01*
G02X465386Y294291I-221J1384D01*
G03X465845Y293836I396J-60D01*
G37*
G36*
G01X776892Y377686D02*
G03X776286Y377668I-295J-270D01*
G02X774019Y379637I-1164J949D01*
G03X774032Y380166I-293J272D01*
G02X774050Y382120I1150J966D01*
G03Y382646I-302J263D01*
G02X776314I1132J987D01*
G03Y382120I302J-263D01*
G02X776284Y380112I-1132J-987D01*
G03X776271Y379583I293J-272D01*
G02X776368Y379453I-1154J-962D01*
G03X776706Y379463I166J112D01*
G02X776892Y377686I1294J-763D01*
G37*
G36*
G01X778810Y371129D02*
G03X778193Y371122I-306J-258D01*
G02X778172Y372904I-1093J878D01*
G03X778789Y372911I306J258D01*
G02X778810Y371129I1093J-878D01*
G37*
G36*
G01X771160Y372542D02*
G03X770929Y373080I-366J161D01*
G02X772683Y373834I472J1320D01*
G03X772914Y373296I366J-161D01*
G02X771160Y372542I-472J-1320D01*
G37*
G36*
G01X767955Y352504D02*
G03X768121Y351953I349J-195D01*
G02X766254Y351393I-644J-1245D01*
G03X766088Y351944I-349J195D01*
G02X767955Y352504I644J1245D01*
G37*
G36*
G01X776250Y347661D02*
G03X776535Y347659I143J139D01*
G02X776633Y345450I1065J-1059D01*
G03X776122Y345454I-258J-306D01*
G02X774069Y347637I-951J1163D01*
G03X774082Y348166I-293J272D01*
G02X774100Y350120I1150J966D01*
G03Y350646I-302J263D01*
G02X776364I1132J987D01*
G03Y350120I302J-263D01*
G02X776216Y347998I-1132J-987D01*
G03X776208Y347702I131J-152D01*
G02X776250Y347661I-1028J-1095D01*
G37*
G36*
G01X776797Y313582D02*
G03X776244Y313565I-268J-297D01*
G02X774069Y315637I-1073J1051D01*
G03X774082Y316166I-293J272D01*
G02X774100Y318120I1150J966D01*
G03Y318646I-302J263D01*
G02X776364I1132J987D01*
G03Y318120I302J-263D01*
G02X776216Y315998I-1132J-987D01*
G03X776208Y315702I131J-152D01*
G02X776301Y315606I-1031J-1092D01*
G03X776610Y315616I150J132D01*
G02X776797Y313582I1190J-916D01*
G37*
G36*
G01X772396Y309446D02*
G03X772325Y308851I227J-329D01*
G02X770482Y309072I-1047J-933D01*
G03X770553Y309667I-227J329D01*
G02X772396Y309446I1047J933D01*
G37*
G36*
G01X776293Y283614D02*
G03X776590Y283612I149J133D01*
G02X776694Y281484I1110J-1012D01*
G03X776162Y281488I-268J-297D01*
G02X774069Y283637I-991J1129D01*
G03X774082Y284166I-293J272D01*
G02X774100Y286120I1150J966D01*
G03Y286646I-302J263D01*
G02X776364I1132J987D01*
G03Y286120I302J-263D01*
G02X776216Y283998I-1132J-987D01*
G03X776208Y283702I131J-152D01*
G02X776293Y283614I-1037J-1086D01*
G37*
G36*
G01X746896Y281538D02*
G02X752004Y280262I2904J762D01*
G02X746896Y281538I-2904J-762D01*
G37*
G36*
G01X778572Y275068D02*
G03X777973Y274913I-236J-323D01*
G02X777528Y276632I-1273J588D01*
G03X778127Y276787I236J323D01*
G02X778572Y275068I1273J-588D01*
G37*
G36*
G01X752199Y274925D02*
G02X757405Y274771I2647J1415D01*
G02X752199Y274925I-2647J-1415D01*
G37*
G36*
G01X746387Y268945D02*
G02X751693Y268755I2703J1305D01*
G02X746387Y268945I-2703J-1305D01*
G37*
G36*
G01X752813Y251578D02*
G02X750240Y251423I-1450J2629D01*
G02X746261Y255750I-1540J2577D01*
G02X751686Y257192I2439J1750D01*
G02X752813Y256836I-323J-2985D01*
G02Y251578I1450J-2629D01*
G37*
G36*
G01X766693Y253259D02*
G03X766354Y252751I45J-397D01*
G02X764846Y253756I-1347J-388D01*
G03X765185Y254264I-45J397D01*
G02X765602Y255701I1347J388D01*
G03X765624Y256278I-266J299D01*
G02X767562Y256203I1008J974D01*
G03X767540Y255626I266J-299D01*
G02X766693Y253259I-1008J-974D01*
G37*
G36*
G01X776293Y251614D02*
G03X776590Y251612I149J133D01*
G02X776694Y249484I1110J-1012D01*
G03X776162Y249488I-268J-297D01*
G02X774069Y251637I-991J1129D01*
G03X774082Y252166I-293J272D01*
G02X774100Y254120I1150J966D01*
G03Y254646I-302J263D01*
G02X776364I1132J987D01*
G03Y254120I302J-263D01*
G02X776216Y251998I-1132J-987D01*
G03X776208Y251702I131J-152D01*
G02X776293Y251614I-1037J-1086D01*
G37*
G36*
G01X747300Y242136D02*
G03X747304Y241569I284J-282D01*
G02X745324Y241555I-983J-1000D01*
G03X745320Y242122I-284J282D01*
G02X747300Y242136I983J1000D01*
G37*
G36*
G01X767662Y224140D02*
G03X767640Y223563I266J-299D01*
G02X765702Y223638I-1008J-974D01*
G03X765724Y224215I-266J299D01*
G02X767662Y224140I1008J974D01*
G37*
G36*
G01X776293Y219614D02*
G03X776590Y219612I149J133D01*
G02X776694Y217484I1110J-1012D01*
G03X776162Y217488I-268J-297D01*
G02X774069Y219637I-991J1129D01*
G03X774082Y220166I-293J272D01*
G02X774100Y222120I1150J966D01*
G03Y222646I-302J263D01*
G02X776364I1132J987D01*
G03Y222120I302J-263D01*
G02X776216Y219998I-1132J-987D01*
G03X776208Y219702I131J-152D01*
G02X776293Y219614I-1037J-1086D01*
G37*
G36*
G01X776171Y211062D02*
G03X775593I-289J-277D01*
G02Y213004I-1011J971D01*
G03X776171I289J277D01*
G02X778252Y212939I1011J-971D01*
G03X778862I305J259D01*
G02Y211127I1070J-906D01*
G03X778252I-305J-259D01*
G02X776171Y211062I-1070J906D01*
G37*
G36*
G01X766290Y380798D02*
G02X764936Y381765I-1333J-435D01*
G03X765310Y382289I-6J400D01*
G02X766009Y383974I1333J435D01*
G03X766122Y384602I-181J357D01*
G02X767789Y384300I1033J948D01*
G03X767676Y383672I181J-357D01*
G02X766664Y381322I-1033J-948D01*
G03X766290Y380798I6J-400D01*
G37*
G36*
G01X764923Y374919D02*
G02X763374Y374904I-763J-1176D01*
G03X763367Y375571I-224J331D01*
G02X764916Y375586I763J1176D01*
G03X764923Y374919I224J-331D01*
G37*
G36*
G01X761107Y361064D02*
G02X759612Y360885I-607J-1264D01*
G03X759533Y361555I-253J310D01*
G02X761028Y361734I607J1264D01*
G03X761107Y361064I253J-310D01*
G37*
G36*
G01X775465Y339137D02*
G02X775435Y340868I-1118J846D01*
G03X776064Y340879I310J252D01*
G02X778252Y340939I1118J-846D01*
G03X778862I305J259D01*
G02Y339127I1070J-906D01*
G03X778252I-305J-259D01*
G02X776094Y339148I-1070J906D01*
G03X775465Y339137I-310J-252D01*
G37*
G36*
G01X764141Y339743D02*
G02X763234Y340819I-1381J-244D01*
G03X763763Y341265I135J377D01*
G02X764359Y342669I1381J242D01*
G03X764352Y343336I-224J331D01*
G02X765901Y343351I763J1176D01*
G03X765908Y342684I224J-331D01*
G02X764670Y340189I-764J-1176D01*
G03X764141Y339743I-135J-377D01*
G37*
G36*
G01X766382Y316635D02*
G02X765182Y317754I-1375J-272D01*
G03X765625Y318228I50J397D01*
G02X765973Y319454I1375J272D01*
G03X765913Y320051I-293J272D01*
G02X767759Y320235I819J1138D01*
G03X767819Y319638I293J-272D01*
G02X766825Y317109I-819J-1138D01*
G03X766382Y316635I-50J-397D01*
G37*
G36*
G01X765908Y310684D02*
G02X764359Y310669I-763J-1176D01*
G03X764352Y311336I-224J331D01*
G02X765901Y311351I763J1176D01*
G03X765908Y310684I224J-331D01*
G37*
G36*
G01X777591Y306631D02*
G02X777150Y308191I-1321J469D01*
G03X777779Y308369I252J311D01*
G02X778220Y306809I1321J-469D01*
G03X777591Y306631I-252J-311D01*
G37*
G36*
G01X766364Y284716D02*
G02X765442Y285696I-1357J-353D01*
G03X765953Y286177I124J380D01*
G02X765923Y286323I1357J355D01*
G03X765406Y286644I-395J-60D01*
G02X766367Y288187I-426J1336D01*
G03X766884Y287866I395J60D01*
G02X766875Y285197I426J-1336D01*
G03X766364Y284716I-124J-380D01*
G37*
G36*
G01X765908Y278684D02*
G02X764359Y278669I-763J-1176D01*
G03X764352Y279336I-224J331D01*
G02X765901Y279351I763J1176D01*
G03X765908Y278684I224J-331D01*
G37*
G36*
G01Y246684D02*
G02X764359Y246669I-763J-1176D01*
G03X764352Y247336I-224J331D01*
G02X765901Y247351I763J1176D01*
G03X765908Y246684I224J-331D01*
G37*
G36*
G01X778282Y242932D02*
G02X778000Y244483I-1282J568D01*
G03X778650Y244601I285J281D01*
G02X778932Y243050I1282J-568D01*
G03X778282Y242932I-285J-281D01*
G37*
G36*
G01X765908Y214684D02*
G02X764359Y214669I-763J-1176D01*
G03X764352Y215336I-224J331D01*
G02X765901Y215351I763J1176D01*
G03X765908Y214684I224J-331D01*
G37*
G36*
G01X1373032Y27613D02*
G03Y27087I302J-263D01*
G02X1370768I-1132J-987D01*
G03Y27613I-302J263D01*
G02Y29587I1132J987D01*
G03Y30113I-302J263D01*
G02X1373032I1132J987D01*
G03Y29587I302J-263D01*
G02Y27613I-1132J-987D01*
G37*
G36*
G01X1382196Y27186D02*
G02X1381043Y24630I-554J-1288D01*
G02X1377988Y29746I-1843J2370D01*
G02X1382162Y27486I2962J486D01*
G02X1382196Y27186I-2962J-488D01*
G37*
G36*
G01X1368378Y4805D02*
G03X1367800I-289J-277D01*
G02Y6747I-1011J971D01*
G03X1368378I289J277D01*
G02Y4805I1011J-971D01*
G37*
G36*
G01X1382754Y-2591D02*
G02X1382952Y-4394I-2746J-1214D01*
G02X1381189Y-6565I-802J-1150D01*
G02X1377932Y-1636I-1181J2760D01*
G02X1378026Y984I2746J1213D01*
G02X1377620Y1591I2274J1960D01*
G03X1377357Y1683I-179J-90D01*
G02X1374463Y6926I-1262J2724D01*
G02X1377028Y7259I1213J704D01*
G02X1377417Y7101I-932J-2854D01*
G03X1377675Y7174I89J179D01*
G02X1382955Y4345I2544J-1594D01*
G02X1382952Y1538I-2655J-1401D01*
G02X1382754Y-2591I-2274J-1960D01*
G37*
G36*
G01X1372721Y-4411D02*
G03Y-4937I302J-263D01*
G02X1370457I-1132J-987D01*
G03Y-4411I-302J263D01*
G02X1370487Y-2403I1132J987D01*
G03X1370500Y-1874I-293J272D01*
G02X1372752Y-1928I1150J967D01*
G03X1372739Y-2457I293J-272D01*
G02X1372721Y-4411I-1150J-966D01*
G37*
G36*
G01X1370996Y395697D02*
G03X1370418I-289J-277D01*
G02Y397639I-1011J971D01*
G03X1370996I289J277D01*
G02Y395697I1011J-971D01*
G37*
G36*
G01X1383278Y395272D02*
G02X1382250Y389671I422J-2972D01*
G02X1377882Y393006I-1450J2629D01*
G03X1377753Y393242I-194J47D01*
G02X1379461Y395195I454J1326D01*
G03X1379712Y395098I179J89D01*
G02X1379932Y395174I1090J-2797D01*
G03X1380190Y395700I-115J383D01*
G02X1382840Y395786I1310J500D01*
G03X1383278Y395272I382J-118D01*
G37*
G36*
G01X1375339Y386481D02*
G03Y385955I302J-263D01*
G02X1373075I-1132J-987D01*
G03Y386481I-302J263D01*
G02X1373105Y388489I1132J987D01*
G03X1373118Y389018I-293J272D01*
G02X1375370Y388964I1150J967D01*
G03X1375357Y388435I293J-272D01*
G02X1375339Y386481I-1150J-966D01*
G37*
G36*
G01X1515380Y611807D02*
G03X1514854I-263J-302D01*
G02X1512846Y611837I-987J1132D01*
G03X1512317Y611850I-272J-293D01*
G02X1512371Y614102I-967J1150D01*
G03X1512900Y614089I272J293D01*
G02X1514854Y614071I966J-1150D01*
G03X1515380I263J302D01*
G02Y611807I987J-1132D01*
G37*
G36*
G01X1479322Y612798D02*
G03X1479833Y612784I264J300D01*
G02X1479767Y610475I927J-1182D01*
G03X1479256Y610489I-264J-300D01*
G02X1477308Y610569I-927J1182D01*
G03X1476779Y610582I-272J-293D01*
G02X1476833Y612834I-967J1150D01*
G03X1477362Y612821I272J293D01*
G02X1479322Y612798I967J-1150D01*
G37*
G36*
G01X1501994Y609800D02*
G02X1507406I2706J1300D01*
G02X1501994I-2706J-1300D01*
G37*
G36*
G01X1466638Y609175D02*
G02X1471863Y609354I2562J1564D01*
G02X1466638Y609175I-2562J-1564D01*
G37*
G36*
G01X1520505Y597038D02*
G03X1520268Y596884I-41J-196D01*
G02X1517342Y596839I-1468J316D01*
G03X1516921Y597142I-388J-96D01*
G02X1516432Y597183I-121J1497D01*
G03X1515948Y596901I-98J-388D01*
G02X1513027Y597008I-1448J399D01*
G03X1512792Y597166I-196J-38D01*
G02X1512319Y597148I-293J1473D01*
G03X1511888Y596866I-48J-397D01*
G02X1509463Y596168I-1438J434D01*
G03X1508937I-263J-302D01*
G02X1506895Y598369I-986J1133D01*
G03X1506912Y598920I-281J284D01*
G02X1508609Y601308I1119J1002D01*
G03X1509117Y601493I153J369D01*
G02X1511937Y600590I1333J-693D01*
G03X1512368Y600135I396J-56D01*
G02X1513973Y598931I132J-1496D01*
G03X1514208Y598773I196J38D01*
G02X1514868Y598756I292J-1473D01*
G03X1515352Y599038I98J388D01*
G02X1518258Y599000I1448J-399D01*
G03X1518679Y598697I388J96D01*
G02X1519108Y598670I121J-1497D01*
G03X1519345Y598824I41J196D01*
G02X1522265Y598892I1468J-316D01*
G03X1522510Y598751I193J52D01*
G02X1523086Y598790I388J-1451D01*
G03X1523310Y598964I25J199D01*
G02X1526268Y599095I1490J-187D01*
G03X1526720Y598784I391J84D01*
G02X1525482Y596983I230J-1484D01*
G03X1525030Y597294I-391J-84D01*
G02X1524614Y597288I-229J1484D01*
G03X1524390Y597114I-25J-199D01*
G02X1521448Y596916I-1490J186D01*
G03X1521203Y597057I-193J-52D01*
G02X1520505Y597038I-389J1451D01*
G37*
G36*
G01X1473925Y594900D02*
G03X1473399I-263J-302D01*
G02X1471191Y595158I-987J1132D01*
G03X1470622Y595242I-325J-233D01*
G02X1469098Y597585I-855J1111D01*
G03X1469083Y598295I-191J351D01*
G02X1470710Y600527I618J1259D01*
G03X1471296Y600537I288J277D01*
G02X1473399Y600664I1116J-1005D01*
G03X1473925I263J302D01*
G02X1476414Y599532I987J-1132D01*
G03X1476880Y599137I400J0D01*
G02X1478601Y597954I249J-1481D01*
G03X1479001Y597634I392J80D01*
G02X1479303Y597609I28J-1502D01*
G03X1479766Y597911I74J393D01*
G02X1482721Y597741I1463J-340D01*
G03X1482942Y597565I199J23D01*
G02X1483463Y597530I161J-1493D01*
G03X1483952Y597846I96J388D01*
G02X1486903Y597857I1477J-275D01*
G03X1487303Y597534I393J77D01*
G02X1487355I26J-1502D01*
G03X1487755Y597857I7J400D01*
G02X1490707Y597837I1474J-287D01*
G03X1491166Y597514I394J72D01*
G02X1489934Y595766I246J-1482D01*
G03X1489475Y596089I-394J-72D01*
G02X1489203Y596069I-246J1482D01*
G03X1488803Y595746I-7J-400D01*
G02X1485855I-1474J286D01*
G03X1485455Y596069I-393J-77D01*
G02X1485070Y596113I-23J1502D01*
G03X1484581Y595797I-96J-388D01*
G02X1481612Y595902I-1477J275D01*
G03X1481391Y596078I-199J-23D01*
G02X1480955Y596094I-164J1493D01*
G03X1480492Y595792I-74J-393D01*
G02X1477557Y595834I-1463J340D01*
G03X1477157Y596154I-392J-80D01*
G02X1476867Y596177I-27J1502D01*
G03X1476401Y595835I-69J-394D01*
G02X1473925Y594900I-1489J197D01*
G37*
G36*
G01X1385364Y578200D02*
G03X1385695Y577683I381J-120D01*
G02X1387825Y576353I-379J-2978D01*
G02X1389002Y575926I161J-1393D01*
G03X1389588Y575931I291J275D01*
G02X1389607Y574020I1035J-945D01*
G03X1389021Y574015I-291J-275D01*
G02X1388092Y573562I-1036J945D01*
G02X1383278Y572501I-2776J1143D01*
G02X1380136Y577250I-778J2899D01*
G02X1379623Y579957I2364J1850D01*
G03X1379198Y580470I-383J115D01*
G02X1379783Y583061I-145J1394D01*
G03X1380354Y583233I209J341D01*
G02X1385359Y580016I2720J-1270D01*
G02X1385364Y578200I-2859J-916D01*
G37*
G36*
G01X1377132Y574469D02*
G03Y573943I302J-263D01*
G02X1374868I-1132J-987D01*
G03Y574469I-302J263D01*
G02X1374859Y576432I1132J987D01*
G03X1374850Y576962I-304J260D01*
G02X1377102Y576997I1111J1011D01*
G03X1377111Y576467I304J-260D01*
G02X1377132Y574469I-1111J-1011D01*
G37*
G36*
G01X1375668Y585155D02*
G02X1375520Y583756I1132J-827D01*
G03X1374832Y583829I-365J-163D01*
G02X1372689Y583685I-1132J827D01*
G03X1372111I-289J-277D01*
G02Y585627I-1011J971D01*
G03X1372689I289J277D01*
G02X1374980Y585228I1011J-971D01*
G03X1375668Y585155I365J163D01*
G37*
G36*
G01X1491077Y560687D02*
G03X1490504Y560667I-277J-289D01*
G02X1490426Y562897I-1188J1075D01*
G03X1490999Y562917I277J289D01*
G02X1493387Y562903I1188J-1075D01*
G03X1493987I300J265D01*
G02X1496267Y563025I1200J-1061D01*
G03X1496812Y563031I269J296D01*
G02X1498963Y563086I1106J-1159D01*
G03X1499485I261J303D01*
G02Y560658I1045J-1214D01*
G03X1498963I-261J-303D01*
G02X1496838Y560689I-1045J1214D01*
G03X1496293Y560683I-269J-296D01*
G02X1493987Y560781I-1106J1159D01*
G03X1493387I-300J-265D01*
G02X1491077Y560687I-1200J1061D01*
G37*
G36*
G01X1496273Y547033D02*
G03X1496820Y547010I286J280D01*
G02X1496723Y544674I1046J-1213D01*
G03X1496176Y544697I-286J-280D01*
G02X1493930Y544849I-1046J1213D01*
G03X1493330I-300J-265D01*
G02X1490874Y544916I-1200J1061D01*
G03X1490298Y544970I-314J-248D01*
G02X1490387Y547006I-918J1060D01*
G03X1490965Y547010I287J278D01*
G02X1493330Y546971I1165J-1100D01*
G03X1493930I300J265D01*
G02X1496273Y547033I1200J-1061D01*
G37*
G36*
G01X1482927Y538690D02*
G03X1482373I-277J-288D01*
G02Y540710I-973J1010D01*
G03X1482927I277J288D01*
G02Y538690I973J-1010D01*
G37*
G36*
G01X1483227Y523190D02*
G03X1482673I-277J-288D01*
G02Y525210I-973J1010D01*
G03X1483227I277J288D01*
G02Y523190I973J-1010D01*
G37*
G36*
G01X1497993Y514621D02*
G03X1497576Y514222I-17J-400D01*
G02X1496160Y515623I-1402J-1D01*
G03X1496555Y516044I-4J400D01*
G02X1498091Y517624I1500J78D01*
G01X1500655D01*
G02X1502156Y516132I-1J-1502D01*
G01Y516037D01*
X1502147Y515953D01*
G02X1500655Y514620I-1492J169D01*
G01X1498091D01*
G02X1497993Y514621I-34J1502D01*
G37*
G36*
G01X1504996Y433308D02*
G03X1504477Y433036I-133J-377D01*
G02X1503591Y434728I-1352J370D01*
G03X1504110Y435000I133J377D01*
G02X1504427Y435576I1353J-369D01*
G03X1504411Y436131I-296J269D01*
G02X1506427Y436187I981J1002D01*
G03X1506443Y435632I296J-269D01*
G02X1504996Y433308I-981J-1002D01*
G37*
G36*
G01Y419784D02*
G03X1504478Y419514I-133J-377D01*
G02X1501738Y419711I-1350J378D01*
G03X1501304Y420058I-397J-51D01*
G02X1502565Y421635I-129J1396D01*
G03X1502999Y421288I397J51D01*
G02X1503591Y421215I128J-1396D01*
G03X1504109Y421485I133J377D01*
G02X1504508Y422137I1350J-378D01*
G03X1504541Y422692I-271J295D01*
G02X1504241Y423278I1063J914D01*
G03X1503691Y423551I-389J-93D01*
G02X1504489Y425160I-566J1283D01*
G03X1505039Y424887I389J93D01*
G02X1506556Y422574I566J-1283D01*
G03X1506523Y422019I271J-295D01*
G02X1504996Y419784I-1065J-912D01*
G37*
G36*
G01X1495528Y530151D02*
G02X1495133Y531647I-1328J449D01*
G03X1495778Y531817I266J298D01*
G02X1496173Y530321I1328J-449D01*
G03X1495528Y530151I-266J-298D01*
G37*
G36*
G01X1513255Y531516D02*
G02X1512857Y529799I863J-1105D01*
G03X1512251Y529940I-360J-174D01*
G02X1510588Y529893I-863J1105D01*
G03X1510008Y529754I-228J-328D01*
G02X1507520Y529784I-1236J662D01*
G03X1506816Y529803I-357J-180D01*
G02X1504666Y529454I-1216J697D01*
G03X1504134I-266J-298D01*
G02Y531546I-934J1046D01*
G03X1504666I266J298D01*
G02X1506852Y531132I934J-1046D01*
G03X1507556Y531113I357J180D01*
G02X1509572Y531568I1217J-697D01*
G03X1510152Y531707I228J328D01*
G02X1512649Y531657I1236J-662D01*
G03X1513255Y531516I360J174D01*
G37*
G36*
G01X1474542Y525426D02*
G02X1473431Y526778I-1402J-19D01*
G03X1473914Y527175I83J391D01*
G02X1475025Y525823I1402J19D01*
G03X1474542Y525426I-83J-391D01*
G37*
G36*
G01X1489743Y518245D02*
G02X1488278Y519206I-1333J-435D01*
G03X1488631Y519687I-38J398D01*
G02X1490100Y521502I1469J313D01*
G01X1492664D01*
G02X1492757Y521501I30J-1502D01*
G03X1492910Y521838I8J200D01*
G02X1494214Y521427I1020J962D01*
G03X1493960Y520818I82J-391D01*
G02X1492664Y518498I-1260J-818D01*
G01X1490099D01*
G02X1489953Y518506I9J1502D01*
G03X1489743Y518245I-20J-199D01*
G37*
G36*
G01X1498426Y506112D02*
G02X1496892Y506674I-1159J-789D01*
G03X1497099Y507308I-106J386D01*
G02X1498277Y509740I1178J931D01*
G01X1500838D01*
X1500841Y509741D01*
G02Y506737I36J-1502D01*
G01X1500838Y506738D01*
X1498756D01*
G03X1498426Y506112I0J-400D01*
G37*
G36*
G01X1532475Y434969D02*
G02X1530569Y436875I-1225J681D01*
G03Y437575I-194J350D01*
G02Y440025I681J1225D01*
G03Y440725I-194J350D01*
G02X1532475Y442631I681J1225D01*
G03X1533175I350J194D01*
G02X1535625I1225J-681D01*
G03X1536325I350J194D01*
G02X1538775I1225J-681D01*
G03X1539475I350J194D01*
G02X1541925I1225J-681D01*
G03X1542625I350J194D01*
G02X1543169Y443175I1225J-681D01*
G03Y443875I-194J350D01*
G02X1544531I681J1225D01*
G03Y443175I194J-350D01*
G02X1544569Y440746I-681J-1225D01*
G03X1544591Y440047I205J-343D01*
G02Y437553I-641J-1247D01*
G03X1544569Y436854I183J-356D01*
G02X1543209Y436897I-719J-1204D01*
G03X1543231Y437596I-183J356D01*
G02Y440004I719J1204D01*
G03X1543209Y440703I-205J343D01*
G02X1542625Y441269I642J1246D01*
G03X1541925I-350J-194D01*
G02X1539475I-1225J681D01*
G03X1538775I-350J-194D01*
G02X1536325I-1225J681D01*
G03X1535625I-350J-194D01*
G02X1535081Y440725I-1225J681D01*
G03Y440025I194J-350D01*
G02Y437575I-681J-1225D01*
G03Y436875I194J-350D01*
G02X1535625Y436331I-681J-1225D01*
G03X1536325I350J194D01*
G02Y434969I1225J-681D01*
G03X1535625I-350J-194D01*
G02X1533175I-1225J681D01*
G03X1532475I-350J-194D01*
G37*
G36*
G01X1525631Y436875D02*
G02X1524269I-681J-1225D01*
G03Y437575I-194J350D01*
G02Y440025I681J1225D01*
G03Y440725I-194J350D01*
G02X1523725Y441269I681J1225D01*
G03X1523025I-350J-194D01*
G02Y442631I-1225J681D01*
G03X1523725I350J194D01*
G02X1525631Y440725I1225J-681D01*
G03Y440025I194J-350D01*
G02Y437575I-681J-1225D01*
G03Y436875I194J-350D01*
G37*
G36*
G01X1491455Y489341D02*
G03X1491749Y488850I387J-102D01*
G02X1490070Y487845I-324J-1364D01*
G03X1489776Y488336I-387J102D01*
G02X1491455Y489341I324J1364D01*
G37*
G36*
G01X1511165Y455164D02*
G02X1511145Y453875I1235J-664D01*
G03X1510435Y453886I-358J-179D01*
G02X1510455Y455175I-1235J664D01*
G03X1511165Y455164I358J179D01*
G37*
G36*
G01X1570800Y480997D02*
G02X1569699Y482101I-1375J-271D01*
G03X1570170Y482571I78J392D01*
G02X1571271Y481467I1375J271D01*
G03X1570800Y480997I-78J-392D01*
G37*
G36*
G01X1886127Y508500D02*
G02Y513904I0J2702D01*
G01X1888527D01*
G02Y508500I0J-2702D01*
G01X1886127D01*
G37*
G36*
G01X1843621Y506748D02*
G03X1843743Y506189I334J-220D01*
G02X1841829Y505772I-743J-1189D01*
G03X1841707Y506331I-334J220D01*
G02X1842636Y508910I743J1189D01*
G03X1843089Y509289I54J396D01*
G02X1844304Y507840I1401J-59D01*
G03X1843851Y507461I-54J-396D01*
G02X1843621Y506748I-1401J58D01*
G37*
G36*
G01X1915424Y468001D02*
G03X1916048I312J250D01*
G02X1916047Y465998I1250J-1002D01*
G03X1915423I-312J-250D01*
G02X1912903Y466023I-1250J1002D01*
G03X1912269I-317J-243D01*
G02Y467977I-1270J977D01*
G03X1912903I317J243D01*
G02X1915424Y468001I1270J-977D01*
G37*
G36*
G01X1911277Y473167D02*
G02X1909723I-777J-1167D01*
G03Y473833I-222J333D01*
G02X1911277I777J1167D01*
G03Y473167I222J-333D01*
G37*
G36*
G01X1905949Y453741D02*
G02Y455103I-1225J681D01*
G03X1906649I350J194D01*
G02Y453741I1225J-681D01*
G03X1905949I-350J-194D01*
G37*
G36*
G01X1918547Y447249D02*
G02X1916039Y447364I-1225J681D01*
G03X1915340Y447424I-366J-162D01*
G02X1912905Y447602I-1167J776D01*
G03X1912206Y447647I-362J-170D01*
G02X1909798Y447718I-1183J753D01*
G03X1909099I-349J-194D01*
G02Y449082I-1225J682D01*
G03X1909798I350J194D01*
G02X1912291Y448998I1225J-682D01*
G03X1912990Y448953I362J170D01*
G02X1915456Y448766I1183J-753D01*
G03X1916155Y448706I366J162D01*
G02X1918547Y448611I1167J-776D01*
G03X1919247I350J194D01*
G02Y447249I1225J-681D01*
G03X1918547I-350J-194D01*
G37*
G54D45*
X388187Y50878D03*
Y31978D03*
G54D46*
X314368Y92657D03*
X311021Y84714D03*
X398029Y28007D03*
X408069D03*
X394682Y49592D03*
X431494Y28007D03*
X424801D03*
X451573Y65699D03*
G54D44*
X251213Y646784D03*
Y652784D03*
X261125Y646784D03*
Y652784D03*
X389473Y646508D03*
Y652508D03*
X379561Y646508D03*
Y652508D03*
X951795Y652234D03*
Y646234D03*
X941883D03*
Y652234D03*
X1196198Y652206D03*
Y646206D03*
X1206110D03*
Y652206D03*
X773419Y270414D03*
X753098Y338316D03*
X744698Y332816D03*
X757500Y374000D03*
X1919230Y483430D03*
X1919000Y487210D03*
G54D47*
X761580Y220160D03*
G54D51*
X1914911Y495775D03*
X1934597D03*
X1924754D03*
G54D49*
X1654678Y137530D03*
X1654685Y140687D03*
X1654686Y134389D03*
X1654685Y131239D03*
X1651536Y134388D03*
Y140687D03*
X1657835Y134389D03*
X1664134Y140688D03*
X1667284Y150136D03*
Y137537D03*
X1660986Y137538D03*
X1664186Y147038D03*
X1664135Y153286D03*
X1660985Y143837D03*
X1664136Y137538D03*
X1667284Y131239D03*
X1660985D03*
X1657836Y137538D03*
Y140688D03*
X1660985D03*
G54D48*
X1392264Y23976D03*
G54D43*
X1500Y295000D03*
X-1190Y53240D03*
X-1470Y63910D03*
X37000Y275000D03*
X321334Y32100D03*
X334292D03*
X327754Y35957D03*
X324407D03*
X311021D03*
X334447D03*
X354526D03*
X347833D03*
X344486D03*
X337793D03*
X317714D03*
X321192Y51000D03*
X334292D03*
X314368Y65814D03*
X321061Y54857D03*
X327754Y46914D03*
X324407Y54857D03*
Y46914D03*
X314368Y54857D03*
X311021Y46914D03*
X334446D03*
X331100Y54857D03*
X354526D03*
X354525Y46922D03*
X351179Y54857D03*
X347833Y46922D03*
X344486D03*
Y54857D03*
X337793Y46914D03*
X341140Y54857D03*
X334447D03*
X317714Y46914D03*
X348978Y220809D03*
Y209109D03*
X352357Y211060D03*
X342218Y220809D03*
X338838Y211058D03*
X355737Y209109D03*
Y220809D03*
X342218Y205210D03*
X345598Y207159D03*
X342218Y209109D03*
X348978Y205210D03*
Y216909D03*
X352357Y218860D03*
X345598D03*
X342218Y213009D03*
X338838Y214960D03*
X359117Y211060D03*
Y218860D03*
X355737Y216909D03*
Y213009D03*
X342218Y216909D03*
X338838Y207158D03*
Y203258D03*
X345598Y211060D03*
X348978Y213009D03*
X352357Y238360D03*
X345598D03*
X355737Y248109D03*
X338838Y230560D03*
X342218Y224709D03*
X345598Y230559D03*
X338838Y222760D03*
X352357D03*
X348978Y224709D03*
X355737D03*
X348978Y228610D03*
X352357Y230559D03*
X348978Y236409D03*
Y240309D03*
X352357Y234460D03*
X345598D03*
X342218Y228610D03*
Y236409D03*
X352357Y246160D03*
X359117Y230559D03*
X355737Y228610D03*
Y236409D03*
X352357Y242260D03*
X355737Y240309D03*
X345598Y222760D03*
X408184Y32100D03*
X404723Y28022D03*
X401377Y35957D03*
X414762Y28021D03*
X404723Y35957D03*
X414763D03*
X394684D03*
X411415Y36058D03*
X408184Y51000D03*
X394492Y54700D03*
X404723Y54857D03*
X401377Y46922D03*
X414763Y54857D03*
X398029Y54842D03*
X404723Y46922D03*
X414763D03*
X408069Y54842D03*
X411416Y46922D03*
X386292Y98800D03*
X362497Y209109D03*
Y220809D03*
X369257D03*
X382777D03*
Y209109D03*
X376017Y220809D03*
Y209109D03*
X389537D03*
Y220809D03*
X396296Y209109D03*
Y220809D03*
X407706Y209109D03*
Y220809D03*
X372637Y207159D03*
X399676D03*
X372637Y211060D03*
X392916D03*
X389537Y213009D03*
X396296D03*
X369257D03*
X396296Y216909D03*
X376017D03*
X365877Y218860D03*
X372637D03*
X362497Y216909D03*
X382777Y213009D03*
X399676Y218860D03*
X386157Y211060D03*
X407706Y216909D03*
X379397Y207159D03*
X369257Y216909D03*
X382777D03*
X379397Y218860D03*
X392916D03*
X362497Y213009D03*
X386157Y218860D03*
X389537Y216909D03*
X376017Y213009D03*
X399676Y211060D03*
X379397Y238360D03*
Y250060D03*
X386157Y238360D03*
X372637Y250060D03*
X389537Y248109D03*
X376017D03*
X382777D03*
X386157Y250060D03*
X359117Y238360D03*
X365877D03*
X372637D03*
X365877Y253960D03*
X362497Y255909D03*
X369257Y252009D03*
X392916Y250060D03*
Y238360D03*
X396296Y248109D03*
X399676Y250060D03*
X407706Y248109D03*
X396296Y244209D03*
Y240309D03*
X376017Y224709D03*
X372637Y222760D03*
X365877D03*
X369257Y224709D03*
X362497D03*
X386157Y222760D03*
X396296Y228610D03*
X389537Y224709D03*
X399676Y222760D03*
X382777Y224709D03*
X379397Y222760D03*
X359117D03*
X392916D03*
X396296Y224709D03*
X379397Y230559D03*
X365877Y242260D03*
X407706Y236409D03*
X372637Y234460D03*
X365877D03*
X372637Y230559D03*
X365877D03*
X369257Y236409D03*
X362497D03*
X369257Y228610D03*
X362497D03*
X382777D03*
X389537Y236409D03*
X399676Y230559D03*
Y234460D03*
X382777Y236409D03*
X392916Y230559D03*
X407706Y224709D03*
Y228610D03*
X376017Y236409D03*
X369257Y240309D03*
X376017D03*
X386157Y230559D03*
X372637Y242260D03*
X379397Y234460D03*
X399676Y238360D03*
X359117Y242260D03*
X362497Y240309D03*
X359117Y234460D03*
Y246160D03*
X386157Y234460D03*
X392916D03*
X389537Y228610D03*
X396296Y236409D03*
X376017Y228610D03*
X372637Y253960D03*
X376017Y252009D03*
X365877Y257860D03*
X369257Y255909D03*
X391787Y254259D03*
X388407Y256500D03*
X374887Y260300D03*
X385027Y254259D03*
X371507Y262300D03*
X381647Y256400D03*
X378267Y258400D03*
X395166Y256400D03*
X398546Y254259D03*
X405306Y254500D03*
X401926Y256500D03*
X399676Y242260D03*
X362497Y248109D03*
X359117Y250060D03*
X389537Y240309D03*
X382777D03*
X392916Y242260D03*
X386157D03*
X379397D03*
X389537Y244209D03*
X382777D03*
X376017D03*
X392916Y246160D03*
X386157D03*
X379397D03*
X372637D03*
X365877D03*
X369257Y248109D03*
X365877Y250060D03*
X362497Y252009D03*
X407706Y244209D03*
X399676Y246160D03*
X433508Y32100D03*
X448292Y31900D03*
X421368Y32100D03*
X438189Y35957D03*
X444880Y28022D03*
X444882Y35957D03*
X428149D03*
X421456Y28022D03*
X434842Y35957D03*
X438189Y28022D03*
X448492Y51000D03*
X421368D03*
X433508D03*
X448692Y89900D03*
X421455Y46921D03*
X438189Y46922D03*
X431494Y54842D03*
X444880Y54859D03*
Y46922D03*
X428149D03*
X421456Y54857D03*
X434842Y46922D03*
X424801Y54842D03*
X438187Y54859D03*
X345598Y343660D03*
X355737Y337809D03*
X348978D03*
X355737Y345609D03*
X348978Y341709D03*
X352357Y343660D03*
Y339760D03*
X359117Y343660D03*
X355737Y341709D03*
X352357Y359260D03*
X345598D03*
X348978Y349509D03*
X342218Y345609D03*
X355737Y349509D03*
Y376809D03*
Y388509D03*
X348978Y376809D03*
X342218D03*
X345598Y390460D03*
X352357Y386560D03*
X342218Y384609D03*
X345598Y386560D03*
X348978Y388509D03*
X342218Y380709D03*
X345598Y378760D03*
X348978Y380709D03*
X345598Y367060D03*
X348978Y372909D03*
X342218D03*
X352357Y378760D03*
Y374860D03*
X359117Y386560D03*
X355737Y380709D03*
X359117Y374860D03*
X355737Y372909D03*
X348978Y369010D03*
X352357Y367060D03*
X355737Y384609D03*
X345598Y355360D03*
X348978Y357309D03*
X345598Y351460D03*
X348978Y361209D03*
X345598Y363160D03*
X342218Y357309D03*
Y369010D03*
Y361209D03*
X352357Y351460D03*
Y363160D03*
X359117D03*
X355737Y361209D03*
Y369010D03*
X352357Y355360D03*
X355737Y357309D03*
X359117Y351460D03*
X348978Y345609D03*
X342218Y349509D03*
X345598Y347560D03*
X348978Y384609D03*
X345598Y374860D03*
X352357Y347560D03*
X359117Y339760D03*
X362497Y341709D03*
X365877Y343660D03*
X388407Y345160D03*
X362497Y337809D03*
X369257Y341709D03*
X365877Y339760D03*
X372637Y343660D03*
X374887Y337360D03*
X381647Y341260D03*
X378267Y339309D03*
X385027Y343209D03*
X395166Y345160D03*
X401926D03*
X362497Y345609D03*
X379397Y359260D03*
X382777Y349509D03*
X379397Y347560D03*
X369257Y345609D03*
X376017D03*
X386157Y351460D03*
X372637Y347560D03*
Y359260D03*
X365877D03*
X359117D03*
X376017Y376809D03*
X369257D03*
X382777Y388509D03*
X369257D03*
X362497D03*
X376017D03*
X389537D03*
Y376809D03*
X382777D03*
X362497D03*
X405306Y347109D03*
X396296Y388509D03*
Y376809D03*
X403056D03*
Y388509D03*
X372637Y390460D03*
X396296Y384609D03*
X372637Y386560D03*
X392916D03*
X389537Y384609D03*
X399676Y390460D03*
X376017Y372909D03*
X369257Y384609D03*
X396296Y380709D03*
X369257Y372909D03*
X362497D03*
X372637Y378760D03*
X362497Y380709D03*
X372637Y374860D03*
X365877D03*
X376017Y380709D03*
X365877Y378760D03*
X382777Y384609D03*
X386157Y374860D03*
X399676Y378760D03*
X396296Y369010D03*
X386157Y386560D03*
X389537Y372909D03*
X403056Y380709D03*
X399676Y374860D03*
X379397Y386560D03*
X369257Y380709D03*
X382777D03*
Y372909D03*
X379397Y378760D03*
Y374860D03*
X392916Y378760D03*
X362497Y384609D03*
X359117Y378760D03*
X386157D03*
X392916Y374860D03*
X389537Y380709D03*
X396296Y372909D03*
X376017Y384609D03*
X379397Y367060D03*
X365877Y355360D03*
X369257Y369010D03*
X362497D03*
X369257Y361209D03*
X362497D03*
X372637Y367060D03*
X365877D03*
X372637Y363160D03*
X365877D03*
X382777Y369010D03*
Y361209D03*
X392916Y367060D03*
X403056Y372909D03*
X376017Y361209D03*
X369257Y357309D03*
X376017D03*
X386157Y367060D03*
X372637Y355360D03*
X379397Y363160D03*
X359117Y355360D03*
X362497Y357309D03*
X359117Y367060D03*
X389537Y369010D03*
X376017D03*
X391787Y347109D03*
X398546D03*
X369257Y349509D03*
X365877Y351460D03*
X372637D03*
X379397D03*
X362497Y349509D03*
X376017D03*
X382777Y353409D03*
X386157Y355360D03*
X403056Y396309D03*
X399676Y386560D03*
X382777Y357309D03*
X379397Y355360D03*
X365877Y347560D03*
X359117D03*
X311798Y324160D03*
X315178Y322209D03*
X321938D03*
X305039Y328060D03*
X328698Y326110D03*
X325318Y324160D03*
X318558Y320260D03*
X301659Y318309D03*
X308418D03*
Y326110D03*
X338838Y316360D03*
X345598Y328060D03*
X342218Y322209D03*
Y318309D03*
Y326110D03*
X345598Y320260D03*
Y324160D03*
X318558Y328060D03*
Y324160D03*
X315178Y326110D03*
X325318Y328060D03*
X311798D03*
X321938Y326110D03*
X357987Y327609D03*
X348978Y322209D03*
Y318309D03*
Y326110D03*
X357057Y320260D03*
Y324160D03*
X361367Y329560D03*
X376785Y538305D03*
X481172Y278596D03*
X465100Y280300D03*
X481172Y282496D03*
X469913Y305896D03*
X477792Y307851D03*
X481172Y309797D03*
X469913Y286396D03*
X481172Y301996D03*
X477792Y303947D03*
Y288347D03*
X481172Y290296D03*
X477792Y315647D03*
Y319547D03*
Y327347D03*
X481172Y313696D03*
X469913Y321496D03*
X481172D03*
Y325396D03*
Y317596D03*
Y333196D03*
X463671Y319386D03*
X466734Y287074D03*
X463800Y289500D03*
X481172Y329296D03*
X466100Y300021D03*
X481172Y286396D03*
X477792Y311747D03*
X469913Y309797D03*
Y313696D03*
Y317596D03*
X477792Y331247D03*
X487932Y282496D03*
Y278596D03*
X484552Y276646D03*
X504832Y307847D03*
X494692Y294196D03*
X491312Y292245D03*
Y300047D03*
X494692Y309797D03*
X487932D03*
X498072Y303947D03*
X484552Y300047D03*
Y292245D03*
X494692Y286396D03*
X501452Y298096D03*
X487932Y317596D03*
X504832Y319547D03*
X484552Y323446D03*
X504832Y315647D03*
X498072Y319547D03*
X504832Y323446D03*
X498072Y327347D03*
X491312Y331247D03*
X487932Y313696D03*
X491312Y315647D03*
X484552Y319546D03*
Y331247D03*
X491312Y288347D03*
Y284447D03*
X498072Y288347D03*
X494692Y290296D03*
X498072Y292247D03*
X487932Y286396D03*
X484552Y284447D03*
X487932Y305896D03*
X491312Y303947D03*
X501452Y305896D03*
X494692Y298096D03*
X498072Y307847D03*
X484552Y303947D03*
X487932Y294196D03*
X491312Y296147D03*
X494692Y301996D03*
X487932D03*
X501452Y309797D03*
X487932Y298096D03*
X484552Y311747D03*
Y315647D03*
X491312Y323446D03*
X504832Y311747D03*
Y303947D03*
Y300045D03*
X501452Y325396D03*
X498072Y323446D03*
Y315647D03*
X501452Y317596D03*
Y321496D03*
X498072Y331247D03*
X501452Y329296D03*
Y313696D03*
X498072Y300047D03*
X504832Y296147D03*
X498072D03*
X501452Y294196D03*
X498072Y311747D03*
X501452Y301996D03*
X494692Y325396D03*
Y321496D03*
X491312Y319547D03*
X494692Y333196D03*
X487932D03*
X491312Y327347D03*
X494692Y329296D03*
X487932D03*
X494692Y313696D03*
X484552Y307847D03*
X491312D03*
Y311747D03*
X494692Y305896D03*
Y317596D03*
X487932Y321496D03*
X484552Y327347D03*
X487932Y325396D03*
X742937Y218574D03*
X771232Y214033D03*
X742897Y229573D03*
X760304Y235827D03*
X768560Y244055D03*
X769019Y276400D03*
X762616Y270113D03*
X761480Y242720D03*
X771650Y246451D03*
Y278451D03*
X759700Y232000D03*
X756114Y316209D03*
X762842Y302434D03*
X765730Y335064D03*
X771700Y342501D03*
X757956Y328095D03*
X758952Y384100D03*
X765007Y348363D03*
X847577Y381842D03*
X840871Y391380D03*
X837272Y391420D03*
X913787Y328060D03*
X937747Y318309D03*
Y326110D03*
X920847Y328060D03*
X930987Y326110D03*
X927607Y328060D03*
X934367Y324160D03*
X924227Y322209D03*
X927607Y320260D03*
X930987Y318309D03*
X934367Y316360D03*
X927607D03*
X924227Y326110D03*
X958026Y318309D03*
X951267D03*
X961406Y324160D03*
X974926D03*
X954647Y328060D03*
X971546Y322209D03*
X968166Y320260D03*
X964786Y322209D03*
X958026Y326110D03*
X944507Y322209D03*
Y318309D03*
X947887Y328060D03*
X941127D03*
X934367D03*
X968166D03*
Y324160D03*
X964786Y326110D03*
X974926Y328060D03*
X961406D03*
X971546Y326110D03*
X920500Y311960D03*
X924227Y310509D03*
X920500Y308560D03*
X924227Y314409D03*
X930987D03*
X927607Y312460D03*
X920847Y324160D03*
X924227Y318309D03*
X920547Y316160D03*
X917167Y318309D03*
Y322209D03*
X917467Y326110D03*
X920847Y320260D03*
X947887Y324160D03*
Y320260D03*
X941127D03*
X934367D03*
X937747Y322209D03*
X930987D03*
X941127Y324160D03*
X927607D03*
X944507Y326110D03*
X995206Y328060D03*
X991826Y326110D03*
X978306D03*
X995206Y324160D03*
X988446Y316360D03*
X991826Y318309D03*
X995206Y320260D03*
X991826Y322209D03*
X998586Y318309D03*
Y322209D03*
Y326110D03*
X1007595Y327609D03*
X1010975Y329560D03*
X1006665Y324160D03*
Y320260D03*
X998586Y220809D03*
X991826D03*
X1005345D03*
X1001965Y211060D03*
X1025625Y220809D03*
X1012105D03*
X1018865D03*
X1032385D03*
X1018865Y213009D03*
X998586Y216909D03*
X1001965Y218860D03*
X995206D03*
X991826Y213009D03*
X1025625Y216909D03*
X1015485Y218860D03*
X1022245D03*
X1012105Y216909D03*
X1018865D03*
X1029005Y218860D03*
X1008725Y211060D03*
X1012105Y213009D03*
X1008725Y218860D03*
X1005345Y216909D03*
Y213009D03*
X991826Y216909D03*
X995206Y211060D03*
X998586Y213009D03*
X995206Y238360D03*
X1029005D03*
X1008725D03*
X1001965D03*
X1035765D03*
Y250060D03*
X1029005D03*
X1032385Y248109D03*
X1025625D03*
X1015485Y238360D03*
X1022245D03*
X991826Y224709D03*
X995206Y230559D03*
X1025625Y224709D03*
X1022245Y222760D03*
X1015485D03*
X1018865Y224709D03*
X1012105D03*
X1035765Y222760D03*
X1001965D03*
X998586Y224709D03*
X1032385D03*
X1029005Y222760D03*
X1008725D03*
X1005345Y224709D03*
X998586Y228610D03*
X1001965Y230559D03*
X998586Y236409D03*
Y240309D03*
X1029005Y230559D03*
X1015485Y242260D03*
X1001965Y234460D03*
X995206D03*
X991826Y228610D03*
Y236409D03*
X1022245Y234460D03*
X1015485D03*
X1022245Y230559D03*
X1015485D03*
X1018865Y236409D03*
X1012105D03*
X1018865Y228610D03*
X1012105D03*
X1032385D03*
Y236409D03*
X1025625D03*
X1018865Y240309D03*
X1025625D03*
X1035765Y230559D03*
X1022245Y242260D03*
X1029005Y234460D03*
X1008725Y242260D03*
X1012105Y240309D03*
X1008725Y230559D03*
Y234460D03*
X1005345Y228610D03*
Y236409D03*
X1001965Y242260D03*
X1005345Y240309D03*
X1035765Y234460D03*
X1025625Y228610D03*
X1034635Y254259D03*
X995206Y222760D03*
X1032385Y240309D03*
X1035765Y242260D03*
X1029005D03*
X1032385Y244209D03*
X1025625D03*
X1035765Y246160D03*
X1029005D03*
X1022245D03*
X1057314Y248109D03*
X1039145D03*
X1042524Y250060D03*
X1049284D03*
X1045904Y248109D03*
X1042524Y238360D03*
X1045904Y244209D03*
Y240309D03*
Y228610D03*
X1039145Y224709D03*
X1057314Y236409D03*
X1039145D03*
X1049284Y230559D03*
Y234460D03*
X1042524Y230559D03*
X1049284Y238360D03*
X1042524Y234460D03*
X1039145Y228610D03*
X1045904Y236409D03*
X1038015Y256500D03*
X1041395Y254259D03*
X1048154D03*
X1051534Y256500D03*
X1044774Y256400D03*
X1054914Y254500D03*
X1049284Y242260D03*
X1039145Y240309D03*
X1042524Y242260D03*
X1039145Y244209D03*
X1042524Y246160D03*
X1057314Y244209D03*
X1049284Y246160D03*
X1015485Y343660D03*
X1012105Y341709D03*
X1021115Y335409D03*
X1018865Y341709D03*
X1015485Y339760D03*
X1024495Y337360D03*
X1027875Y339309D03*
X1034635Y343209D03*
X1031255Y341260D03*
X1022245Y343660D03*
X1008725D03*
X1012105Y345609D03*
X995206Y359260D03*
X998586Y376809D03*
X991826D03*
X1001965Y359260D03*
X1005345Y349509D03*
X1008725Y359260D03*
X1015485D03*
X1018865Y345609D03*
X1022245Y347560D03*
X1025625Y345609D03*
X1022245Y359260D03*
X1029005Y347560D03*
Y359260D03*
X1032385Y349509D03*
X1035765Y351460D03*
X1032385Y388509D03*
Y376809D03*
X1005345D03*
Y388509D03*
X1001965Y386560D03*
X1025625Y376809D03*
Y388509D03*
X1018865Y376809D03*
X1012105D03*
X1018865Y388509D03*
X1012105D03*
X991826Y384609D03*
X1022245Y390460D03*
X995206Y386560D03*
X1022245D03*
X998586Y388509D03*
X991826Y380709D03*
X995206Y378760D03*
X998586Y380709D03*
X1025625Y372909D03*
X1018865Y384609D03*
X995206Y367060D03*
X998586Y372909D03*
X991826D03*
X988446Y374860D03*
Y370959D03*
Y378760D03*
X1018865Y372909D03*
X1012105D03*
X1022245Y378760D03*
X1012105Y380709D03*
X1022245Y374860D03*
X1015485D03*
X1025625Y380709D03*
X1015485Y378760D03*
X1032385Y384609D03*
X1035765Y374860D03*
Y386560D03*
X1029005D03*
X1018865Y380709D03*
X1001965Y378760D03*
Y374860D03*
X1032385Y380709D03*
Y372909D03*
X1029005Y378760D03*
Y374860D03*
X1008725Y386560D03*
X1012105Y384609D03*
X1008725Y378760D03*
X1005345Y380709D03*
X1008725Y374860D03*
X1005345Y372909D03*
X998586Y369010D03*
X1001965Y367060D03*
X1005345Y384609D03*
X1035765Y378760D03*
X1025625Y384609D03*
X998586Y357309D03*
X1029005Y367060D03*
X1015485Y355360D03*
X998586Y361209D03*
X995206Y363160D03*
X991826Y369010D03*
Y361209D03*
X1018865Y369010D03*
X1012105D03*
X1018865Y361209D03*
X1012105D03*
X1022245Y367060D03*
X1015485D03*
X1022245Y363160D03*
X1015485D03*
X1032385Y369010D03*
Y361209D03*
X1025625D03*
X1018865Y357309D03*
X1001965Y351460D03*
Y363160D03*
X1025625Y357309D03*
X1035765Y367060D03*
X1022245Y355360D03*
X1029005Y363160D03*
X1008725Y355360D03*
X1012105Y357309D03*
X1008725Y363160D03*
Y367060D03*
X1005345Y361209D03*
Y369010D03*
X1001965Y355360D03*
X1005345Y357309D03*
X1008725Y351460D03*
X1035765Y363160D03*
X1025625Y369010D03*
X1018865Y349509D03*
X1032385Y353409D03*
X1035765Y355360D03*
X998586Y384609D03*
X995206Y374860D03*
X1032385Y357309D03*
X1029005Y355360D03*
X1015485Y351460D03*
X1022245D03*
X1029005D03*
X1012105Y349509D03*
X1025625D03*
X1015485Y347560D03*
X1008725D03*
X1038015Y345160D03*
X1044774D03*
X1051534D03*
X1039145Y388509D03*
X1045904D03*
X1052664D03*
X1039145Y376809D03*
X1045904D03*
X1052664D03*
X1045904Y384609D03*
X1042524Y386560D03*
X1039145Y384609D03*
X1049284Y390460D03*
X1045904Y380709D03*
X1049284Y378760D03*
X1045904Y369010D03*
X1039145Y372909D03*
X1052664Y380709D03*
X1049284Y374860D03*
X1042524Y378760D03*
Y374860D03*
X1039145Y380709D03*
X1045904Y372909D03*
X1042524Y367060D03*
X1052664Y372909D03*
X1039145Y369010D03*
X1041395Y347109D03*
X1049284Y386560D03*
X1388627Y35032D03*
X1379025Y-9799D03*
X1397500Y51000D03*
X1389138Y58499D03*
X1389100Y74600D03*
X1364856Y366666D03*
X1371200Y402100D03*
X1375201Y396303D03*
X1392500Y592000D03*
X1463419Y606912D03*
X1470353Y592128D03*
X1461500Y540000D03*
X1526525Y467206D03*
X1522625D03*
X1518725D03*
X1522625Y460446D03*
X1526525D03*
X1518725D03*
X1501175Y436786D03*
Y428214D03*
X1516775Y463826D03*
X1524575D03*
X1514825Y467206D03*
X1520675Y463826D03*
X1501490Y504988D03*
X1501934Y513047D03*
X1516775Y470586D03*
X1510925Y473966D03*
X1508975Y470586D03*
Y477346D03*
X1520675Y470586D03*
X1503400Y524663D03*
X1524575Y470586D03*
X1512875D03*
X1499225Y487486D03*
X1507025Y473966D03*
X1501175Y484106D03*
X1505075D03*
X1503125Y480726D03*
X1505075Y477346D03*
X1507025Y480726D03*
X1518000Y562330D03*
X1510740Y557860D03*
X1478700Y533700D03*
X1549925Y446926D03*
Y440166D03*
X1551875Y443546D03*
X1503125Y467206D03*
X1493375Y463826D03*
X1501175D03*
X1497275Y457066D03*
X1501175D03*
X1503125Y460446D03*
Y453786D03*
X1507025Y460446D03*
X1510925D03*
X1499225D03*
X1495325D03*
X1497275Y463826D03*
X1505075D03*
X1518675Y451425D03*
X1505075Y457066D03*
X1501200Y450600D03*
X1499225Y453686D03*
Y467206D03*
X1491425D03*
X1495325D03*
X1489475Y484106D03*
X1487525Y487486D03*
X1491425Y473966D03*
X1501175Y470586D03*
X1476800Y498900D03*
X1497275Y470586D03*
Y477346D03*
X1489475D03*
X1499225Y473966D03*
X1493375Y470586D03*
X1495325Y473966D03*
X1493375Y477346D03*
X1491425Y480726D03*
X1493375Y484106D03*
X1495325Y480726D03*
X1547975Y457066D03*
X1551875Y463826D03*
X1553825Y467206D03*
X1540175Y457066D03*
X1544075D03*
X1534325Y460446D03*
X1547975Y463826D03*
X1551875Y457066D03*
X1542125Y460446D03*
X1538225D03*
X1549925Y467206D03*
X1536300Y455200D03*
X1549925Y460446D03*
X1546025D03*
X1569425Y473966D03*
X1565525Y480726D03*
X1555775Y484106D03*
Y477346D03*
X1557725Y473966D03*
X1555775Y470586D03*
X1553825Y473966D03*
X1547975Y470586D03*
X1549925Y473966D03*
X1557725Y480726D03*
X1553825D03*
X1551875Y470586D03*
X1549925Y480726D03*
X1551875Y477346D03*
X1547975D03*
X1559675Y484106D03*
X1561625Y480726D03*
X1567475Y484106D03*
X1563575D03*
X1559675Y477346D03*
X1563575D03*
X1571375D03*
X1561625Y473966D03*
X1565525D03*
X1567475Y477346D03*
X1664135Y131239D03*
X1657835D03*
X1852340Y509140D03*
X1859530Y516430D03*
X1842400Y516800D03*
X1864339Y509560D03*
X1869914Y517225D03*
X1866688Y517128D03*
X1900890Y477200D03*
X1938410Y490650D03*
X1905010Y479410D03*
X1915100Y480050D03*
X1929480Y472880D03*
X1919510Y475100D03*
Y479200D03*
X1928620Y482710D03*
G54D41*
X40500Y-42250D03*
Y-52250D03*
X60500Y-42250D03*
X80500D03*
X60500Y-52250D03*
X80500D03*
X467246Y-52301D03*
Y-42301D03*
X487246Y-52301D03*
Y-42301D03*
X507246Y-52301D03*
Y-42301D03*
X798984Y-52057D03*
Y-42057D03*
X818984Y-52057D03*
Y-42057D03*
X838984Y-52057D03*
Y-42057D03*
X1135583Y-52285D03*
Y-42285D03*
X1155583Y-52285D03*
Y-42285D03*
X1392258Y-52257D03*
Y-42257D03*
G54D50*
X1894689Y518328D03*
G54D42*
X-7874Y216181D03*
Y325315D03*
G54D40*
X-3937Y-43307D03*
X1956693D03*
X-3937Y646063D03*
X1956693D03*
%LPD*%
G75*
G36*
G01X372212Y36387D02*
X371290Y37309D01*
Y45512D01*
X371434Y45554D01*
G03Y48246I-392J1346D01*
G01X371290Y48288D01*
Y86980D01*
X372024Y87714D01*
X381506D01*
X386384Y82836D01*
Y75346D01*
G03X384586Y72228I1803J-3117D01*
G01Y67328D01*
G03X386384Y64210I3601J-1D01*
G01Y61550D01*
X382610Y57776D01*
Y37850D01*
X381147Y36387D01*
X372212D01*
G37*
%LPC*%
G75*
G36*
G01X375007Y75306D02*
G02X373577I-715J-1206D01*
G03Y75994I-204J344D01*
G02X375007I715J1206D01*
G03Y75306I204J-344D01*
G37*
G54D43*
X380792Y56500D03*
%LPD*%
G75*
G36*
G01X1903400Y122500D02*
Y135250D01*
X1913800D01*
Y122500D01*
X1903400D01*
G37*
G54D10*
X-17936Y-49379D03*
Y-53779D03*
Y-44979D03*
Y-40579D03*
X-18079Y-35764D03*
Y-58764D03*
X-14186Y196989D03*
Y199989D03*
X-17179Y643156D03*
X-17194Y638753D03*
X-17179Y647556D03*
Y660756D03*
Y651956D03*
Y656356D03*
X-13636Y-40479D03*
Y-44879D03*
Y-53679D03*
X-9079Y-50164D03*
X-4679D03*
X-279D03*
X-9079Y-54264D03*
X-4679D03*
X-279D03*
X22964Y-40379D03*
Y-44779D03*
Y-53579D03*
Y-49179D03*
X18964Y-53579D03*
Y-49179D03*
X13964Y-53579D03*
Y-49179D03*
X8964Y-40379D03*
Y-44779D03*
Y-53579D03*
Y-49179D03*
X3964Y-40379D03*
Y-44779D03*
Y-53579D03*
Y-49179D03*
X25921Y-35764D03*
X30321D03*
X43521D03*
X39121D03*
X34721D03*
X8321D03*
X12721D03*
X21521D03*
X17121D03*
X-13679D03*
X-9279D03*
X3921D03*
X-4879D03*
X-479D03*
X17121Y-58764D03*
X21521D03*
X12721D03*
X8321D03*
X34721D03*
X39121D03*
X43521D03*
X30321D03*
X25921D03*
X-479D03*
X-13679D03*
X-4879D03*
X3921D03*
X-13636Y-49279D03*
X-9279Y-58764D03*
X875Y211336D03*
X6074Y211293D03*
X3474Y211263D03*
X875Y208352D03*
X36200Y208600D03*
X33200D03*
X20700D03*
X17700Y211600D03*
X20700D03*
X17700Y208600D03*
X23700Y211600D03*
Y208600D03*
X33200Y211600D03*
X30200D03*
Y208600D03*
X36200Y211600D03*
X6074Y208321D03*
X3474Y208263D03*
X5500Y218500D03*
X-5300Y200191D03*
X-7900D03*
X-2700Y200202D03*
X-11586Y196989D03*
Y199989D03*
X-2600Y232300D03*
X-5246Y232351D03*
X-7846D03*
X20500Y221000D03*
Y224000D03*
X17500Y221000D03*
Y224000D03*
X23500D03*
Y221000D03*
X33300Y224000D03*
Y221000D03*
X30300D03*
Y224000D03*
X36300D03*
Y221000D03*
X-14129Y235221D03*
X-11484Y235215D03*
Y232215D03*
X-14084D03*
X2678Y221018D03*
X5277Y221110D03*
X5173Y224042D03*
X2574Y223963D03*
X-26Y223982D03*
X19800Y257900D03*
X22421Y647556D03*
X26821D03*
X31221D03*
X18021D03*
Y643156D03*
X31221D03*
X26821D03*
X22421D03*
X18006Y638753D03*
X9221Y647556D03*
X13621D03*
Y643156D03*
X9221D03*
X4821D03*
Y647556D03*
X22406Y638753D03*
X26806D03*
X31206D03*
X-12794D03*
X-12779Y647556D03*
Y643156D03*
X40006Y638753D03*
X44406D03*
X35606D03*
X35621Y647556D03*
Y643156D03*
X18021Y660756D03*
X35621Y656356D03*
X26821Y660756D03*
X18021Y651956D03*
X31221D03*
X22421Y660756D03*
X26821Y651956D03*
X22421D03*
X4821D03*
X13621D03*
X9221D03*
X-8379Y660756D03*
X4821Y656356D03*
X9221D03*
X13621D03*
X-3979D03*
X421D03*
X13621Y660756D03*
X-3979D03*
X421D03*
X4821D03*
X-12779Y651956D03*
X22421Y656356D03*
X26821D03*
X31221D03*
X18021D03*
X-8379D03*
X-12779D03*
X31221Y660756D03*
X35621Y651956D03*
Y660756D03*
X44421D03*
X40021D03*
X-12779D03*
X9221D03*
X107921Y-58764D03*
X102921D03*
X97921D03*
X92921D03*
X87921D03*
X82921D03*
X77921D03*
X72921D03*
X67921D03*
X62921D03*
X57921D03*
X52921D03*
X47921Y-35764D03*
Y-58764D03*
X107921Y-35764D03*
X102921D03*
X97921D03*
X92921D03*
X87921D03*
X82921D03*
X77921D03*
X72921D03*
X67921D03*
X62921D03*
X57921D03*
X52921D03*
X58200Y230400D03*
Y233400D03*
X55600Y230400D03*
X53000Y230300D03*
Y233300D03*
X55600Y233400D03*
X58200Y227400D03*
X53000Y227300D03*
X55600Y227400D03*
X58200Y239400D03*
X53000Y239300D03*
X55600Y239400D03*
X58200Y236400D03*
X55600D03*
X53000Y236300D03*
X71500Y263300D03*
X68800D03*
X53004Y244632D03*
X55275Y245900D03*
X57875D03*
X57457Y248537D03*
Y251237D03*
X57444Y257456D03*
X57600Y262800D03*
X57500Y260200D03*
X62800Y265500D03*
X71500Y266000D03*
X65500Y265500D03*
X68800Y266000D03*
X60000Y265500D03*
X48806Y638753D03*
X75206D03*
X106006D03*
X70806D03*
X53206D03*
X66406D03*
X92806D03*
X97206D03*
X101606D03*
X57606D03*
X62006D03*
X79606D03*
X84006D03*
X88406D03*
X53221Y660756D03*
X101621D03*
X97221D03*
X92821D03*
X106021D03*
X48821D03*
X70821D03*
X66421D03*
X62021D03*
X57621D03*
X75221D03*
X88421D03*
X84021D03*
X79621D03*
X167921Y-58764D03*
X162921D03*
X157921D03*
X152921D03*
X147921D03*
X142921D03*
X137921D03*
X132921D03*
X127921D03*
X122921D03*
X117921D03*
X112921D03*
X162921Y-35764D03*
X157921D03*
X152921D03*
X147921D03*
X142921D03*
X137921D03*
X132921D03*
X127921D03*
X122921D03*
X117921D03*
X112921D03*
X167921D03*
X166000Y212900D03*
X168600D03*
X164300Y207870D03*
X160800Y212900D03*
X163400D03*
X157800Y207300D03*
X161216Y209533D03*
Y206933D03*
X154500Y205500D03*
X150600Y212900D03*
X151000Y205500D03*
X140889Y211972D03*
X137615Y212039D03*
X143900Y204600D03*
X147500Y205500D03*
X140200Y204400D03*
X153200Y212900D03*
X139815Y268974D03*
X137900Y272800D03*
X139800Y237000D03*
X165825Y239543D03*
X168425Y236943D03*
Y239543D03*
X165825Y236943D03*
X163225D03*
X152825D03*
X145025D03*
X147625D03*
X150225D03*
X142425D03*
X163225Y239543D03*
X158025Y236943D03*
X155425D03*
X160625D03*
X142371Y244384D03*
X142466Y268982D03*
X142700Y276200D03*
X136729Y276386D03*
X139683Y276174D03*
X163225Y242143D03*
X168425Y244743D03*
X165825D03*
X163225D03*
X168425Y242143D03*
X165825D03*
X150700Y276800D03*
X169150Y259470D03*
Y255470D03*
X157633Y268727D03*
X162833D03*
X160233D03*
X165433D03*
X168033Y271327D03*
X162833Y276527D03*
Y273927D03*
Y271327D03*
X165433Y276527D03*
Y273927D03*
Y271327D03*
X159983Y276507D03*
X168033Y276527D03*
Y273927D03*
Y268727D03*
X153300Y276800D03*
X139866Y333016D03*
X160233Y306257D03*
Y308857D03*
Y303657D03*
X157518Y335391D03*
X157745Y332800D03*
X139900Y302400D03*
X142433Y301057D03*
X147633D03*
X150233D03*
X145033D03*
X145200Y341300D03*
X148200D03*
X142465Y332940D03*
X152833Y301057D03*
X163233Y306257D03*
Y308857D03*
X168433Y306257D03*
Y308857D03*
Y301057D03*
X165833D03*
X163233D03*
X160633D03*
X158033D03*
X155433D03*
X169150Y287600D03*
Y291600D03*
X165833Y306257D03*
X163233Y303657D03*
X168433D03*
X165833D03*
Y308857D03*
X151000Y341300D03*
X169150Y323600D03*
Y319600D03*
X160501Y332965D03*
X160274Y335556D03*
X165701Y338165D03*
Y335565D03*
X163101Y332965D03*
X168301D03*
X165701D03*
X163101Y335565D03*
X168301Y340765D03*
Y338165D03*
Y335565D03*
X163101Y338165D03*
Y340765D03*
X165701D03*
X154200Y341100D03*
X139767Y364883D03*
X147833Y364457D03*
X142421Y364908D03*
X145033Y364457D03*
X142863Y402829D03*
X140219Y402894D03*
X137619Y402900D03*
X134992D03*
X142818Y400163D03*
X143073Y397194D03*
X140475Y397310D03*
X140218Y400163D03*
X137529Y400296D03*
X134929D03*
X150633Y364457D03*
X167433Y369657D03*
X169150Y355600D03*
Y351600D03*
X167700Y363900D03*
X161833Y364457D03*
X164633D03*
X159033D03*
X156233D03*
X153433D03*
X164633Y369657D03*
X161833D03*
X161933Y372357D03*
X164733D03*
X167533D03*
X166340Y374785D03*
X167670Y383993D03*
Y387993D03*
X110406Y638753D03*
X145606D03*
X141206D03*
X136806D03*
X132406D03*
X158806D03*
X119206D03*
X123606D03*
X114806D03*
X128006D03*
X163206D03*
X154406D03*
X167606D03*
X150006D03*
X132421Y660756D03*
X145621D03*
X141221D03*
X136821D03*
X123621D03*
X114821D03*
X128021D03*
X110421D03*
X119221D03*
X150021D03*
X167621D03*
X163221D03*
X158821D03*
X154421D03*
X182921Y-58764D03*
X177921D03*
X172921D03*
X227921Y-35764D03*
X222921D03*
X217921D03*
X212921D03*
X207921D03*
X202921D03*
X197921D03*
X192921D03*
X187921D03*
X182921D03*
X177921D03*
X227921Y-58764D03*
X222921D03*
X217921D03*
X212921D03*
X207921D03*
X202921D03*
X197921D03*
X192921D03*
X187921D03*
X172921Y-35764D03*
X174750Y389308D03*
X211606Y638753D03*
X224806D03*
X220406D03*
X216006D03*
X189606D03*
X198406D03*
X202806D03*
X207206D03*
X176406D03*
X172006D03*
X185206D03*
X180806D03*
X194006D03*
X226500Y649900D03*
X229206Y638753D03*
X224821Y660756D03*
X220421D03*
X198421D03*
X211621D03*
X189621D03*
X202821D03*
X207221D03*
X194021D03*
X185221D03*
X172021D03*
X176421D03*
X180821D03*
X229221D03*
X216021D03*
X292921Y-35764D03*
X287921D03*
X282921D03*
X277921D03*
X272921D03*
X267921D03*
X262921D03*
X257921D03*
X252921D03*
X247921D03*
X242921D03*
X237921D03*
X232921D03*
X292921Y-58764D03*
X287921D03*
X282921D03*
X277921D03*
X272921D03*
X267921D03*
X262921D03*
X257921D03*
X252921D03*
X247921D03*
X242921D03*
X237921D03*
X232921D03*
X290806Y638753D03*
X268806D03*
X273206D03*
X277606D03*
X282006D03*
X260006D03*
X264406D03*
X255606D03*
X251206D03*
X286406D03*
X242406D03*
X246806D03*
X233606D03*
X238006D03*
X286421Y660756D03*
X268821D03*
X282021D03*
X273221D03*
X277621D03*
X264421D03*
X251221D03*
X255621D03*
X260021D03*
X246821D03*
X242421D03*
X238021D03*
X233621D03*
X290821D03*
X352921Y-58764D03*
Y-35764D03*
X347921Y-58764D03*
Y-35764D03*
X342921Y-58764D03*
Y-35764D03*
X337921Y-58764D03*
Y-35764D03*
X332921Y-58764D03*
Y-35764D03*
X327921Y-58764D03*
Y-35764D03*
X322921Y-58764D03*
Y-35764D03*
X317921Y-58764D03*
Y-35764D03*
X312921Y-58764D03*
X307921D03*
Y-35764D03*
X302921Y-58764D03*
Y-35764D03*
X297921D03*
Y-58764D03*
X312921Y-35764D03*
X330406Y638753D03*
X348006D03*
X326006D03*
X312806D03*
X317206D03*
X321606D03*
X352406D03*
X295206D03*
X299606D03*
X308406D03*
X304006D03*
X334806D03*
X339206D03*
X343606D03*
X312821Y660756D03*
X317221D03*
X308421D03*
X304021D03*
X352421D03*
X295221D03*
X326021D03*
X321621D03*
X339221D03*
X299621D03*
X334821D03*
X330421D03*
X343621D03*
X348021D03*
X392921Y-35764D03*
X387921Y-58764D03*
Y-35764D03*
X382921Y-58764D03*
Y-35764D03*
X377921Y-58764D03*
Y-35764D03*
X372921Y-58764D03*
Y-35764D03*
X367921Y-58764D03*
Y-35764D03*
X362921Y-58764D03*
Y-35764D03*
X357921Y-58764D03*
Y-35764D03*
X392921Y-58764D03*
X402921Y-35764D03*
X397921Y-58764D03*
Y-35764D03*
X412921Y-58764D03*
Y-35764D03*
X407921Y-58764D03*
Y-35764D03*
X402921Y-58764D03*
X404594Y264899D03*
X407594D03*
X411188D03*
X414188D03*
X417190D03*
X366822Y324459D03*
X377894Y326777D03*
X378785Y329580D03*
X375223Y326798D03*
X369748Y326902D03*
X367121Y327057D03*
X372391Y326746D03*
X375848Y329512D03*
X383206Y638753D03*
X387606D03*
X392006D03*
X396406D03*
X400806D03*
X405206D03*
X409606D03*
X414006D03*
X370006D03*
X365606D03*
X374406D03*
X378806D03*
X356806D03*
X361206D03*
X374421Y660756D03*
X387621D03*
X383221D03*
X400821D03*
X396421D03*
X392021D03*
X405221D03*
X409621D03*
X414021D03*
X361221D03*
X365621D03*
X356821D03*
X370021D03*
X378821D03*
X477921Y-58764D03*
Y-35764D03*
X472921Y-58764D03*
Y-35764D03*
X467921Y-58764D03*
Y-35764D03*
X462921Y-58764D03*
Y-35764D03*
X457921Y-58764D03*
Y-35764D03*
X452921Y-58764D03*
Y-35764D03*
X447921Y-58764D03*
Y-35764D03*
X442921Y-58764D03*
Y-35764D03*
X437921Y-58764D03*
Y-35764D03*
X432921Y-58764D03*
X422921Y-35764D03*
X417921Y-58764D03*
Y-35764D03*
X432921D03*
X427921Y-58764D03*
Y-35764D03*
X422921Y-58764D03*
X425911Y264710D03*
X420188Y264899D03*
X423092Y264697D03*
X448593Y646514D03*
X466806Y638753D03*
X462406D03*
X475606D03*
X471206D03*
X418406D03*
X422806D03*
X427206D03*
X440406D03*
X436006D03*
X431606D03*
X449206D03*
X458006D03*
X453606D03*
X444806D03*
X448593Y652514D03*
X458021Y660756D03*
X449221D03*
X462421D03*
X466821D03*
X471221D03*
X418421D03*
X475621D03*
X453621D03*
X422821D03*
X427221D03*
X440421D03*
X431621D03*
X436021D03*
X444821D03*
X537921Y-58764D03*
Y-35764D03*
X532921Y-58764D03*
Y-35764D03*
X527921Y-58764D03*
Y-35764D03*
X522921Y-58764D03*
Y-35764D03*
X517921Y-58764D03*
Y-35764D03*
X512921Y-58764D03*
Y-35764D03*
X507921Y-58764D03*
Y-35764D03*
X502921Y-58764D03*
Y-35764D03*
X497921Y-58764D03*
Y-35764D03*
X492921Y-58764D03*
Y-35764D03*
X487921Y-58764D03*
Y-35764D03*
X482921Y-58764D03*
Y-35764D03*
X480006Y638753D03*
X484406D03*
X488806D03*
X493206D03*
X497606D03*
X510806D03*
X537206D03*
X519606D03*
X524006D03*
X532806D03*
X528406D03*
X515206D03*
X502006D03*
X506406D03*
X524021Y660756D03*
X480021D03*
X484421D03*
X497621D03*
X493221D03*
X488821D03*
X519621D03*
X532821D03*
X537221D03*
X528421D03*
X515221D03*
X510821D03*
X506421D03*
X502021D03*
X597921Y-35764D03*
Y-58764D03*
X592921Y-35764D03*
Y-58764D03*
X587921Y-35764D03*
Y-58764D03*
X582921Y-35764D03*
Y-58764D03*
X577921Y-35764D03*
Y-58764D03*
X572921Y-35764D03*
Y-58764D03*
X567921Y-35764D03*
Y-58764D03*
X562921Y-35764D03*
Y-58764D03*
X557921Y-35764D03*
Y-58764D03*
X552921Y-35764D03*
Y-58764D03*
X547921D03*
Y-35764D03*
X542921Y-58764D03*
Y-35764D03*
X567029Y646238D03*
X590006Y638753D03*
X572406D03*
X559206D03*
X568006D03*
X563606D03*
X550406D03*
X581206D03*
X585606D03*
X576806D03*
X598806D03*
X594406D03*
X601500Y649500D03*
X554806Y638753D03*
X541606D03*
X546006D03*
X567029Y652238D03*
X559221Y660756D03*
X546021D03*
X554821D03*
X598821D03*
X572421D03*
X568021D03*
X563621D03*
X585621D03*
X541621D03*
X594421D03*
X576821D03*
X590021D03*
X581221D03*
X550421D03*
X637921Y-58764D03*
X632921Y-35764D03*
Y-58764D03*
X627921Y-35764D03*
Y-58764D03*
X622921Y-35764D03*
Y-58764D03*
X617921Y-35764D03*
Y-58764D03*
X612921Y-35764D03*
Y-58764D03*
X607921Y-35764D03*
Y-58764D03*
X602921Y-35764D03*
Y-58764D03*
X652921Y-35764D03*
Y-58764D03*
X647921Y-35764D03*
Y-58764D03*
X642921Y-35764D03*
Y-58764D03*
X637921Y-35764D03*
X662921D03*
Y-58764D03*
X657921Y-35764D03*
Y-58764D03*
X641541Y243828D03*
X628589Y463649D03*
X629359Y469583D03*
X632771Y473269D03*
X605176Y487581D03*
X641107Y471989D03*
X634033Y467638D03*
X638406Y638753D03*
X634006D03*
X642806D03*
X629606D03*
X616406D03*
X612006D03*
X603206D03*
X625206D03*
X651606D03*
X647206D03*
X660406D03*
X620806D03*
X656006D03*
X607606D03*
X607621Y660756D03*
X638421D03*
X647221D03*
X616421D03*
X634021D03*
X612021D03*
X620821D03*
X625221D03*
X629621D03*
X642821D03*
X603221D03*
X656021D03*
X660421D03*
X651621D03*
X692921Y-58764D03*
X687921Y-35764D03*
Y-58764D03*
X682921Y-35764D03*
Y-58764D03*
X677921Y-35764D03*
Y-58764D03*
X672921Y-35764D03*
Y-58764D03*
X667921Y-35764D03*
Y-58764D03*
X697921Y-35764D03*
Y-58764D03*
X692921Y-35764D03*
X722921D03*
Y-58764D03*
X717921Y-35764D03*
Y-58764D03*
X712921Y-35764D03*
Y-58764D03*
X707921Y-35764D03*
Y-58764D03*
X702921Y-35764D03*
Y-58764D03*
X695606Y638753D03*
X673606D03*
X708806D03*
X704406D03*
X700006D03*
X722006D03*
X717606D03*
X713206D03*
X664806D03*
X669206D03*
X686806D03*
X682406D03*
X678006D03*
X691206D03*
X664821Y660756D03*
X695621D03*
X708821D03*
X700021D03*
X704421D03*
X669221D03*
X686821D03*
X691221D03*
X678021D03*
X673621D03*
X682421D03*
X722021D03*
X717621D03*
X713221D03*
X777921Y-58764D03*
X772921Y-35764D03*
Y-58764D03*
X767921Y-35764D03*
Y-58764D03*
X762921Y-35764D03*
Y-58764D03*
X757921Y-35764D03*
Y-58764D03*
X752921Y-35764D03*
Y-58764D03*
X787921Y-35764D03*
Y-58764D03*
X782921Y-35764D03*
Y-58764D03*
X777921Y-35764D03*
X747921D03*
Y-58764D03*
X742921Y-35764D03*
Y-58764D03*
X737921Y-35764D03*
Y-58764D03*
X732921Y-35764D03*
Y-58764D03*
X727921Y-35764D03*
Y-58764D03*
X786674Y211463D03*
X786300Y207400D03*
X787200Y244200D03*
Y271900D03*
X787100Y241100D03*
X770632Y234833D03*
X770965Y237519D03*
X773800Y237700D03*
X768382Y237861D03*
X769637Y266647D03*
X770485Y269489D03*
X772630Y266810D03*
X787200Y276400D03*
X787100Y303900D03*
X775200Y301200D03*
X770900Y301800D03*
X768290Y301780D03*
X747498Y335516D03*
X750298Y338316D03*
Y335516D03*
X744698Y338316D03*
Y335516D03*
X747498Y338316D03*
X769440Y298735D03*
X772400Y299400D03*
X787000Y308300D03*
X771730Y330665D03*
X775732Y332989D03*
X770278Y333272D03*
X772949Y333009D03*
X787400Y340400D03*
X747000Y386000D03*
X743500D03*
X750500D03*
X754000D03*
X750298Y344833D03*
X744698Y347833D03*
X747498D03*
X750298D03*
X747673Y364009D03*
X745073D03*
X750273D03*
X747573Y366909D03*
X744973D03*
X750173D03*
X744698Y344833D03*
X747498D03*
X747000Y380000D03*
X743500D03*
X753874Y379863D03*
X750500Y380000D03*
Y374000D03*
X754000D03*
X747000D03*
X743500D03*
X769380Y366440D03*
X775070Y365070D03*
X772290Y365020D03*
X769440Y363810D03*
X785400Y372400D03*
X775420Y397110D03*
X772742Y397209D03*
X766860Y396240D03*
X769770Y396070D03*
X770406Y638753D03*
X779206D03*
X774806D03*
X730806D03*
X726406D03*
X739606D03*
X735206D03*
X748406D03*
X744006D03*
X766006D03*
X761606D03*
X757206D03*
X752806D03*
X783606D03*
X744021Y660756D03*
X735221D03*
X779221D03*
X770421D03*
X774821D03*
X726421D03*
X730821D03*
X739621D03*
X748421D03*
X783621D03*
X757221D03*
X761621D03*
X752821D03*
X766021D03*
X842921Y-35764D03*
X837921Y-58764D03*
Y-35764D03*
X832921Y-58764D03*
X847921D03*
Y-35764D03*
X842921Y-58764D03*
X832921Y-35764D03*
X827921Y-58764D03*
Y-35764D03*
X822921Y-58764D03*
Y-35764D03*
X817921Y-58764D03*
Y-35764D03*
X812921Y-58764D03*
Y-35764D03*
X807921Y-58764D03*
Y-35764D03*
X802921Y-58764D03*
Y-35764D03*
X797921D03*
Y-58764D03*
X792921Y-35764D03*
Y-58764D03*
X816900Y216300D03*
X816874Y212863D03*
X814274D03*
X811674D03*
X808818Y211179D03*
X808618Y208579D03*
X803200Y213100D03*
X800600D03*
X794474Y211463D03*
X791874D03*
X789274D03*
X814849Y205001D03*
X792514Y201290D03*
X797717Y201907D03*
X803134Y202969D03*
X808165Y203529D03*
X818960Y202230D03*
X789432Y236947D03*
X789400Y273700D03*
X811983Y244843D03*
Y242243D03*
X814583Y239643D03*
X815432Y237000D03*
X814583Y244843D03*
Y242243D03*
X812832Y237000D03*
X811983Y239643D03*
X802432Y237000D03*
X799832D03*
X792032D03*
X794632D03*
X810232D03*
X797232D03*
X805032D03*
X807632D03*
X791000Y244400D03*
X793600D03*
X816800Y234300D03*
X816900Y230900D03*
X817000Y252500D03*
X789800Y276400D03*
X792400D03*
X801991Y276557D03*
X804591D03*
X792191Y269101D03*
X789591D03*
X814891Y271657D03*
Y274257D03*
Y276857D03*
Y269057D03*
X812291D03*
Y274257D03*
Y276857D03*
Y271657D03*
X817000Y255100D03*
Y257700D03*
X817491Y276857D03*
Y274257D03*
Y271657D03*
Y269057D03*
X817183Y242243D03*
Y239643D03*
Y244843D03*
X818032Y237000D03*
X788600Y306100D03*
X789500Y301200D03*
X797300D03*
X799900D03*
X810300D03*
X802500D03*
X812900D03*
X807700D03*
X805100D03*
X815500D03*
X811991Y308957D03*
Y306357D03*
Y303757D03*
X814591Y306357D03*
Y308957D03*
Y303757D03*
X792900Y308400D03*
X789900D03*
X794700Y301200D03*
X792100D03*
X793000Y340400D03*
X790300Y340300D03*
X816991Y337357D03*
Y334757D03*
Y339957D03*
X814391D03*
Y337357D03*
Y334757D03*
X811791Y337357D03*
Y339957D03*
Y334757D03*
X791879Y332798D03*
X794600Y332600D03*
X816938Y319888D03*
Y323888D03*
X817100Y317000D03*
X818100Y301200D03*
X817191Y303757D03*
Y306357D03*
Y308957D03*
X789860Y364947D03*
X820218Y385950D03*
Y382950D03*
X826097Y385923D03*
X816591Y369857D03*
Y372457D03*
X811391Y369857D03*
X813991D03*
Y372457D03*
X811391D03*
X790900Y372300D03*
X788300Y372400D03*
X802759Y364575D03*
X816672Y358809D03*
X795310Y364721D03*
X816593Y356210D03*
X807959Y364575D03*
X805359D03*
X810559D03*
X815759D03*
X813159D03*
X816900Y361400D03*
X792610Y364821D03*
X816591Y375057D03*
X792238Y396753D03*
X789600Y396809D03*
X811515Y397289D03*
X808915D03*
X813648Y395557D03*
X815472Y390442D03*
X814877Y393138D03*
X792000Y399409D03*
X789400D03*
X821658Y369463D03*
X832058Y366863D03*
Y369463D03*
X834658D03*
Y366863D03*
X837363Y366829D03*
X826858Y366863D03*
Y369463D03*
X824258Y366863D03*
Y369463D03*
X829458D03*
Y366863D03*
X821658D03*
X826216Y383108D03*
X823218Y382950D03*
X848608Y376068D03*
Y378668D03*
X846008Y376068D03*
Y378668D03*
X848932Y373257D03*
X823218Y385950D03*
X849606Y638753D03*
X836406D03*
X832006D03*
X796806D03*
X801206D03*
X792406D03*
X827606D03*
X818806D03*
X823206D03*
X810006D03*
X788006D03*
X845206D03*
X814406D03*
X805606D03*
X840806D03*
X849621Y660756D03*
X832021D03*
X810021D03*
X818821D03*
X836421D03*
X788021D03*
X814421D03*
X801221D03*
X805621D03*
X823221D03*
X827621D03*
X840821D03*
X796821D03*
X792421D03*
X845221D03*
X907921Y-58764D03*
Y-35764D03*
X902921Y-58764D03*
Y-35764D03*
X897921Y-58764D03*
Y-35764D03*
X892921Y-58764D03*
Y-35764D03*
X887921Y-58764D03*
Y-35764D03*
X882921Y-58764D03*
Y-35764D03*
X877921Y-58764D03*
Y-35764D03*
X872921Y-58764D03*
Y-35764D03*
X867921Y-58764D03*
Y-35764D03*
X862921Y-58764D03*
Y-35764D03*
X857921Y-58764D03*
Y-35764D03*
X852921Y-58764D03*
Y-35764D03*
X851208Y376068D03*
Y378668D03*
X851727Y373197D03*
X858406Y638753D03*
X854006D03*
X884806D03*
X880406D03*
X876006D03*
X871606D03*
X867206D03*
X911206D03*
X906806D03*
X889206D03*
X898006D03*
X902406D03*
X893606D03*
X862806D03*
X854021Y660756D03*
X858421D03*
X862821D03*
X898021D03*
X902421D03*
X871621D03*
X884821D03*
X893621D03*
X867221D03*
X889221D03*
X911221D03*
X906821D03*
X880421D03*
X876021D03*
X937921Y-35764D03*
X932921Y-58764D03*
Y-35764D03*
X927921Y-58764D03*
Y-35764D03*
X922921Y-58764D03*
Y-35764D03*
X917921Y-58764D03*
Y-35764D03*
X912921Y-58764D03*
Y-35764D03*
X942921D03*
X967921D03*
X962921Y-58764D03*
Y-35764D03*
X957921Y-58764D03*
Y-35764D03*
X952921Y-58764D03*
Y-35764D03*
X947921Y-58764D03*
Y-35764D03*
X942921Y-58764D03*
X972921D03*
Y-35764D03*
X967921Y-58764D03*
X937921D03*
X924406Y638753D03*
X920006D03*
X915606D03*
X972806D03*
X968406D03*
X964006D03*
X917100Y649300D03*
X942006Y638753D03*
X937606D03*
X933206D03*
X928806D03*
X959606D03*
X955206D03*
X950806D03*
X946406D03*
X959621Y660756D03*
X964021D03*
X968421D03*
X972821D03*
X920021D03*
X915621D03*
X924421D03*
X946421D03*
X942021D03*
X937621D03*
X933221D03*
X928821D03*
X955221D03*
X950821D03*
X1002921Y-58764D03*
Y-35764D03*
X997921Y-58764D03*
Y-35764D03*
X992921Y-58764D03*
Y-35764D03*
X987921Y-58764D03*
Y-35764D03*
X982921Y-58764D03*
Y-35764D03*
X977921Y-58764D03*
Y-35764D03*
X1032921Y-58764D03*
Y-35764D03*
X1027921Y-58764D03*
Y-35764D03*
X1022921Y-58764D03*
Y-35764D03*
X1017921Y-58764D03*
Y-35764D03*
X1012921Y-58764D03*
Y-35764D03*
X1007921Y-58764D03*
Y-35764D03*
X1003606Y638753D03*
X1012406D03*
X977206D03*
X990406D03*
X986006D03*
X994806D03*
X1016806D03*
X1021206D03*
X981606D03*
X999206D03*
X1025606D03*
X1008006D03*
X1030006D03*
X1034406D03*
X999221Y660756D03*
X1034421D03*
X1030021D03*
X1008021D03*
X1012421D03*
X1003621D03*
X1016821D03*
X977221D03*
X981621D03*
X1021221D03*
X1025621D03*
X994821D03*
X986021D03*
X990421D03*
X1067921Y-58764D03*
Y-35764D03*
X1062921Y-58764D03*
Y-35764D03*
X1057921Y-58764D03*
Y-35764D03*
X1052921Y-58764D03*
Y-35764D03*
X1047921Y-58764D03*
Y-35764D03*
X1042921Y-58764D03*
Y-35764D03*
X1037921Y-58764D03*
Y-35764D03*
X1092921Y-58764D03*
Y-35764D03*
X1087921Y-58764D03*
Y-35764D03*
X1082921Y-58764D03*
Y-35764D03*
X1077921Y-58764D03*
Y-35764D03*
X1072921Y-58764D03*
Y-35764D03*
X1075865Y264766D03*
X1070300Y264900D03*
X1073200Y264991D03*
X1057202Y264899D03*
X1060402Y264799D03*
X1066300Y264700D03*
X1063402Y264799D03*
X1054202Y264899D03*
X1077282Y338533D03*
X1080282D03*
X1056792Y338673D03*
X1063992D03*
X1060992D03*
X1071192D03*
X1068192D03*
X1096006Y638753D03*
X1078406D03*
X1082806D03*
X1074006D03*
X1069606D03*
X1091606D03*
X1052006D03*
X1038806D03*
X1087206D03*
X1060806D03*
X1056406D03*
X1065206D03*
X1043206D03*
X1047606D03*
X1078421Y660756D03*
X1060821D03*
X1087221D03*
X1038821D03*
X1091621D03*
X1052021D03*
X1074021D03*
X1065221D03*
X1096021D03*
X1056421D03*
X1043221D03*
X1047621D03*
X1082821D03*
X1069621D03*
X1157921Y-58764D03*
Y-35764D03*
X1152921Y-58764D03*
Y-35764D03*
X1147921Y-58764D03*
Y-35764D03*
X1142921Y-58764D03*
Y-35764D03*
X1137921Y-58764D03*
Y-35764D03*
X1132921Y-58764D03*
Y-35764D03*
X1127921Y-58764D03*
Y-35764D03*
X1122921Y-58764D03*
Y-35764D03*
X1117921Y-58764D03*
Y-35764D03*
X1112921Y-58764D03*
Y-35764D03*
X1107921Y-58764D03*
Y-35764D03*
X1102921Y-58764D03*
Y-35764D03*
X1097921Y-58764D03*
Y-35764D03*
X1135606Y638753D03*
X1126806D03*
X1144406D03*
X1140006D03*
X1118006D03*
X1122406D03*
X1153206D03*
X1157606D03*
X1104806D03*
X1100406D03*
X1131206D03*
X1148806D03*
X1109206D03*
X1113606D03*
X1157621Y660756D03*
X1148821D03*
X1122421D03*
X1126821D03*
X1100421D03*
X1118021D03*
X1140021D03*
X1113621D03*
X1109221D03*
X1153221D03*
X1144421D03*
X1104821D03*
X1131221D03*
X1135621D03*
X1217921Y-58764D03*
Y-35764D03*
X1212921Y-58764D03*
Y-35764D03*
X1207921Y-58764D03*
Y-35764D03*
X1202921Y-58764D03*
Y-35764D03*
X1197921Y-58764D03*
Y-35764D03*
X1192921Y-58764D03*
Y-35764D03*
X1187921Y-58764D03*
Y-35764D03*
X1182921Y-58764D03*
Y-35764D03*
X1177921Y-58764D03*
Y-35764D03*
X1172921Y-58764D03*
Y-35764D03*
X1167921Y-58764D03*
Y-35764D03*
X1162921Y-58764D03*
Y-35764D03*
X1188406Y638753D03*
X1214806D03*
X1197206D03*
X1201606D03*
X1192806D03*
X1170806D03*
X1162006D03*
X1166406D03*
X1206006D03*
X1219206D03*
X1179606D03*
X1175206D03*
X1210406D03*
X1184006D03*
X1184021Y660756D03*
X1219221D03*
X1192821D03*
X1188421D03*
X1201621D03*
X1179621D03*
X1214821D03*
X1206021D03*
X1166421D03*
X1210421D03*
X1170821D03*
X1162021D03*
X1175221D03*
X1197221D03*
X1232921Y-58764D03*
Y-35764D03*
X1227921Y-58764D03*
Y-35764D03*
X1222921Y-58764D03*
Y-35764D03*
X1252921Y-58764D03*
Y-35764D03*
X1247921Y-58764D03*
Y-35764D03*
X1242921Y-58764D03*
Y-35764D03*
X1237921Y-58764D03*
Y-35764D03*
X1257921D03*
X1272921Y-58764D03*
Y-35764D03*
X1267921Y-58764D03*
Y-35764D03*
X1262921Y-58764D03*
Y-35764D03*
X1257921Y-58764D03*
X1277921D03*
Y-35764D03*
X1265293Y646264D03*
X1263206Y638753D03*
X1223606D03*
X1228006D03*
X1258806D03*
X1241206D03*
X1236806D03*
X1250006D03*
X1245606D03*
X1276406D03*
X1254406D03*
X1280806D03*
X1272006D03*
X1267606D03*
X1232406D03*
X1265293Y652264D03*
X1228021Y660756D03*
X1232421D03*
X1280821D03*
X1245621D03*
X1236821D03*
X1223621D03*
X1276421D03*
X1241221D03*
X1272021D03*
X1258821D03*
X1250021D03*
X1254421D03*
X1263221D03*
X1267621D03*
X1342921Y-35764D03*
Y-58764D03*
X1317921D03*
X1312921Y-35764D03*
Y-58764D03*
X1307921Y-35764D03*
Y-58764D03*
X1302921Y-35764D03*
Y-58764D03*
X1297921D03*
Y-35764D03*
X1292921Y-58764D03*
Y-35764D03*
X1287921Y-58764D03*
Y-35764D03*
X1282921Y-58764D03*
Y-35764D03*
X1322921D03*
Y-58764D03*
X1317921Y-35764D03*
X1337921D03*
Y-58764D03*
X1332921Y-35764D03*
Y-58764D03*
X1327921Y-35764D03*
Y-58764D03*
X1324806Y638753D03*
X1298406D03*
X1285206D03*
X1294006D03*
X1302806D03*
X1333606D03*
X1338006D03*
X1320406D03*
X1311606D03*
X1329206D03*
X1307206D03*
X1342406D03*
X1289606D03*
X1316006D03*
X1329221Y660756D03*
X1311621D03*
X1316021D03*
X1333621D03*
X1342421D03*
X1285221D03*
X1324821D03*
X1338021D03*
X1298421D03*
X1289621D03*
X1294021D03*
X1320421D03*
X1302821D03*
X1307221D03*
X1402921Y-58764D03*
X1397921D03*
X1402921Y-35764D03*
X1392921Y-58764D03*
X1397921Y-35764D03*
X1387921Y-58764D03*
X1392921Y-35764D03*
X1382921Y-58764D03*
X1387921Y-35764D03*
X1377921Y-58764D03*
X1382921Y-35764D03*
X1372921Y-58764D03*
X1377921Y-35764D03*
X1367921Y-58764D03*
X1362921Y-35764D03*
Y-58764D03*
X1357921Y-35764D03*
Y-58764D03*
X1352921Y-35764D03*
Y-58764D03*
X1347921Y-35764D03*
Y-58764D03*
X1351206Y638753D03*
X1360006D03*
X1404506Y638853D03*
X1355606Y638753D03*
X1386906Y638853D03*
X1364406Y638753D03*
X1391306Y638853D03*
X1346806Y638753D03*
X1400106Y638853D03*
X1382006Y638753D03*
X1377606D03*
X1373206D03*
X1395706Y638853D03*
X1368806Y638753D03*
X1368821Y660756D03*
X1346821D03*
X1355621D03*
X1360021D03*
X1364421D03*
X1351221D03*
X1404521Y660856D03*
X1400121D03*
X1395721D03*
X1386921D03*
X1377621Y660756D03*
X1382021D03*
X1373221D03*
X1391321Y660856D03*
X1407921Y-58764D03*
X1412921Y-35764D03*
X1407921D03*
X1442921Y-58764D03*
X1447921Y-35764D03*
X1437921Y-58764D03*
X1442921Y-35764D03*
X1432921Y-58764D03*
X1437921Y-35764D03*
X1427921Y-58764D03*
X1432921Y-35764D03*
X1422921Y-58764D03*
X1427921Y-35764D03*
X1417921Y-58764D03*
X1422921Y-35764D03*
X1412921Y-58764D03*
X1417921Y-35764D03*
X1462921Y-58764D03*
X1457921D03*
X1462921Y-35764D03*
X1452921Y-58764D03*
X1457921Y-35764D03*
X1447921Y-58764D03*
X1452921Y-35764D03*
X1422106Y638853D03*
X1466106D03*
X1448506D03*
X1457306D03*
X1417706D03*
X1413306D03*
X1461706D03*
X1452906D03*
X1408906D03*
X1444106D03*
X1435306D03*
X1426506D03*
X1430906D03*
X1439706D03*
X1457321Y660856D03*
X1417721D03*
X1413321D03*
X1408921D03*
X1422121D03*
X1426521D03*
X1435321D03*
X1444121D03*
X1439721D03*
X1430921D03*
X1448521D03*
X1452921D03*
X1466121D03*
X1461721D03*
X1502921Y-58764D03*
X1507921Y-35764D03*
X1497921Y-58764D03*
X1502921Y-35764D03*
X1492921Y-58764D03*
X1497921Y-35764D03*
X1487921Y-58764D03*
X1492921Y-35764D03*
X1482921Y-58764D03*
X1487921Y-35764D03*
X1477921Y-58764D03*
X1482921Y-35764D03*
X1472921Y-58764D03*
X1477921Y-35764D03*
X1467921Y-58764D03*
X1472921Y-35764D03*
X1467921D03*
X1527921Y-58764D03*
X1522921D03*
X1527921Y-35764D03*
X1517921Y-58764D03*
X1522921Y-35764D03*
X1512921Y-58764D03*
X1517921Y-35764D03*
X1507921Y-58764D03*
X1512921Y-35764D03*
X1526586Y559860D03*
X1527285Y562386D03*
X1524538Y562286D03*
X1509696Y646236D03*
X1496906Y638853D03*
X1492506D03*
X1501706Y638753D03*
X1506106D03*
X1514906D03*
X1483706Y638853D03*
X1523706Y638753D03*
X1510506D03*
X1488106Y638853D03*
X1474906D03*
X1519306Y638753D03*
X1479306Y638853D03*
X1528106Y638753D03*
X1470506Y638853D03*
X1509696Y652236D03*
X1496921Y660856D03*
X1483721D03*
X1488121D03*
X1492521D03*
X1479321D03*
X1510521Y660756D03*
X1528121D03*
X1523721D03*
X1501721D03*
X1506121D03*
X1514921D03*
X1519321D03*
X1474921Y660856D03*
X1470521D03*
X1587921Y-58764D03*
X1582921D03*
X1587921Y-35764D03*
X1532921D03*
X1542921D03*
X1532921Y-58764D03*
X1537921Y-35764D03*
X1577921Y-58764D03*
X1582921Y-35764D03*
X1572921Y-58764D03*
X1577921Y-35764D03*
X1567921Y-58764D03*
X1572921Y-35764D03*
X1562921Y-58764D03*
X1567921Y-35764D03*
X1557921Y-58764D03*
X1562921Y-35764D03*
X1552921Y-58764D03*
X1557921Y-35764D03*
X1547921Y-58764D03*
X1552921Y-35764D03*
X1542921Y-58764D03*
X1547921Y-35764D03*
X1537921Y-58764D03*
X1531986Y559860D03*
X1529286D03*
X1529985Y562386D03*
X1532685D03*
X1546795Y563316D03*
X1546685Y568656D03*
X1546825Y565986D03*
X1549395Y563541D03*
X1549285Y568881D03*
X1549425Y566211D03*
X1535385Y562386D03*
X1534897Y559808D03*
X1541267Y563185D03*
X1543967D03*
X1541080Y565859D03*
X1538331Y563913D03*
X1538385Y560978D03*
X1544080Y568859D03*
Y565859D03*
X1580121Y647556D03*
X1555106Y638753D03*
X1555121Y647556D03*
X1590121D03*
X1590106Y638753D03*
X1590121Y643156D03*
X1585121Y647556D03*
X1585106Y638753D03*
X1585121Y643156D03*
X1565121Y647556D03*
X1570121Y643156D03*
X1570106Y638753D03*
X1565106D03*
X1565121Y643156D03*
X1570121Y647556D03*
X1560121D03*
X1560106Y638753D03*
X1560121Y643156D03*
X1575121D03*
X1575106Y638753D03*
X1575121Y647556D03*
X1555121Y643156D03*
X1580106Y638753D03*
X1580121Y643156D03*
X1550121Y647556D03*
X1541306Y638753D03*
X1545706D03*
X1550106D03*
X1550121Y643156D03*
X1536906Y638753D03*
X1532506D03*
X1565121Y651956D03*
X1570121Y660756D03*
Y656356D03*
X1565121Y660756D03*
X1555121Y651956D03*
X1590121Y660756D03*
Y656356D03*
Y651956D03*
X1585121Y660756D03*
Y656356D03*
Y651956D03*
X1580121Y660756D03*
Y656356D03*
Y651956D03*
X1560121Y660756D03*
Y656356D03*
Y651956D03*
X1555121Y660756D03*
Y656356D03*
X1570121Y651956D03*
X1575121D03*
Y656356D03*
Y660756D03*
X1565121Y656356D03*
X1550121Y651956D03*
Y656356D03*
X1541321Y660756D03*
X1550121D03*
X1545721D03*
X1532521D03*
X1536921D03*
X1642921Y-35764D03*
Y-58764D03*
X1637921Y-35764D03*
Y-58764D03*
X1632921Y-35764D03*
Y-58764D03*
X1627921D03*
X1622921D03*
X1627921Y-35764D03*
X1617921Y-58764D03*
X1622921Y-35764D03*
X1612921Y-58764D03*
X1617921Y-35764D03*
X1607921Y-58764D03*
X1612921Y-35764D03*
X1602921Y-58764D03*
X1607921Y-35764D03*
X1597921Y-58764D03*
X1602921Y-35764D03*
X1592921Y-58764D03*
X1597921Y-35764D03*
X1592921D03*
X1647921D03*
Y-58764D03*
X1625106Y638753D03*
X1625121Y647556D03*
X1630121Y643156D03*
X1630106Y638753D03*
X1630121Y647556D03*
X1635121Y643156D03*
X1635106Y638753D03*
X1635121Y647556D03*
X1640121Y643156D03*
Y647556D03*
X1640106Y638753D03*
X1650121Y647556D03*
X1650106Y638753D03*
X1650121Y643156D03*
X1645121Y647556D03*
X1645106Y638753D03*
X1645121Y643156D03*
X1625121D03*
X1620121Y647556D03*
X1620106Y638753D03*
X1620121Y643156D03*
X1615121Y647556D03*
X1615106Y638753D03*
X1615121Y643156D03*
X1610121Y647556D03*
X1610106Y638753D03*
X1610121Y643156D03*
X1605121Y647556D03*
X1605106Y638753D03*
X1605121Y643156D03*
X1600121Y647556D03*
X1600106Y638753D03*
X1600121Y643156D03*
X1595121Y647556D03*
X1595106Y638753D03*
X1595121Y643156D03*
X1625121Y651956D03*
Y660756D03*
X1630121Y651956D03*
Y656356D03*
Y660756D03*
X1635121Y651956D03*
Y656356D03*
Y660756D03*
X1625121Y656356D03*
X1640121D03*
Y651956D03*
X1650121Y660756D03*
Y656356D03*
Y651956D03*
X1645121Y660756D03*
Y656356D03*
Y651956D03*
X1640121Y660756D03*
X1620121D03*
Y656356D03*
Y651956D03*
X1615121Y660756D03*
Y656356D03*
Y651956D03*
X1610121Y660756D03*
Y656356D03*
Y651956D03*
X1605121Y660756D03*
Y656356D03*
Y651956D03*
X1600121Y660756D03*
Y656356D03*
Y651956D03*
X1595121Y660756D03*
Y656356D03*
Y651956D03*
X1692921Y-40764D03*
X1702921Y-54764D03*
X1687921D03*
X1682921D03*
X1677921D03*
X1672921D03*
X1692921D03*
X1697921D03*
X1707921D03*
X1712921D03*
X1697921Y-40764D03*
X1692921Y-50764D03*
X1687921D03*
X1682921D03*
X1677921D03*
X1672921D03*
X1712921D03*
X1707921D03*
X1702921D03*
X1697921Y-45764D03*
X1707921D03*
X1702921D03*
X1712921D03*
X1697921Y-50764D03*
X1667921Y-35764D03*
X1712921D03*
Y-58764D03*
X1707921Y-35764D03*
Y-58764D03*
X1702921Y-35764D03*
Y-58764D03*
X1697921Y-35764D03*
Y-58764D03*
X1687921Y-40764D03*
X1672921Y-45764D03*
X1677921D03*
X1682921D03*
Y-40764D03*
X1687921Y-45764D03*
X1692921D03*
X1667921Y-58764D03*
X1662921Y-35764D03*
Y-58764D03*
X1657921Y-35764D03*
Y-58764D03*
X1652921Y-35764D03*
Y-58764D03*
X1712921Y-40764D03*
X1707921D03*
X1702921D03*
X1677921D03*
X1672921D03*
X1677921Y-35764D03*
Y-58764D03*
X1672921Y-35764D03*
Y-58764D03*
X1682921Y-35764D03*
Y-58764D03*
X1692921Y-35764D03*
Y-58764D03*
X1687921Y-35764D03*
Y-58764D03*
X1690121Y647556D03*
X1710121D03*
X1710106Y638753D03*
X1710121Y643156D03*
X1705121Y647556D03*
X1705106Y638753D03*
X1695121Y643156D03*
X1695106Y638753D03*
X1695121Y647556D03*
X1700121Y643156D03*
X1700106Y638753D03*
X1685121Y647556D03*
X1685106Y638753D03*
X1685121Y643156D03*
X1680121Y647556D03*
X1680106Y638753D03*
X1680121Y643156D03*
X1675121Y647556D03*
X1675106Y638753D03*
X1675121Y643156D03*
X1670121Y647556D03*
X1670106Y638753D03*
X1670121Y643156D03*
X1665121Y647556D03*
X1665106Y638753D03*
X1665121Y643156D03*
X1660121Y647556D03*
X1660106Y638753D03*
X1660121Y643156D03*
X1655121Y647556D03*
X1655106Y638753D03*
X1655121Y643156D03*
X1690121D03*
X1690106Y638753D03*
X1700121Y647556D03*
X1705121Y643156D03*
X1690121Y656356D03*
Y651956D03*
X1710121Y660756D03*
Y656356D03*
Y651956D03*
X1705121Y660756D03*
Y656356D03*
Y651956D03*
X1690121Y660756D03*
X1695121Y651956D03*
Y656356D03*
Y660756D03*
X1685121Y651956D03*
X1680121Y660756D03*
Y656356D03*
Y651956D03*
X1675121Y660756D03*
Y656356D03*
Y651956D03*
X1670121Y660756D03*
Y656356D03*
Y651956D03*
X1665121Y660756D03*
Y656356D03*
Y651956D03*
X1660121Y660756D03*
Y656356D03*
Y651956D03*
X1655121Y660756D03*
Y656356D03*
Y651956D03*
X1685121Y660756D03*
Y656356D03*
X1700121Y651956D03*
Y656356D03*
Y660756D03*
X1737921Y-50764D03*
X1722921Y-45764D03*
X1727921D03*
X1732921D03*
X1747921D03*
X1752921D03*
X1727921Y-54764D03*
X1757921D03*
X1717921D03*
X1722921D03*
X1767921Y-40764D03*
Y-50764D03*
X1762921D03*
X1757921D03*
X1762921Y-54764D03*
X1752921D03*
X1747921D03*
X1742921D03*
X1737921D03*
X1732921D03*
X1772921D03*
X1767921D03*
X1762921Y-40764D03*
X1772921D03*
X1722921Y-50764D03*
X1717921D03*
X1732921D03*
X1757921Y-40764D03*
X1717921Y-45764D03*
Y-58764D03*
X1742921Y-50764D03*
X1747921D03*
X1752921D03*
X1742921Y-58764D03*
X1737921Y-35764D03*
Y-58764D03*
X1732921Y-35764D03*
Y-58764D03*
X1727921Y-35764D03*
Y-58764D03*
X1722921Y-35764D03*
Y-58764D03*
X1717921Y-35764D03*
X1757921Y-45764D03*
X1762921D03*
X1742921D03*
X1752921Y-40764D03*
X1747921D03*
X1742921D03*
X1737921D03*
X1732921D03*
X1727921D03*
X1722921D03*
X1717921D03*
X1727921Y-50764D03*
X1767921Y-45764D03*
X1772921D03*
X1737921D03*
X1772921Y-35764D03*
Y-58764D03*
X1767921Y-35764D03*
Y-58764D03*
X1762921Y-35764D03*
Y-58764D03*
X1757921Y-35764D03*
Y-58764D03*
X1752921Y-35764D03*
Y-58764D03*
X1747921Y-35764D03*
Y-58764D03*
X1742921Y-35764D03*
X1772921Y-50764D03*
X1775121Y643156D03*
Y647556D03*
X1775106Y638753D03*
X1730121Y647556D03*
X1730106Y638753D03*
X1730121Y643156D03*
X1725121Y647556D03*
X1725106Y638753D03*
X1725121Y643156D03*
X1720121Y647556D03*
X1720106Y638753D03*
X1720121Y643156D03*
X1715121Y647556D03*
X1715106Y638753D03*
X1715121Y643156D03*
X1770121Y647556D03*
X1770106Y638753D03*
X1770121Y643156D03*
X1765121Y647556D03*
X1765106Y638753D03*
X1765121Y643156D03*
X1760121Y647556D03*
X1760106Y638753D03*
X1760121Y643156D03*
X1755121Y647556D03*
X1755106Y638753D03*
X1755121Y643156D03*
X1750121Y647556D03*
X1750106Y638753D03*
X1750121Y643156D03*
X1745121Y647556D03*
X1745106Y638753D03*
X1745121Y643156D03*
X1740121Y647556D03*
X1740106Y638753D03*
X1740121Y643156D03*
X1735121Y647556D03*
X1735106Y638753D03*
X1735121Y643156D03*
X1770121Y660756D03*
X1775121D03*
Y656356D03*
Y651956D03*
X1725121Y660756D03*
Y656356D03*
Y651956D03*
X1720121Y660756D03*
Y656356D03*
Y651956D03*
X1715121Y660756D03*
Y656356D03*
Y651956D03*
X1770121D03*
X1765121Y660756D03*
Y656356D03*
Y651956D03*
X1760121Y660756D03*
Y656356D03*
Y651956D03*
X1755121Y660756D03*
Y656356D03*
Y651956D03*
X1750121Y660756D03*
Y656356D03*
Y651956D03*
X1745121Y660756D03*
Y656356D03*
Y651956D03*
X1740121Y660756D03*
Y656356D03*
Y651956D03*
X1735121Y660756D03*
Y656356D03*
Y651956D03*
X1730121Y660756D03*
Y656356D03*
X1770121D03*
X1730121Y651956D03*
X1817921Y-40764D03*
X1832921Y-45764D03*
Y-54764D03*
X1827921D03*
X1822921D03*
X1817921D03*
X1812921D03*
X1807921D03*
X1802921D03*
X1797921D03*
X1792921D03*
X1787921D03*
X1782921D03*
X1777921D03*
X1832921Y-50764D03*
X1827921D03*
X1822921D03*
X1817921D03*
X1812921D03*
X1807921D03*
X1802921D03*
X1797921D03*
X1792921D03*
X1787921D03*
X1782921Y-40764D03*
X1792921D03*
X1802921D03*
X1807921D03*
X1822921D03*
X1827921D03*
X1832921D03*
X1812921D03*
X1797921D03*
X1777921Y-45764D03*
X1782921D03*
X1787921D03*
X1792921D03*
X1797921D03*
X1802921D03*
X1807921D03*
X1812921D03*
X1817921D03*
X1822921D03*
X1787921Y-40764D03*
X1832921Y-35764D03*
Y-58764D03*
X1827921Y-35764D03*
Y-58764D03*
X1822921Y-35764D03*
Y-58764D03*
X1817921Y-35764D03*
Y-58764D03*
X1812921Y-35764D03*
Y-58764D03*
X1807921Y-35764D03*
Y-58764D03*
X1802921Y-35764D03*
Y-58764D03*
X1797921Y-35764D03*
Y-58764D03*
X1792921Y-35764D03*
Y-58764D03*
X1787921Y-35764D03*
Y-58764D03*
X1782921Y-35764D03*
Y-58764D03*
X1777921Y-35764D03*
Y-58764D03*
X1782921Y-50764D03*
X1777921D03*
Y-40764D03*
X1827921Y-45764D03*
X1780121Y643156D03*
X1780106Y638753D03*
X1780121Y647556D03*
X1785121Y643156D03*
X1790121D03*
X1835121Y647556D03*
X1835106Y638753D03*
X1835121Y643156D03*
X1830121Y647556D03*
X1830106Y638753D03*
X1830121Y643156D03*
X1825121Y647556D03*
X1825106Y638753D03*
X1825121Y643156D03*
X1820121Y647556D03*
X1820106Y638753D03*
X1820121Y643156D03*
X1815121Y647556D03*
X1815106Y638753D03*
X1815121Y643156D03*
X1810121Y647556D03*
X1810106Y638753D03*
X1810121Y643156D03*
X1805121Y647556D03*
X1805106Y638753D03*
X1805121Y643156D03*
X1800121Y647556D03*
X1800106Y638753D03*
X1800121Y643156D03*
X1795121Y647556D03*
X1795106Y638753D03*
X1795121Y643156D03*
X1790121Y647556D03*
X1790106Y638753D03*
X1785121Y647556D03*
X1785106Y638753D03*
X1800121Y656356D03*
X1780121Y651956D03*
Y656356D03*
Y660756D03*
X1835121D03*
Y656356D03*
Y651956D03*
X1830121Y660756D03*
Y656356D03*
Y651956D03*
X1825121Y660756D03*
Y656356D03*
Y651956D03*
X1820121Y660756D03*
Y656356D03*
Y651956D03*
X1815121Y660756D03*
Y656356D03*
Y651956D03*
X1810121Y660756D03*
Y656356D03*
Y651956D03*
X1805121Y660756D03*
Y656356D03*
Y651956D03*
X1800121Y660756D03*
Y651956D03*
X1795121Y660756D03*
Y656356D03*
Y651956D03*
X1790121Y660756D03*
Y656356D03*
Y651956D03*
X1785121Y660756D03*
Y656356D03*
Y651956D03*
X1857921Y-45764D03*
X1837921D03*
X1897921D03*
X1892921D03*
X1887921D03*
X1882921D03*
X1877921D03*
X1872921D03*
X1867921D03*
X1862921D03*
X1842921Y-54764D03*
X1852921Y-45764D03*
X1847921D03*
X1842921D03*
X1897921Y-54764D03*
X1892921D03*
X1887921D03*
X1882921D03*
X1877921D03*
X1872921D03*
X1867921D03*
X1862921D03*
X1857921D03*
X1852921D03*
X1847921D03*
X1837921D03*
X1897921Y-50764D03*
X1892921D03*
X1887921D03*
X1882921D03*
X1877921D03*
X1872921D03*
X1867921D03*
X1862921D03*
X1857921D03*
X1852921D03*
X1847921D03*
X1842921D03*
X1837921D03*
X1892921Y-40764D03*
X1897921D03*
X1877921D03*
X1882921D03*
X1887921D03*
X1857921D03*
X1862921D03*
X1867921D03*
X1872921D03*
X1837921D03*
X1842921D03*
X1847921D03*
X1852921D03*
Y-35764D03*
Y-58764D03*
X1847921Y-35764D03*
Y-58764D03*
X1842921Y-35764D03*
Y-58764D03*
X1837921Y-35764D03*
Y-58764D03*
X1862921D03*
X1857921Y-35764D03*
Y-58764D03*
X1882921D03*
X1877921Y-35764D03*
Y-58764D03*
X1872921Y-35764D03*
Y-58764D03*
X1867921Y-35764D03*
Y-58764D03*
X1862921Y-35764D03*
X1897921D03*
Y-58764D03*
X1892921Y-35764D03*
Y-58764D03*
X1887921Y-35764D03*
Y-58764D03*
X1882921Y-35764D03*
X1895121Y647556D03*
X1895106Y638753D03*
X1895121Y643156D03*
X1890121Y647556D03*
X1890106Y638753D03*
X1890121Y643156D03*
X1885121Y647556D03*
X1885106Y638753D03*
X1885121Y643156D03*
X1880121Y647556D03*
X1880106Y638753D03*
X1880121Y643156D03*
X1875121Y647556D03*
X1875106Y638753D03*
X1875121Y643156D03*
X1870121Y647556D03*
X1870106Y638753D03*
X1870121Y643156D03*
X1865121Y647556D03*
X1865106Y638753D03*
X1865121Y643156D03*
X1860121Y647556D03*
X1860106Y638753D03*
X1860121Y643156D03*
X1855121Y647556D03*
X1855106Y638753D03*
X1855121Y643156D03*
X1850121Y647556D03*
X1850106Y638753D03*
X1850121Y643156D03*
X1845121Y647556D03*
X1845106Y638753D03*
X1845121Y643156D03*
X1840121Y647556D03*
X1840106Y638753D03*
X1840121Y643156D03*
X1895121Y660756D03*
Y656356D03*
Y651956D03*
X1890121Y660756D03*
Y656356D03*
Y651956D03*
X1885121Y660756D03*
Y656356D03*
Y651956D03*
X1880121Y660756D03*
Y656356D03*
Y651956D03*
X1875121Y660756D03*
Y656356D03*
Y651956D03*
X1870121Y660756D03*
Y656356D03*
Y651956D03*
X1865121Y660756D03*
Y656356D03*
Y651956D03*
X1860121Y660756D03*
Y656356D03*
Y651956D03*
X1855121Y660756D03*
Y656356D03*
Y651956D03*
X1850121Y660756D03*
Y656356D03*
Y651956D03*
X1845121Y660756D03*
Y656356D03*
Y651956D03*
X1840121Y660756D03*
Y656356D03*
Y651956D03*
X1927921Y-40764D03*
X1947921Y-45764D03*
X1942921D03*
X1937921D03*
X1932921D03*
X1927921D03*
X1922921D03*
X1917921D03*
X1912921D03*
X1907921D03*
X1902921D03*
X1927921Y-50764D03*
X1932921D03*
Y-40764D03*
X1937921D03*
X1942921D03*
X1947921D03*
X1907921Y-50764D03*
X1902921D03*
X1922921Y-40764D03*
X1917921D03*
X1912921D03*
X1907921D03*
X1902921D03*
X1922921Y-54764D03*
X1917921D03*
X1912921D03*
X1907921D03*
X1902921D03*
X1927921D03*
X1932921D03*
X1937921D03*
X1942921D03*
X1947921D03*
X1952921D03*
X1957921D03*
Y-50764D03*
X1952921D03*
X1947921D03*
X1942921D03*
X1937921D03*
X1922921D03*
X1917921D03*
X1912921D03*
X1957921Y-35764D03*
Y-58764D03*
X1952921Y-35764D03*
Y-58764D03*
X1947921Y-35764D03*
Y-58764D03*
X1942921Y-35764D03*
Y-58764D03*
X1937921Y-35764D03*
Y-58764D03*
X1932921Y-35764D03*
Y-58764D03*
X1927921Y-35764D03*
Y-58764D03*
X1922921Y-35764D03*
Y-58764D03*
X1917921Y-35764D03*
Y-58764D03*
X1912921Y-35764D03*
Y-58764D03*
X1907921Y-35764D03*
Y-58764D03*
X1902921Y-35764D03*
Y-58764D03*
X1938150Y70447D03*
X1937950Y73247D03*
X1940750Y73347D03*
X1929961Y73247D03*
X1935350D03*
X1932730Y73310D03*
X1942390Y76040D03*
X1943550Y73347D03*
X1946350Y73447D03*
X1948951Y73448D03*
X1945020Y76060D03*
X1954271Y80449D03*
X1936706Y75987D03*
X1939470Y76000D03*
X1930150Y70447D03*
X1932950D03*
X1935550D03*
X1940950Y70547D03*
X1943750D03*
X1907385Y93926D03*
X1904678Y93845D03*
X1907428Y91133D03*
X1904742Y96552D03*
X1907448Y96615D03*
X1908400Y101010D03*
X1960106Y638753D03*
X1955106D03*
X1950106D03*
X1945121Y647556D03*
Y643156D03*
X1945106Y638753D03*
X1940121Y647556D03*
Y643156D03*
X1940106Y638753D03*
X1935121Y647556D03*
Y643156D03*
X1935106Y638753D03*
X1930106D03*
X1925106D03*
X1920121Y647556D03*
X1910121Y643156D03*
X1910106Y638753D03*
X1905121Y647556D03*
Y643156D03*
X1905106Y638753D03*
X1900121Y647556D03*
X1900106Y638753D03*
X1900121Y643156D03*
X1920106Y638753D03*
X1915121Y647556D03*
X1920121Y643156D03*
X1910121Y647556D03*
X1915106Y638753D03*
X1915121Y643156D03*
X1960121Y656356D03*
Y660756D03*
X1955121Y656356D03*
Y660756D03*
X1950121Y651956D03*
Y656356D03*
Y660756D03*
X1945121Y651956D03*
Y656356D03*
Y660756D03*
X1940121Y651956D03*
Y656356D03*
Y660756D03*
X1935121Y651956D03*
Y656356D03*
Y660756D03*
X1930121Y651956D03*
Y656356D03*
Y660756D03*
X1925121Y651956D03*
Y656356D03*
Y660756D03*
X1920121Y651956D03*
Y656356D03*
X1905121Y651956D03*
Y656356D03*
Y660756D03*
X1900121D03*
Y656356D03*
Y651956D03*
X1915121D03*
Y656356D03*
Y660756D03*
X1920121D03*
X1910121D03*
Y656356D03*
Y651956D03*
X1967921Y-45764D03*
X1962921D03*
Y-40764D03*
X1967921D03*
Y-54764D03*
X1962921D03*
X1967921Y-50764D03*
X1962921D03*
X1967921Y-35764D03*
Y-58764D03*
X1962921Y-35764D03*
Y-58764D03*
X1970121Y647556D03*
Y643156D03*
X1970106Y638753D03*
X1965121Y647556D03*
Y643156D03*
X1965106Y638753D03*
X1970121Y651956D03*
Y656356D03*
Y660756D03*
X1965121Y651956D03*
Y656356D03*
Y660756D03*
G54D20*
X1482000Y-15000D03*
X1779504Y-5000D03*
G54D11*
X-15354Y124843D03*
Y156339D03*
X1181Y124843D03*
Y140591D03*
X6299Y148465D03*
X-10236D03*
X17716Y156339D03*
X1181D03*
X-9843D03*
X6693Y124843D03*
X-9843D03*
X11811Y148465D03*
X6693Y140591D03*
Y156339D03*
X-4725Y148465D03*
X23228Y156339D03*
X1181Y380984D03*
X-10236Y373110D03*
X-4725D03*
X17716Y380984D03*
X-4725Y388858D03*
X6693Y380984D03*
X-9843D03*
G54D30*
G01X548049Y-193422D02*
Y-210922D01*
G01X543027Y-193422D02*
X553071D01*
G01X565549Y-199256D02*
Y-210922D01*
G01Y-194589D02*
X565112Y-194297D01*
Y-193714D01*
X565549Y-193422D01*
X565986Y-193714D01*
Y-194297D01*
X565549Y-194589D01*
G01X583049Y-210922D02*
X581739Y-210630D01*
X580429Y-209464D01*
X579555Y-207422D01*
X579119Y-205089D01*
X579555Y-202755D01*
X580429Y-200714D01*
X581739Y-199547D01*
X583049Y-199256D01*
X584359Y-199547D01*
X585669Y-200714D01*
X586542Y-202755D01*
X586761Y-205089D01*
X586542Y-207422D01*
X585669Y-209464D01*
X584359Y-210630D01*
X583049Y-210922D01*
G01X597492Y-215297D02*
X599021Y-216464D01*
X600767Y-216755D01*
X602295Y-216464D01*
X603606Y-215006D01*
X604479Y-212964D01*
Y-199256D01*
G01Y-201589D02*
X603606Y-200422D01*
X602295Y-199547D01*
X600767Y-199256D01*
X599021Y-199839D01*
X597929Y-201005D01*
X597055Y-203047D01*
X596619Y-205089D01*
X596837Y-206839D01*
X597711Y-208881D01*
X599021Y-210339D01*
X600767Y-210922D01*
X602077Y-210630D01*
X603606Y-209464D01*
X604479Y-208298D01*
G01X621979Y-210922D02*
Y-199256D01*
G01Y-201297D02*
X621106Y-200131D01*
X619795Y-199547D01*
X618267Y-199256D01*
X616739Y-199839D01*
X615429Y-201005D01*
X614555Y-202755D01*
X614119Y-205089D01*
X614555Y-207422D01*
X615429Y-209172D01*
X616739Y-210339D01*
X618267Y-210922D01*
X619795Y-210630D01*
X621106Y-209756D01*
X621979Y-208589D01*
G01X648682Y-210922D02*
Y-193422D01*
X653922D01*
X655669Y-194297D01*
X656979Y-196339D01*
X657416Y-198672D01*
X656979Y-201005D01*
X655887Y-202755D01*
X653922Y-203631D01*
X648682D01*
G01X674479Y-210922D02*
Y-199256D01*
G01Y-201297D02*
X673606Y-200131D01*
X672295Y-199547D01*
X670767Y-199256D01*
X669239Y-199839D01*
X667929Y-201005D01*
X667055Y-202755D01*
X666619Y-205089D01*
X667055Y-207422D01*
X667929Y-209172D01*
X669239Y-210339D01*
X670767Y-210922D01*
X672295Y-210630D01*
X673606Y-209756D01*
X674479Y-208589D01*
G01X684774Y-208881D02*
X685866Y-210047D01*
X687394Y-210922D01*
X688704D01*
X690014Y-210339D01*
X690887Y-209464D01*
X691324Y-208298D01*
X691106Y-206547D01*
X690232Y-205672D01*
X686302Y-203922D01*
X685429Y-201880D01*
X685866Y-200422D01*
X686739Y-199547D01*
X688049Y-199256D01*
X689359Y-199547D01*
X690669Y-200422D01*
G01X702274Y-208881D02*
X703366Y-210047D01*
X704894Y-210922D01*
X706204D01*
X707514Y-210339D01*
X708387Y-209464D01*
X708824Y-208298D01*
X708606Y-206547D01*
X707732Y-205672D01*
X703802Y-203922D01*
X702929Y-201880D01*
X703366Y-200422D01*
X704239Y-199547D01*
X705549Y-199256D01*
X706859Y-199547D01*
X708169Y-200422D01*
G01X735746Y-210922D02*
Y-193422D01*
X740112D01*
X741859Y-194297D01*
X743169Y-195464D01*
X744261Y-197213D01*
X745134Y-199256D01*
X745352Y-202172D01*
X745134Y-205089D01*
X744261Y-207131D01*
X743169Y-208881D01*
X741859Y-210047D01*
X740112Y-210922D01*
X735746D01*
G01X752590Y-193422D02*
X758049Y-210922D01*
X763508Y-193422D01*
G01X775549D02*
Y-210922D01*
G01X770527Y-193422D02*
X780571D01*
G01X804872Y-210922D02*
Y-193422D01*
X810549Y-208005D01*
X816226Y-193422D01*
Y-210922D01*
G01X829795Y-201589D02*
X830669Y-200714D01*
X831324Y-199256D01*
X831761Y-197213D01*
X831324Y-195464D01*
X830451Y-194297D01*
X828922Y-193422D01*
X823027D01*
Y-210922D01*
X830232D01*
X831761Y-209756D01*
X832634Y-208005D01*
X833071Y-205964D01*
X832634Y-203922D01*
X831324Y-202172D01*
X829795Y-201589D01*
X823027D01*
G01X647372Y-165922D02*
Y-148422D01*
X653049Y-163005D01*
X658726Y-148422D01*
Y-165922D01*
G01X670549D02*
X669239Y-165630D01*
X667929Y-164464D01*
X667055Y-162422D01*
X666619Y-160089D01*
X667055Y-157755D01*
X667929Y-155714D01*
X669239Y-154547D01*
X670549Y-154256D01*
X671859Y-154547D01*
X673169Y-155714D01*
X674042Y-157755D01*
X674261Y-160089D01*
X674042Y-162422D01*
X673169Y-164464D01*
X671859Y-165630D01*
X670549Y-165922D01*
G01X691979Y-148422D02*
Y-165922D01*
G01Y-163298D02*
X691106Y-164756D01*
X689795Y-165630D01*
X688267Y-165922D01*
X686521Y-165339D01*
X685211Y-163881D01*
X684337Y-162131D01*
X684119Y-160089D01*
X684337Y-158047D01*
X685211Y-156297D01*
X686521Y-154839D01*
X688267Y-154256D01*
X689795Y-154547D01*
X690887Y-155131D01*
X691979Y-156297D01*
G01X702274Y-158047D02*
X709261D01*
X708606Y-156005D01*
X707514Y-154839D01*
X705986Y-154256D01*
X704457Y-154547D01*
X703147Y-155422D01*
X702274Y-157464D01*
X701837Y-159214D01*
Y-160964D01*
X702274Y-162714D01*
X703366Y-164464D01*
X704676Y-165630D01*
X706204Y-165922D01*
X707732Y-165339D01*
X709261Y-163589D01*
G01X723049Y-165922D02*
Y-148422D01*
G01X975549Y-210922D02*
Y-193422D01*
X972929Y-196922D01*
G01Y-210922D02*
X978169D01*
G01X988246Y-208298D02*
X989555Y-209756D01*
X991084Y-210630D01*
X993049Y-210922D01*
X995014Y-210339D01*
X996542Y-209172D01*
X997634Y-207131D01*
X997852Y-204797D01*
X997416Y-202464D01*
X996324Y-201005D01*
X994795Y-199839D01*
X993267Y-199547D01*
X991739Y-199839D01*
X989774Y-201005D01*
X990429Y-193422D01*
X996324D01*
G01X1010549Y-210922D02*
Y-193422D01*
X1007929Y-196922D01*
G01Y-210922D02*
X1013169D01*
G01X1023901Y-196339D02*
X1025211Y-194589D01*
X1026739Y-193714D01*
X1028486Y-193422D01*
X1030669Y-194005D01*
X1032197Y-195464D01*
X1032634Y-197213D01*
X1032416Y-198964D01*
X1031542Y-200422D01*
X1027176Y-203339D01*
X1025211Y-205380D01*
X1023901Y-208298D01*
X1023464Y-210922D01*
X1032634D01*
G01X1041401Y-203631D02*
X1042929Y-201589D01*
X1044239Y-200422D01*
X1045986Y-199839D01*
X1047514Y-200422D01*
X1048606Y-201589D01*
X1049479Y-203339D01*
X1049697Y-205380D01*
X1049479Y-207131D01*
X1048606Y-208881D01*
X1047295Y-210339D01*
X1045767Y-210922D01*
X1044021Y-210339D01*
X1042492Y-208589D01*
X1041619Y-205964D01*
X1041401Y-203047D01*
X1041837Y-199256D01*
X1042492Y-197213D01*
X1043584Y-195172D01*
X1045112Y-193714D01*
X1046641Y-193422D01*
X1048169Y-194005D01*
X1049261Y-195464D01*
G01X962432Y-165922D02*
Y-148422D01*
X967672D01*
X969419Y-149297D01*
X970729Y-151339D01*
X971166Y-153672D01*
X970729Y-156005D01*
X969637Y-157755D01*
X967672Y-158631D01*
X962432D01*
G01X989102Y-149881D02*
X987792Y-149005D01*
X986264Y-148422D01*
X984517D01*
X982552Y-149297D01*
X981024Y-150755D01*
X979932Y-152506D01*
X979059Y-155422D01*
X978840Y-158047D01*
X979277Y-160672D01*
X979932Y-162422D01*
X981242Y-164172D01*
X982771Y-165339D01*
X984299Y-165922D01*
X985827D01*
X987356Y-165339D01*
X988666Y-164464D01*
X989758Y-163298D01*
G01X1003545Y-156589D02*
X1004419Y-155714D01*
X1005074Y-154256D01*
X1005511Y-152213D01*
X1005074Y-150464D01*
X1004201Y-149297D01*
X1002672Y-148422D01*
X996777D01*
Y-165922D01*
X1003982D01*
X1005511Y-164756D01*
X1006384Y-163005D01*
X1006821Y-160964D01*
X1006384Y-158922D01*
X1005074Y-157172D01*
X1003545Y-156589D01*
X996777D01*
G01X1012749Y-171755D02*
X1025849D01*
G01X1031777Y-165922D02*
Y-148422D01*
X1041821Y-165922D01*
Y-148422D01*
G01X1054299Y-165922D02*
X1052552Y-165630D01*
X1051024Y-164464D01*
X1049714Y-162714D01*
X1048840Y-160672D01*
X1048404Y-158339D01*
Y-156005D01*
X1048840Y-153672D01*
X1049714Y-151630D01*
X1051024Y-149881D01*
X1052552Y-148714D01*
X1054299Y-148422D01*
X1056045Y-148714D01*
X1057574Y-149881D01*
X1058884Y-151630D01*
X1059758Y-153672D01*
X1060194Y-156005D01*
Y-158339D01*
X1059758Y-160672D01*
X1058884Y-162714D01*
X1057574Y-164464D01*
X1056045Y-165630D01*
X1054299Y-165922D01*
G01X1128099Y-210922D02*
Y-193422D01*
X1125479Y-196922D01*
G01Y-210922D02*
X1130719D01*
G01X1147345Y-201589D02*
X1148219Y-200714D01*
X1148874Y-199256D01*
X1149311Y-197213D01*
X1148874Y-195464D01*
X1148001Y-194297D01*
X1146472Y-193422D01*
X1140577D01*
Y-210922D01*
X1147782D01*
X1149311Y-209756D01*
X1150184Y-208005D01*
X1150621Y-205964D01*
X1150184Y-203922D01*
X1148874Y-202172D01*
X1147345Y-201589D01*
X1140577D01*
G01X1105140Y-148422D02*
X1110599Y-165922D01*
X1116058Y-148422D01*
G01X1132466Y-165922D02*
X1123732D01*
Y-148422D01*
X1132466D01*
G01X1128972Y-156880D02*
X1123732D01*
G01X1141232Y-165922D02*
Y-148422D01*
X1146691D01*
X1148437Y-149297D01*
X1149529Y-150464D01*
X1149966Y-152797D01*
X1149529Y-155131D01*
X1148219Y-156589D01*
X1146691Y-157464D01*
X1141232D01*
G01X1146691D02*
X1149966Y-165922D01*
G01X1163099Y-166505D02*
X1162662Y-166214D01*
Y-165630D01*
X1163099Y-165339D01*
X1163536Y-165630D01*
Y-166214D01*
X1163099Y-166505D01*
G01X1299916Y-193422D02*
Y-210922D01*
X1291182D01*
G01X1278049D02*
Y-193422D01*
X1280669Y-196922D01*
G01Y-210922D02*
X1275429D01*
G01X1260549Y-193422D02*
X1262296Y-194005D01*
X1263606Y-195464D01*
X1264479Y-197213D01*
X1265134Y-199547D01*
X1265352Y-202172D01*
X1265134Y-204797D01*
X1264479Y-207131D01*
X1263606Y-208881D01*
X1262296Y-210339D01*
X1260549Y-210922D01*
X1258803Y-210339D01*
X1257492Y-208881D01*
X1256619Y-207131D01*
X1255964Y-204797D01*
X1255746Y-202172D01*
X1255964Y-199547D01*
X1256619Y-197213D01*
X1257492Y-195464D01*
X1258803Y-194005D01*
X1260549Y-193422D01*
G01X1238682Y-148422D02*
Y-165922D01*
X1247416D01*
G01X1264479D02*
Y-154256D01*
G01Y-156297D02*
X1263606Y-155131D01*
X1262295Y-154547D01*
X1260767Y-154256D01*
X1259239Y-154839D01*
X1257929Y-156005D01*
X1257055Y-157755D01*
X1256619Y-160089D01*
X1257055Y-162422D01*
X1257929Y-164172D01*
X1259239Y-165339D01*
X1260767Y-165922D01*
X1262295Y-165630D01*
X1263606Y-164756D01*
X1264479Y-163589D01*
G01X1273464Y-171172D02*
X1274774Y-171755D01*
X1276521Y-171172D01*
X1277612Y-170006D01*
X1278486Y-168547D01*
X1279795Y-163881D01*
X1282634Y-154256D01*
G01X1275647D02*
X1279795Y-163881D01*
G01X1292274Y-158047D02*
X1299261D01*
X1298606Y-156005D01*
X1297514Y-154839D01*
X1295986Y-154256D01*
X1294457Y-154547D01*
X1293147Y-155422D01*
X1292274Y-157464D01*
X1291837Y-159214D01*
Y-160964D01*
X1292274Y-162714D01*
X1293366Y-164464D01*
X1294676Y-165630D01*
X1296204Y-165922D01*
X1297732Y-165339D01*
X1299261Y-163589D01*
G01X1309992Y-165922D02*
Y-154256D01*
G01Y-156589D02*
X1311084Y-155422D01*
X1312176Y-154547D01*
X1313704Y-154256D01*
X1314795Y-154547D01*
X1316106Y-155422D01*
G01X1380796Y-165922D02*
Y-148422D01*
X1385162D01*
X1386909Y-149297D01*
X1388219Y-150464D01*
X1389311Y-152213D01*
X1390184Y-154256D01*
X1390402Y-157172D01*
X1390184Y-160089D01*
X1389311Y-162131D01*
X1388219Y-163881D01*
X1386909Y-165047D01*
X1385162Y-165922D01*
X1380796D01*
G01X1399824Y-158047D02*
X1406811D01*
X1406156Y-156005D01*
X1405064Y-154839D01*
X1403536Y-154256D01*
X1402007Y-154547D01*
X1400697Y-155422D01*
X1399824Y-157464D01*
X1399387Y-159214D01*
Y-160964D01*
X1399824Y-162714D01*
X1400916Y-164464D01*
X1402226Y-165630D01*
X1403754Y-165922D01*
X1405282Y-165339D01*
X1406811Y-163589D01*
G01X1417324Y-163881D02*
X1418416Y-165047D01*
X1419944Y-165922D01*
X1421254D01*
X1422564Y-165339D01*
X1423437Y-164464D01*
X1423874Y-163298D01*
X1423656Y-161547D01*
X1422782Y-160672D01*
X1418852Y-158922D01*
X1417979Y-156880D01*
X1418416Y-155422D01*
X1419289Y-154547D01*
X1420599Y-154256D01*
X1421909Y-154547D01*
X1423219Y-155422D01*
G01X1438099Y-154256D02*
Y-165922D01*
G01Y-149589D02*
X1437662Y-149297D01*
Y-148714D01*
X1438099Y-148422D01*
X1438536Y-148714D01*
Y-149297D01*
X1438099Y-149589D01*
G01X1452542Y-170297D02*
X1454071Y-171464D01*
X1455817Y-171755D01*
X1457345Y-171464D01*
X1458656Y-170006D01*
X1459529Y-167964D01*
Y-154256D01*
G01Y-156589D02*
X1458656Y-155422D01*
X1457345Y-154547D01*
X1455817Y-154256D01*
X1454071Y-154839D01*
X1452979Y-156005D01*
X1452105Y-158047D01*
X1451669Y-160089D01*
X1451887Y-161839D01*
X1452761Y-163881D01*
X1454071Y-165339D01*
X1455817Y-165922D01*
X1457127Y-165630D01*
X1458656Y-164464D01*
X1459529Y-163298D01*
G01X1469387Y-165922D02*
Y-154256D01*
G01Y-157172D02*
X1470261Y-155714D01*
X1471571Y-154547D01*
X1473317Y-154256D01*
X1474845Y-154547D01*
X1476156Y-155714D01*
X1476811Y-157755D01*
Y-165922D01*
G01X1487324Y-158047D02*
X1494311D01*
X1493656Y-156005D01*
X1492564Y-154839D01*
X1491036Y-154256D01*
X1489507Y-154547D01*
X1488197Y-155422D01*
X1487324Y-157464D01*
X1486887Y-159214D01*
Y-160964D01*
X1487324Y-162714D01*
X1488416Y-164464D01*
X1489726Y-165630D01*
X1491254Y-165922D01*
X1492782Y-165339D01*
X1494311Y-163589D01*
G01X1505042Y-165922D02*
Y-154256D01*
G01Y-156589D02*
X1506134Y-155422D01*
X1507226Y-154547D01*
X1508754Y-154256D01*
X1509845Y-154547D01*
X1511156Y-155422D01*
G01X1426729Y-193422D02*
X1431969D01*
G01X1429349D02*
Y-210922D01*
G01X1426729D02*
X1431969D01*
G01X1441390Y-193422D02*
X1446849Y-210922D01*
X1452308Y-193422D01*
G01X1464349Y-210922D02*
Y-203047D01*
X1459982Y-193422D01*
G01X1468716D02*
X1464349Y-203047D01*
G01X1551799Y-193422D02*
X1550052Y-194005D01*
X1548742Y-195464D01*
X1547869Y-197213D01*
X1547214Y-199547D01*
X1546996Y-202172D01*
X1547214Y-204797D01*
X1547869Y-207131D01*
X1548742Y-208881D01*
X1550052Y-210339D01*
X1551799Y-210922D01*
X1553545Y-210339D01*
X1554856Y-208881D01*
X1555729Y-207131D01*
X1556384Y-204797D01*
X1556602Y-202172D01*
X1556384Y-199547D01*
X1555729Y-197213D01*
X1554856Y-195464D01*
X1553545Y-194005D01*
X1551799Y-193422D01*
G01X1565151Y-196339D02*
X1566461Y-194589D01*
X1567989Y-193714D01*
X1569736Y-193422D01*
X1571919Y-194005D01*
X1573447Y-195464D01*
X1573884Y-197213D01*
X1573666Y-198964D01*
X1572792Y-200422D01*
X1568426Y-203339D01*
X1566461Y-205380D01*
X1565151Y-208298D01*
X1564714Y-210922D01*
X1573884D01*
G01X1582869Y-211505D02*
X1590729Y-193422D01*
G01X1604299Y-210922D02*
Y-193422D01*
X1601679Y-196922D01*
G01Y-210922D02*
X1606919D01*
G01X1621799Y-193422D02*
X1620052Y-194005D01*
X1618742Y-195464D01*
X1617869Y-197213D01*
X1617214Y-199547D01*
X1616996Y-202172D01*
X1617214Y-204797D01*
X1617869Y-207131D01*
X1618742Y-208881D01*
X1620052Y-210339D01*
X1621799Y-210922D01*
X1623545Y-210339D01*
X1624856Y-208881D01*
X1625729Y-207131D01*
X1626384Y-204797D01*
X1626602Y-202172D01*
X1626384Y-199547D01*
X1625729Y-197213D01*
X1624856Y-195464D01*
X1623545Y-194005D01*
X1621799Y-193422D01*
G01X1635369Y-211505D02*
X1643229Y-193422D01*
G01X1652651Y-196339D02*
X1653961Y-194589D01*
X1655489Y-193714D01*
X1657236Y-193422D01*
X1659419Y-194005D01*
X1660947Y-195464D01*
X1661384Y-197213D01*
X1661166Y-198964D01*
X1660292Y-200422D01*
X1655926Y-203339D01*
X1653961Y-205380D01*
X1652651Y-208298D01*
X1652214Y-210922D01*
X1661384D01*
G01X1674299Y-193422D02*
X1672552Y-194005D01*
X1671242Y-195464D01*
X1670369Y-197213D01*
X1669714Y-199547D01*
X1669496Y-202172D01*
X1669714Y-204797D01*
X1670369Y-207131D01*
X1671242Y-208881D01*
X1672552Y-210339D01*
X1674299Y-210922D01*
X1676045Y-210339D01*
X1677356Y-208881D01*
X1678229Y-207131D01*
X1678884Y-204797D01*
X1679102Y-202172D01*
X1678884Y-199547D01*
X1678229Y-197213D01*
X1677356Y-195464D01*
X1676045Y-194005D01*
X1674299Y-193422D01*
G01X1691799Y-210922D02*
Y-193422D01*
X1689179Y-196922D01*
G01Y-210922D02*
X1694419D01*
G01X1708862D02*
X1709299Y-207131D01*
X1709954Y-203922D01*
X1710827Y-201005D01*
X1711919Y-197797D01*
X1713666Y-193422D01*
X1704932D01*
G01X1599496Y-165922D02*
Y-148422D01*
X1603862D01*
X1605609Y-149297D01*
X1606919Y-150464D01*
X1608011Y-152213D01*
X1608884Y-154256D01*
X1609102Y-157172D01*
X1608884Y-160089D01*
X1608011Y-162131D01*
X1606919Y-163881D01*
X1605609Y-165047D01*
X1603862Y-165922D01*
X1599496D01*
G01X1625729D02*
Y-154256D01*
G01Y-156297D02*
X1624856Y-155131D01*
X1623545Y-154547D01*
X1622017Y-154256D01*
X1620489Y-154839D01*
X1619179Y-156005D01*
X1618305Y-157755D01*
X1617869Y-160089D01*
X1618305Y-162422D01*
X1619179Y-164172D01*
X1620489Y-165339D01*
X1622017Y-165922D01*
X1623545Y-165630D01*
X1624856Y-164756D01*
X1625729Y-163589D01*
G01X1639299Y-148422D02*
Y-165922D01*
G01X1636242Y-154256D02*
X1642356D01*
G01X1653524Y-158047D02*
X1660511D01*
X1659856Y-156005D01*
X1658764Y-154839D01*
X1657236Y-154256D01*
X1655707Y-154547D01*
X1654397Y-155422D01*
X1653524Y-157464D01*
X1653087Y-159214D01*
Y-160964D01*
X1653524Y-162714D01*
X1654616Y-164464D01*
X1655926Y-165630D01*
X1657454Y-165922D01*
X1658982Y-165339D01*
X1660511Y-163589D01*
G54D21*
X1694000Y580079D03*
X1691047Y600551D03*
Y615512D03*
G54D12*
G01X38645Y184032D02*
X44291Y178386D01*
G01X36589D02*
X44291D01*
G01X-7615Y172740D02*
X-1969Y178386D01*
G01D02*
X3677Y184032D01*
G01X-7615D02*
X-1969Y178386D01*
G01D02*
X3677Y172740D01*
G01X12582D02*
X18228Y178386D01*
G01D02*
X23874Y184032D01*
G01X12582D02*
X18228Y178386D01*
G01D02*
X23874Y172740D01*
G01X97200Y265000D02*
X84235Y277965D01*
X66941D01*
X64941Y279965D01*
Y283559D01*
X62300Y286200D01*
X61900D01*
G01X99758Y240300D02*
X106464Y233594D01*
Y230764D01*
X99500Y223800D01*
G01X99758Y240300D02*
X105400Y245942D01*
Y262880D01*
X103280Y265000D01*
X97200D01*
G01X116310Y222940D02*
X115608Y222238D01*
Y219996D01*
X117013Y218591D01*
X121409D01*
X124800Y215200D01*
X128800D01*
X130324Y213676D01*
Y212033D01*
G01Y197684D02*
Y212033D01*
G01X116000Y254643D02*
X115608Y254251D01*
Y251996D01*
X117453Y250151D01*
X122167D01*
X124102Y248216D01*
X127804D01*
X130324Y245696D01*
Y244033D01*
G01X116000Y286643D02*
X115608Y286251D01*
Y283996D01*
X117605Y281999D01*
X122785D01*
X124772Y280012D01*
X127912D01*
X130324Y277600D01*
Y276033D01*
G01Y308033D02*
Y310204D01*
X128324Y312204D01*
X124490D01*
X122103Y314591D01*
X117013D01*
X115608Y315996D01*
Y318251D01*
X116000Y318643D01*
G01X129700Y340152D02*
X127048Y342804D01*
X125773D01*
X121986Y346591D01*
X117013D01*
X115608Y347996D01*
Y350251D01*
X116000Y350643D01*
G01Y382643D02*
Y378901D01*
X119777Y375124D01*
Y371040D01*
X121217Y369600D01*
X124299D01*
X124739Y369160D01*
X128585D01*
X130585Y371160D01*
Y372085D01*
G01X174750Y389308D02*
Y390444D01*
X164294Y400900D01*
X152300D01*
X146400Y406800D01*
X133000D01*
X129880Y403680D01*
Y398780D01*
X133530Y395130D01*
Y378052D01*
X131530Y376052D01*
X123809D01*
X122473Y374716D01*
G01X430749Y-124922D02*
G02I-12000J0D01*
G01X425599D02*
G02I-6850J0D01*
G01X434749D02*
X402749D01*
G01X434749Y-140922D02*
Y-220922D01*
G01D02*
X1729349D01*
G01X434749Y-176422D02*
X1729349D01*
G01X418749Y-140922D02*
Y-108922D01*
G01X434749Y-140922D02*
X1729349D01*
G01X941849D02*
Y-220922D01*
G01X1079349Y-140922D02*
Y-220922D01*
G01X1194349Y-140922D02*
Y-220922D01*
G01X1361849Y-140922D02*
Y-220922D01*
G01X1388300Y346200D02*
X1371600Y362900D01*
G01D02*
Y368700D01*
G01X1531849Y-140922D02*
Y-220922D01*
G01X1593756Y129048D02*
Y129941D01*
X1595262Y131447D01*
X1597653D01*
X1600041Y129059D01*
X1608262D01*
X1609591Y130388D01*
X1624143D01*
X1629500Y125031D01*
Y124000D01*
X1632639Y120861D01*
Y118640D01*
G01X1729349Y-140922D02*
Y-220922D01*
G01X1757349Y-124922D02*
G02I-12000J0D01*
G01X1752199D02*
G02I-6850J0D01*
G01X1745349Y-140922D02*
Y-108922D01*
G01X1761349Y-124922D02*
X1729349D01*
G01X1714114Y148950D02*
Y149436D01*
X1716022Y151344D01*
X1743065D01*
X1748600Y145809D01*
Y122400D01*
X1749416Y121584D01*
X1749417D01*
X1750819Y120182D01*
Y109819D01*
X1745500Y104500D01*
G01X1877103Y60791D02*
X1877983D01*
X1879908Y62716D01*
Y64361D01*
X1893597Y78050D01*
X1900296D01*
X1900956Y77390D01*
X1906496D01*
X1911115Y82009D01*
Y116915D01*
X1915300Y121100D01*
Y142795D01*
X1911785Y146310D01*
X1904649D01*
X1900790Y150169D01*
Y160524D01*
X1898300Y163014D01*
Y179794D01*
X1907474Y188968D01*
Y199627D01*
X1906517Y200584D01*
Y203692D01*
X1906642Y203817D01*
Y213868D01*
X1910123Y217349D01*
G01X1886200Y161000D02*
Y162400D01*
X1889100Y165300D01*
Y174600D01*
X1887563Y176137D01*
X1883930D01*
G01X1844018Y586482D02*
X1849902Y580598D01*
X1863602D01*
X1870100Y574100D01*
Y561150D01*
X-18000Y247400D03*
X-15000D03*
X-18000Y262700D03*
X-15000D03*
X-19802Y476738D03*
X-19783Y481286D03*
X19964Y18793D03*
X16550Y18300D03*
X2871Y22791D03*
X-10850Y30800D03*
X2934Y26933D03*
X-8610Y59810D03*
X-1750Y43320D03*
X-1920Y47290D03*
X8700Y49700D03*
X-3560Y34620D03*
X-13610Y64360D03*
X-9987Y50899D03*
X-7050Y50900D03*
X-10470Y64450D03*
X-8370Y62600D03*
X-6010Y61030D03*
X-9390Y67410D03*
X35650Y91150D03*
X34000Y93350D03*
X5500Y77444D03*
X5600Y80444D03*
X11625Y81267D03*
X9125D03*
X11200Y49600D03*
X14010Y49570D03*
X11925Y74867D03*
X11864Y71294D03*
X11539Y39927D03*
X11500Y43400D03*
X11539Y47127D03*
X11864Y78494D03*
X47309Y154356D03*
X5120Y276058D03*
X2269Y273532D03*
X19904Y254162D03*
X41000Y265350D03*
X37000D03*
X44310Y268160D03*
X33490Y267900D03*
X3806Y302347D03*
X7995Y285385D03*
X6806Y302347D03*
X37550Y425400D03*
X40965Y429434D03*
X10365Y461602D03*
X46100Y416271D03*
Y413520D03*
X-5690Y467840D03*
X-4350Y482100D03*
X2589Y481983D03*
X-900Y482300D03*
X-9600Y526100D03*
X46507Y523953D03*
X6748Y517021D03*
X3354Y517143D03*
X5689Y481983D03*
X-9287Y531604D03*
X-3100Y533991D03*
X-9283Y571324D03*
X-6566Y568363D03*
X-9291Y535201D03*
X67564Y-20745D03*
X65164Y-19456D03*
X64159Y11303D03*
X63683Y-12866D03*
X66061Y-13689D03*
X87091Y-16391D03*
X93500Y-18000D03*
X79500Y72500D03*
X68725Y90900D03*
X63725D03*
X105898Y55194D03*
X63098Y151473D03*
X68098D03*
X51309Y154356D03*
X65384Y109750D03*
Y104750D03*
X65405Y118730D03*
X60831Y144750D03*
X65687Y132750D03*
X60831Y130750D03*
X60700Y116750D03*
X60801Y97750D03*
X60831Y139750D03*
X65687Y137750D03*
X60831Y125750D03*
X65405Y123730D03*
X60700Y111750D03*
X60801Y102750D03*
X102507Y211047D03*
X107700Y211040D03*
X90831Y184982D03*
X61356Y181000D03*
X61256Y186000D03*
X99500Y223800D03*
X57500Y254100D03*
X99758Y240300D03*
X97200Y265000D03*
X94360Y335210D03*
X61900Y286200D03*
X72100Y321800D03*
X82500Y341400D03*
X56300Y338500D03*
X87400Y337200D03*
X68418Y336150D03*
X103500Y304700D03*
Y308500D03*
X102322Y295478D03*
X104600Y316602D03*
X103200Y335190D03*
Y330190D03*
X48550Y301650D03*
X90518Y388828D03*
X74800Y383114D03*
X85609Y385234D03*
X49100Y354500D03*
X54662Y416478D03*
X51645Y416281D03*
X65450Y475610D03*
X67477Y477940D03*
X66750Y521900D03*
Y519400D03*
X64503Y521054D03*
X64380Y523606D03*
Y526202D03*
X64600Y515600D03*
X66750Y516900D03*
X64600Y518100D03*
X66840Y526800D03*
Y524300D03*
X47369Y527005D03*
X88855Y522359D03*
X86100Y505200D03*
X66016Y468350D03*
X89497Y479201D03*
X91650Y522000D03*
X71050Y478670D03*
X92326Y480398D03*
X62500Y535500D03*
X91952Y620900D03*
X114000Y3500D03*
X114100Y6120D03*
X109057Y92774D03*
X112007Y93139D03*
X116200Y70387D03*
X130324Y212033D03*
X124340Y197750D03*
X117600Y193805D03*
X141263Y215216D03*
X137763Y217716D03*
X141263D03*
X137763Y215216D03*
X169150Y223600D03*
Y227600D03*
X116310Y222940D03*
X130324Y244033D03*
Y276033D03*
X116000Y254643D03*
X141263Y234216D03*
X141200Y229600D03*
X141211Y225615D03*
X141300Y221700D03*
X139763Y231700D03*
Y227600D03*
Y223700D03*
X139582Y219800D03*
X141263Y249716D03*
Y247216D03*
X137763D03*
Y249716D03*
X141300Y253700D03*
X139631Y251900D03*
X137763Y279216D03*
X141263Y266216D03*
X139763Y255700D03*
Y259600D03*
X139800Y263700D03*
X141313Y257533D03*
X141263Y279216D03*
X141200Y261600D03*
X137300Y337200D03*
X130324Y308033D03*
X129700Y340152D03*
X116000Y286643D03*
X117063Y289016D03*
X116000Y318643D03*
X141263Y311216D03*
X137763D03*
X141263Y281716D03*
X139730Y284200D03*
X139763Y288200D03*
Y292000D03*
Y296000D03*
X141200Y286100D03*
X141261Y290076D03*
X141300Y294000D03*
X141263Y298216D03*
X137763Y281716D03*
X141211Y325515D03*
X141263Y330216D03*
X139763Y327800D03*
X141300Y317500D03*
Y321500D03*
X139582Y315800D03*
X139763Y319400D03*
X141263Y313716D03*
X137763D03*
X139763Y323600D03*
X130585Y372085D03*
X116000Y382643D03*
X122473Y374716D03*
X116000Y350643D03*
X118008Y348991D03*
X141289Y349488D03*
X141300Y353300D03*
X141200Y357200D03*
X137763Y345716D03*
X141263D03*
Y343216D03*
X137763D03*
X141263Y362216D03*
X139582Y347800D03*
X139763Y351400D03*
Y355200D03*
Y359500D03*
X141300Y381800D03*
X139763Y384000D03*
X141263Y394216D03*
Y390416D03*
X141261Y385876D03*
X139736Y392300D03*
X137763Y375216D03*
X141263D03*
Y377716D03*
X137763D03*
X139631Y379900D03*
X139900Y388000D03*
X109500Y370000D03*
X157862Y416012D03*
X148666Y417397D03*
X148300Y414600D03*
X148409Y422239D03*
X150650Y409860D03*
X289124Y550714D03*
X284024Y553100D03*
X273910Y550914D03*
X270864Y555957D03*
X280203Y550914D03*
X277557Y555957D03*
X289124Y553314D03*
X284024Y550500D03*
X270864Y566699D03*
X273824Y572500D03*
X277557Y566699D03*
X280203Y572500D03*
X289124Y569340D03*
X284024Y572199D03*
X289124Y571949D03*
X284050Y569550D03*
X311021Y28014D03*
X317714D03*
X327754D03*
X347833Y28022D03*
X337793Y28014D03*
X311021Y65814D03*
X321061Y35957D03*
X314368D03*
Y46914D03*
X311021Y54857D03*
X317714D03*
X321061Y46914D03*
X331100D03*
Y35957D03*
X327754Y54857D03*
X314368Y73757D03*
Y87392D03*
X311021Y89964D03*
X321061Y92757D03*
X327754Y87392D03*
X324407Y89964D03*
X341140Y35957D03*
X337793Y54857D03*
X351179Y46922D03*
X347833Y54857D03*
X341140Y46922D03*
X351179Y35957D03*
X354415Y87392D03*
X351179Y89964D03*
X347833Y87392D03*
X344486Y84714D03*
Y89964D03*
X337793Y84599D03*
X341140Y92757D03*
X354415D03*
X326592Y105600D03*
X313637Y105725D03*
X338838Y218860D03*
X345598Y214960D03*
X352357D03*
X345598Y203260D03*
X355737Y205210D03*
X342218Y248109D03*
X348978Y252009D03*
Y255909D03*
X345598Y261760D03*
X348978Y259809D03*
X345598Y257860D03*
X352357D03*
X342218Y252009D03*
X338838Y250060D03*
X342218Y232509D03*
X355737Y244209D03*
X348978D03*
X345598Y226660D03*
X352357D03*
X348978Y232509D03*
X355737D03*
X335458Y322209D03*
X328698Y314409D03*
X321938D03*
X332078Y328060D03*
X328698Y322209D03*
Y318309D03*
X332078Y324160D03*
Y320260D03*
Y316360D03*
X325318Y320260D03*
X305039D03*
X321938Y318309D03*
X315178D03*
X318558Y316360D03*
X301659Y322209D03*
X325318Y316360D03*
X305039Y324160D03*
X311798Y320260D03*
X308418Y322209D03*
X301659Y326110D03*
X335458Y314409D03*
Y326110D03*
Y318309D03*
X338838Y320260D03*
Y324160D03*
Y328060D03*
X345598Y370959D03*
X355737Y353409D03*
X348978D03*
X342218Y365109D03*
Y353409D03*
X338838Y367060D03*
X348978Y365109D03*
X355737D03*
X352357Y370959D03*
X338838Y382660D03*
X345598D03*
X352357D03*
X348978Y392410D03*
X355737D03*
X321061Y518157D03*
X341140D03*
X337793Y509999D03*
X344486Y515364D03*
Y510114D03*
X347833Y512792D03*
X351179Y515364D03*
X354307Y512792D03*
X354526Y518157D03*
X324407Y515364D03*
X297635Y550914D03*
X294289Y555957D03*
X304328Y550914D03*
X300982Y555957D03*
X294289Y566699D03*
X297635Y572900D03*
X300982Y566699D03*
X304328Y572900D03*
X357872Y28014D03*
X367911D03*
X380600Y37400D03*
X380980Y60210D03*
X380892Y63200D03*
X367911Y46914D03*
Y54842D03*
Y35942D03*
X358619Y36031D03*
X358618Y54842D03*
X357872Y65736D03*
X366992Y65950D03*
X357872Y46914D03*
X357965Y92500D03*
X367911Y87500D03*
X368311Y92500D03*
X367742Y73450D03*
X357872Y87500D03*
X358491Y73479D03*
X384992Y81600D03*
X375337Y86377D03*
Y83877D03*
X408069Y35942D03*
X401376Y54842D03*
X408069Y46907D03*
X398029Y65807D03*
X408069D03*
X398029Y35942D03*
Y46907D03*
X411416Y54857D03*
X404722Y89964D03*
X398029D03*
X414761Y87392D03*
X408068Y92757D03*
X408126Y103116D03*
X401375D03*
X414819D03*
X357987Y193507D03*
X378267D03*
X386157Y207159D03*
X382777Y201309D03*
X365877Y214960D03*
X372637D03*
X379397D03*
X359117D03*
X365877Y203260D03*
X376017Y205211D03*
X362497Y205210D03*
X386157Y214960D03*
X404392Y199100D03*
X392898Y195041D03*
X392916Y214960D03*
Y203260D03*
X396296Y197359D03*
X399676Y203260D03*
Y214960D03*
X386157Y226660D03*
X389537Y232509D03*
X369257Y244209D03*
X362497D03*
X372637Y226660D03*
X365877D03*
X369257Y232509D03*
X362497D03*
X379397Y226660D03*
X382777Y232509D03*
X376017D03*
X359117Y226660D03*
X390894Y264899D03*
X407706Y240309D03*
Y232509D03*
X392916Y226660D03*
X396296Y232509D03*
X399676Y226660D03*
X397394Y264899D03*
X400394D03*
X393894D03*
X407448Y338641D03*
X416448D03*
X413948D03*
X410948D03*
X403648Y338341D03*
X401148D03*
X398148D03*
X394648D03*
X389537Y357309D03*
X396296D03*
X379397Y370959D03*
X372637D03*
X365877D03*
X359117D03*
X386157D03*
X362497Y353409D03*
X376017D03*
X369257D03*
X389537Y365109D03*
X382777D03*
X369257D03*
X362497D03*
X376017D03*
X390657Y394359D03*
X369257Y392410D03*
X362497D03*
X379397Y382660D03*
X372637D03*
X365877D03*
X359117D03*
X379397Y390460D03*
X376017Y392410D03*
X386157Y382660D03*
X392916Y355360D03*
Y370959D03*
X399676D03*
X396296Y365109D03*
X392916Y382660D03*
Y390460D03*
X399676Y382660D03*
X403056Y392410D03*
X375192Y516356D03*
Y518856D03*
X404722Y515364D03*
X394682Y512792D03*
X408068Y518157D03*
X414761Y512792D03*
X398029Y515364D03*
X376792Y543700D03*
X394595Y537058D03*
X398029Y529007D03*
X408069D03*
X386970Y623539D03*
X418108Y28007D03*
X441533D03*
X434842Y54857D03*
X441533Y54842D03*
X424801Y46907D03*
X431494D03*
X428149Y54857D03*
X441533Y46907D03*
X431494Y65807D03*
X424801D03*
X418108Y54842D03*
X431494Y35942D03*
X441533D03*
X424801D03*
X418108D03*
Y46907D03*
X421512Y103116D03*
X427696Y103100D03*
X447148Y278841D03*
X449848D03*
X450800Y275600D03*
X477792Y276646D03*
Y280547D03*
X453400Y275600D03*
X474413Y274696D03*
X469913Y278596D03*
X447800Y335900D03*
X426494Y338361D03*
X430089Y338428D03*
X419400Y338600D03*
X449500Y309800D03*
X451648Y308341D03*
X447000Y309800D03*
X450700Y335550D03*
X453200D03*
X454148Y310341D03*
Y307841D03*
X469913Y298096D03*
Y301996D03*
X477792Y284447D03*
Y296147D03*
Y300047D03*
Y292247D03*
X469913Y282496D03*
Y294196D03*
Y290296D03*
X474413Y329296D03*
X468783Y332897D03*
X474413Y333196D03*
Y325396D03*
X477792Y323446D03*
X435192Y499400D03*
X421454Y612560D03*
X518352Y210345D03*
X528491Y212296D03*
X494692D03*
X501452Y216196D03*
X504832Y218147D03*
X511592Y214247D03*
X514972Y216196D03*
X518352Y214247D03*
X531871D03*
X514972Y212296D03*
Y208397D03*
X521731Y212296D03*
X525111Y210346D03*
X504832Y214247D03*
X498072D03*
X508212Y216196D03*
X535251Y212296D03*
X498072Y218147D03*
X494692Y216196D03*
X525111Y214247D03*
X531871Y210346D03*
X535251Y216196D03*
X538631Y218147D03*
X535251Y208397D03*
X525111Y249347D03*
X504832D03*
X538631Y276646D03*
Y245447D03*
X535251Y274696D03*
X538631Y268847D03*
Y264947D03*
X531871Y245447D03*
X535251Y262996D03*
X538631Y253247D03*
X531871Y280547D03*
X538631Y241547D03*
X531871Y272747D03*
X494692Y220096D03*
X535251D03*
X504832Y222047D03*
X538631Y272747D03*
X494692Y274696D03*
X484552Y280547D03*
X521731Y243496D03*
X525111Y272747D03*
X518352D03*
X510401Y260511D03*
X498072Y264947D03*
X535251Y270796D03*
X538631Y261047D03*
X501452Y220096D03*
X514972Y243496D03*
X508212Y247396D03*
X538631Y280547D03*
X535251Y243496D03*
Y278596D03*
X528491Y282496D03*
X535251Y286396D03*
Y282496D03*
X481172Y298096D03*
Y305896D03*
X487932Y290296D03*
X484552Y288347D03*
Y296147D03*
X481172Y294196D03*
X504832Y327347D03*
X531871Y284447D03*
X518352Y401447D03*
X504832Y385847D03*
Y393647D03*
X535251Y395597D03*
Y387796D03*
Y391696D03*
X531871Y397546D03*
X528491Y399496D03*
X521731Y403396D03*
X538631Y385847D03*
Y389747D03*
X531871Y393647D03*
X535251Y399496D03*
X528491Y395597D03*
X525111Y401447D03*
X518352Y374146D03*
X521731Y379996D03*
X514972Y383896D03*
X511592Y381947D03*
X508212Y391696D03*
X504832Y389747D03*
X508212Y395597D03*
X518352Y378047D03*
Y381947D03*
Y385847D03*
X511592D03*
X501452Y387796D03*
X511592Y393647D03*
X504832Y397546D03*
X518352Y405347D03*
X525111D03*
X538355Y553100D03*
X506644Y553314D03*
X538355Y550500D03*
X501544D03*
X506644Y550714D03*
X501544Y553100D03*
X528241Y550914D03*
X525195Y555957D03*
X534534Y550914D03*
X531888Y555957D03*
X515155Y550914D03*
X511809Y555957D03*
X491430Y550914D03*
X488384Y555957D03*
X521848Y550914D03*
X518502Y555957D03*
X497723Y550914D03*
X495077Y555957D03*
X506644Y569340D03*
X538355Y572199D03*
X501544D03*
X525195Y566699D03*
X528155Y572500D03*
X531888Y566699D03*
X534534Y572500D03*
X511809Y566699D03*
X515155Y572900D03*
X488384Y566699D03*
X491344Y572500D03*
X518502Y566699D03*
X521848Y572900D03*
X495077Y566699D03*
X497723Y572500D03*
X538381Y569550D03*
X506644Y571949D03*
X501570Y569550D03*
X545391Y214247D03*
Y218147D03*
X548771Y216196D03*
X542011Y212296D03*
Y216196D03*
X548771Y220096D03*
X555531D03*
Y227896D03*
X542011Y278596D03*
Y262996D03*
Y259096D03*
X545391Y257147D03*
Y249347D03*
X548771Y223996D03*
X542011Y243496D03*
X552151Y222047D03*
X542011Y251296D03*
X545391Y245447D03*
X548771Y259096D03*
X542011Y220096D03*
X548771Y247396D03*
X545391Y241547D03*
X555531Y223996D03*
X545391Y261047D03*
Y253247D03*
X542011Y255196D03*
Y266896D03*
Y290296D03*
Y282496D03*
X545391Y284447D03*
X542011Y286396D03*
Y383896D03*
X543455Y553314D03*
Y550714D03*
X551966Y550914D03*
X548620Y555957D03*
X558659Y550914D03*
X555313Y555957D03*
X558659Y572900D03*
X543455Y571949D03*
X548620Y566699D03*
X551966Y572900D03*
X555313Y566699D03*
X543455Y569340D03*
X623000Y-3000D03*
X624770Y-640D03*
X662700Y-17900D03*
X654016Y31150D03*
X618800Y100100D03*
X633800Y119000D03*
X609482Y124568D03*
X626040Y98281D03*
X621165Y256075D03*
X620850Y253416D03*
X651235Y249165D03*
X657700Y250172D03*
X660588Y250312D03*
X624500Y240500D03*
X639622Y290210D03*
X643823Y289650D03*
X623600Y521700D03*
X646200Y499700D03*
X648025Y501575D03*
X609470Y484060D03*
X611250Y476750D03*
X655100Y614100D03*
Y611500D03*
X627705Y611973D03*
X629977Y613024D03*
X718975Y-4451D03*
X701100Y8100D03*
X704450Y4950D03*
X710800Y7100D03*
X694600Y85000D03*
X707329Y88955D03*
X705972Y86660D03*
X703845Y88830D03*
X716268Y88683D03*
X716894Y84047D03*
X713115Y88629D03*
X701500Y85500D03*
X698300Y85300D03*
X709560Y84648D03*
X720572Y88700D03*
X670503Y115884D03*
X715100Y213344D03*
X710500Y224500D03*
X713800Y221544D03*
X713700Y224144D03*
X667700Y275600D03*
X674469Y287375D03*
X704404Y310875D03*
X697521Y320500D03*
X697120Y305349D03*
X688924Y288147D03*
X704404Y315875D03*
X697521Y325500D03*
X697352Y335500D03*
Y330500D03*
X697120Y300349D03*
X669194Y351206D03*
X674194D03*
X679194D03*
X684194D03*
X718546Y500283D03*
X677800Y485600D03*
X680300Y485700D03*
X691000Y498200D03*
X688202Y497736D03*
X679049Y503746D03*
X708700Y499400D03*
X713200Y505500D03*
X715900Y505650D03*
X715009Y512917D03*
X721414Y508986D03*
X720565Y511338D03*
X721894Y501346D03*
X675080Y485570D03*
X696000Y496800D03*
X702100Y568800D03*
X702000Y571400D03*
X665000Y598500D03*
X729600Y17991D03*
X734256D03*
X733740Y95230D03*
X731910Y92790D03*
X766824Y85943D03*
X763930Y85100D03*
X730038Y88408D03*
X732599D03*
X735241Y88329D03*
X763350Y81220D03*
X732734Y82626D03*
X746600Y103900D03*
X741700Y102000D03*
X752900Y101000D03*
X744200Y102800D03*
X756800Y99400D03*
Y102000D03*
X787371Y215216D03*
Y217716D03*
X737837Y222364D03*
Y224964D03*
X740300Y228100D03*
X742937Y221174D03*
Y223774D03*
X740437Y224964D03*
Y222364D03*
X775200Y230500D03*
X775171Y227116D03*
Y234316D03*
X787371Y247216D03*
Y249716D03*
X775271Y262716D03*
X775171Y259116D03*
Y266316D03*
X787371Y279216D03*
X749126Y220843D03*
X742897Y226773D03*
X775271Y294716D03*
X775171Y291116D03*
Y298316D03*
X787371Y281716D03*
Y311216D03*
X775271Y326716D03*
X775171Y323116D03*
Y330316D03*
X787371Y313716D03*
X775171Y362316D03*
X775271Y358716D03*
X775171Y355116D03*
X787371Y343216D03*
Y345716D03*
X787321Y374916D03*
Y377316D03*
X775121Y394316D03*
X775221Y390716D03*
X775121Y387116D03*
X752900Y521121D03*
Y518621D03*
X739307Y598850D03*
X726857Y610871D03*
X729616Y610863D03*
X732500Y611000D03*
X790871Y215216D03*
Y217716D03*
X789500Y231800D03*
X790900Y234000D03*
Y229700D03*
X790846Y225774D03*
X790882Y221723D03*
X790871Y247216D03*
Y249716D03*
X789471Y227742D03*
X789576Y223737D03*
X789554Y219723D03*
X790900Y253900D03*
X789432Y252000D03*
X790871Y266216D03*
X789432Y255800D03*
X790867Y257724D03*
X789432Y259800D03*
X789500Y263900D03*
X790885Y261711D03*
X790871Y279216D03*
Y311216D03*
X789432Y284200D03*
Y288300D03*
Y292400D03*
X789400Y296200D03*
X790871Y298216D03*
X790937Y294270D03*
X790900Y290300D03*
Y286200D03*
X790871Y281716D03*
Y313716D03*
X789432Y319900D03*
Y323900D03*
X790900Y322000D03*
Y326000D03*
X790871Y330216D03*
X789500Y328000D03*
X789478Y315671D03*
X790800Y317700D03*
X824000Y402863D03*
X827800D03*
X832300D03*
X789432Y348100D03*
Y352100D03*
X789597Y356105D03*
X789500Y360200D03*
X790900Y358200D03*
X790835Y354048D03*
X790867Y350024D03*
X790871Y345716D03*
Y343216D03*
Y362216D03*
X790821Y374916D03*
X790900Y389300D03*
X789500Y391300D03*
X790900Y393400D03*
Y381100D03*
X789582Y383200D03*
X790900Y385300D03*
X789500Y387300D03*
X790821Y377316D03*
X789282Y379200D03*
X851430Y367468D03*
X970669Y92757D03*
X971546Y314409D03*
Y318309D03*
X964786D03*
X951267Y322209D03*
X954647Y324160D03*
X961406Y320260D03*
X954647D03*
X958026Y322209D03*
X951267Y326110D03*
X968166Y316360D03*
X970669Y518157D03*
X947243Y550914D03*
X923518D03*
X929811D03*
X938732Y553314D03*
X933632Y550500D03*
X938732Y550714D03*
X933632Y553100D03*
X943897Y566699D03*
X947243Y572900D03*
X943897Y555957D03*
X920472Y566699D03*
X923432Y572500D03*
X920472Y555957D03*
X927165Y566699D03*
X929811Y572500D03*
X927165Y555957D03*
X938732Y571949D03*
X933658Y569550D03*
X953936Y550914D03*
Y572900D03*
X950590Y555957D03*
X938732Y569340D03*
X933632Y572199D03*
X950590Y566699D03*
X1028639Y-6615D03*
X990748Y92757D03*
X987401Y84599D03*
X994094Y89964D03*
Y84714D03*
X997441Y87392D03*
X1000787Y89964D03*
X1004023Y87392D03*
Y92757D03*
X974015Y89964D03*
X977362Y87392D03*
X988446Y218860D03*
X995206Y214960D03*
X1001965D03*
X1015485D03*
X1022245D03*
X1029005D03*
X1008725D03*
X998586Y252009D03*
Y255909D03*
X995206Y257860D03*
X998586Y259809D03*
X995206Y261760D03*
X1001965Y257860D03*
X998586Y244209D03*
Y232509D03*
X991826D03*
X995206Y226660D03*
X1032385Y232509D03*
X1018865Y244209D03*
X1012105D03*
X1018865Y232509D03*
X1015485Y226660D03*
X1022245D03*
X1012105Y232509D03*
X1025625D03*
X1029005Y226660D03*
X1005345Y244209D03*
X1008725Y226660D03*
X1005345Y232509D03*
X1001965Y226660D03*
X998586Y337809D03*
Y341709D03*
X985066Y314409D03*
X978306D03*
Y318309D03*
Y322209D03*
X981686Y320260D03*
X974926Y316360D03*
Y320260D03*
X985066Y326110D03*
X981686Y328060D03*
X988446D03*
Y324160D03*
X985066Y318309D03*
Y322209D03*
X988446Y320260D03*
X981686Y324160D03*
Y316360D03*
X1016399Y324304D03*
X1022393Y326580D03*
X1024893D03*
X1017393D03*
X1028393Y329580D03*
X1019893Y326580D03*
X1027393D03*
X1025755Y328951D03*
X998586Y345609D03*
X988446Y367060D03*
X998586Y365109D03*
Y353409D03*
X991826Y365109D03*
X995206Y370959D03*
X998586Y392410D03*
X988446Y382660D03*
X995206D03*
X1005345Y365109D03*
X1008725Y370959D03*
X1001965D03*
X1005345Y353409D03*
X1018865Y365109D03*
X1012105D03*
X1025625D03*
X1022245Y370959D03*
X1015485D03*
X1018865Y353409D03*
X1012105D03*
X1025625D03*
X1029005Y370959D03*
X1032385Y365109D03*
X1008725Y382660D03*
X1001965D03*
X1005345Y392410D03*
X1029005Y390460D03*
X1025625Y392410D03*
X1022245Y382660D03*
X1015485D03*
X1012105Y392410D03*
X1018865D03*
X1029005Y382660D03*
X974015Y515364D03*
X990748Y518157D03*
X994094Y515364D03*
X997441Y512792D03*
X1000787Y515364D03*
X1003915Y512792D03*
X1004134Y518157D03*
X987401Y509999D03*
X994094Y510114D03*
X1057677Y65807D03*
X1047637D03*
X1057676Y92757D03*
X1064369Y87392D03*
X1047637Y89964D03*
X1054330D03*
X1074409Y65807D03*
X1081102D03*
X1071120Y103116D03*
X1057734D03*
X1064427D03*
X1050983D03*
X1077304Y103100D03*
X1042524Y226660D03*
X1039145Y232509D03*
X1035765Y226660D03*
X1057314Y240309D03*
X1049284Y226660D03*
X1045904Y232509D03*
X1057314D03*
X1050002Y264899D03*
X1047002D03*
X1043502D03*
X1040502D03*
X1047756Y338341D03*
X1044256D03*
X1050756D03*
X1053702Y338404D03*
X1049284Y370959D03*
X1035765D03*
X1042524D03*
X1045904Y365109D03*
X1039145D03*
X1042524Y355360D03*
X1045904Y357309D03*
X1039145D03*
X1052664Y392410D03*
X1040265Y394359D03*
X1049284Y382660D03*
X1035765D03*
X1042524D03*
Y390460D03*
X1044290Y512792D03*
X1057676Y518157D03*
X1064369Y512792D03*
X1047637Y515364D03*
X1054330D03*
X1084800Y499400D03*
X1044203Y537058D03*
X1057677Y529007D03*
X1047637D03*
X1134160Y272747D03*
X1154440Y237647D03*
X1147680Y241547D03*
X1157820Y227896D03*
X1147680Y229847D03*
X1144300Y274696D03*
X1147680Y280547D03*
X1157820Y266896D03*
X1119521D03*
Y262996D03*
X1134160Y276646D03*
X1154440Y233746D03*
X1144300Y227896D03*
X1151060Y235696D03*
X1144300Y239596D03*
X1151060Y243496D03*
Y239596D03*
X1144300Y266896D03*
X1108125Y276799D03*
X1147680Y237647D03*
X1144300Y231797D03*
X1157820Y235696D03*
X1151060Y227896D03*
Y231797D03*
X1099391Y337001D03*
X1105800Y336830D03*
X1114839Y320075D03*
X1102300Y336700D03*
X1130780Y282496D03*
Y286396D03*
X1134160Y311747D03*
Y315647D03*
X1124021Y344896D03*
X1127400Y350747D03*
X1130780Y348796D03*
X1127400Y346847D03*
X1147331Y550914D03*
X1141038D03*
X1156252Y550714D03*
Y553314D03*
Y569340D03*
X1144685Y566699D03*
X1151152Y550500D03*
Y553100D03*
X1151178Y569550D03*
X1137992Y555957D03*
X1147331Y572500D03*
X1144685Y555957D03*
X1137992Y566699D03*
X1156252Y571949D03*
X1151152Y572199D03*
X1140952Y572500D03*
X1218868Y214869D03*
X1218000Y218100D03*
X1205139Y278596D03*
X1184859Y227896D03*
X1194999Y229847D03*
X1178099Y231797D03*
X1171339Y227896D03*
X1174719Y222047D03*
X1208519Y253247D03*
X1205139Y262996D03*
X1191619Y235696D03*
X1164580Y231797D03*
X1205139Y270796D03*
X1198379Y274696D03*
X1201759Y253247D03*
X1212199Y227896D03*
X1161200Y237647D03*
X1205139Y243496D03*
Y235696D03*
Y255196D03*
X1208519Y229847D03*
X1174719Y249347D03*
X1161200Y225947D03*
X1181479D03*
Y233746D03*
Y229847D03*
X1205139Y259096D03*
X1216234Y268055D03*
X1212199Y223996D03*
Y231797D03*
X1205139Y239596D03*
X1208519Y237647D03*
X1191619Y231797D03*
X1188239Y233746D03*
Y229847D03*
X1174719Y225947D03*
X1171339Y223996D03*
X1161200Y229847D03*
X1174719Y233746D03*
X1167960Y225947D03*
X1174719Y229847D03*
X1208519Y241547D03*
X1205139Y251296D03*
X1208519Y257147D03*
X1201759Y264947D03*
X1205139Y266896D03*
X1208519Y268847D03*
X1201759D03*
Y276646D03*
X1184859Y231797D03*
X1208519Y225947D03*
X1191619Y227896D03*
X1201759Y272747D03*
Y280547D03*
X1208519Y249347D03*
X1198379Y231797D03*
X1161200Y233746D03*
X1214732Y243496D03*
X1212199Y239596D03*
X1217476Y243482D03*
X1216234Y265555D03*
X1208819Y284447D03*
X1201759Y292247D03*
X1205439Y286596D03*
Y294196D03*
Y290296D03*
X1205139Y282496D03*
X1171456Y550914D03*
X1164763D03*
X1177849D03*
X1161417Y566699D03*
X1174803D03*
X1184142Y550914D03*
X1208267D03*
X1201574D03*
X1187963Y553100D03*
X1193063Y550714D03*
Y553314D03*
X1181496Y566699D03*
X1204921D03*
X1198228D03*
X1187989Y569550D03*
X1193063Y571949D03*
Y569340D03*
X1204921Y555957D03*
X1198228D03*
X1187963Y550500D03*
X1184142Y572500D03*
X1201574Y572900D03*
X1187963Y572199D03*
X1208267Y572900D03*
X1181496Y555957D03*
X1174803D03*
X1161417D03*
X1171456Y572900D03*
X1168110Y555957D03*
Y566699D03*
X1177763Y572500D03*
X1164763Y572900D03*
X1276346Y-10250D03*
X1267959Y47245D03*
X1268111Y58040D03*
X1270350Y98300D03*
X1269810Y154398D03*
X1278000Y145780D03*
X1268236Y141938D03*
X1266646Y150540D03*
X1259950Y144650D03*
X1264700Y154800D03*
X1261546Y150584D03*
X1264146D03*
X1261800Y154973D03*
X1262569Y147201D03*
X1252000Y145300D03*
X1233902Y173337D03*
X1240309Y161900D03*
X1267050Y169800D03*
X1241381Y172040D03*
X1246655Y176395D03*
X1263300Y169450D03*
X1259200Y168350D03*
X1267800Y161800D03*
X1271400Y161900D03*
X1220702Y216708D03*
X1268404Y246304D03*
X1277504Y250346D03*
X1275154Y236296D03*
X1279950Y229338D03*
X1276628Y234270D03*
X1272761Y240220D03*
X1274100Y255300D03*
X1275577Y253123D03*
X1270478Y243490D03*
X1225908Y259300D03*
Y261800D03*
X1262700Y461804D03*
X1258140Y474540D03*
X1271571Y479000D03*
X1271662Y487326D03*
X1271640Y474420D03*
X1271647Y482500D03*
X1262843Y497553D03*
X1277800Y497108D03*
X1280595Y496439D03*
X1266162Y496404D03*
X1269006Y496016D03*
X1262900Y466504D03*
X1256320Y490660D03*
X1258126Y469540D03*
X1256350Y486080D03*
X1277200Y539100D03*
X1273200Y582200D03*
X1303774Y-18842D03*
X1287700Y-16700D03*
X1282252Y-14747D03*
X1284859Y-14524D03*
X1320000Y85500D03*
X1296908Y36900D03*
X1304500Y40066D03*
X1302526Y119102D03*
X1310098Y150040D03*
X1306900Y131744D03*
X1323030Y216531D03*
X1326474Y216500D03*
X1331824Y209051D03*
X1300300Y169900D03*
X1281799Y193190D03*
X1300444Y267919D03*
X1309462Y240229D03*
X1319310Y300795D03*
X1299700Y298557D03*
X1299735Y301298D03*
X1303380Y309441D03*
X1302768Y296942D03*
X1319297Y296878D03*
X1331720Y334810D03*
X1320900Y321300D03*
X1323750Y319750D03*
X1308887Y285015D03*
X1316600Y305500D03*
X1336336Y333825D03*
X1326014Y347732D03*
X1315496Y361190D03*
X1332613Y346417D03*
X1329757Y346511D03*
X1335250Y344250D03*
X1336886Y351113D03*
X1339597Y349756D03*
X1335100Y427500D03*
X1329419Y464337D03*
X1323815Y463543D03*
X1318054Y460507D03*
X1285769Y440062D03*
X1341528Y463528D03*
X1321172Y464474D03*
X1288671Y445338D03*
X1335100Y432500D03*
X1304200Y462030D03*
X1286831Y443058D03*
X1322360Y472592D03*
X1322260Y477492D03*
X1297878Y493150D03*
X1295240Y493359D03*
X1290500Y480200D03*
Y482700D03*
X1299450Y484950D03*
X1301240Y476228D03*
X1304200Y466600D03*
X1320300Y498300D03*
X1341050Y498275D03*
X1329419Y469337D03*
X1308500Y540784D03*
X1305500Y542500D03*
X1282600Y581000D03*
Y583600D03*
X1290900Y563300D03*
X1343100Y566300D03*
X1340700D03*
X1338000D03*
X1340526Y563337D03*
X1343026D03*
X1338026D03*
X1333026D03*
X1335526D03*
Y566237D03*
X1327956Y545655D03*
X1324707Y545493D03*
X1333026Y566237D03*
X1292190Y576952D03*
X1290292Y578962D03*
X1311876Y619501D03*
X1314476D03*
X1301384Y618119D03*
X1376842Y15185D03*
X1374431Y15170D03*
X1371598Y-11633D03*
X1371632Y-9191D03*
X1371605Y-14069D03*
X1371941Y22617D03*
X1371950Y20200D03*
X1371900Y17800D03*
Y15400D03*
X1397550Y68059D03*
X1395050D03*
X1397050Y58559D03*
X1392050D03*
X1394550D03*
X1397050Y55559D03*
X1394550D03*
X1392050D03*
X1397539Y65098D03*
X1394939D03*
X1392339D03*
X1395000Y78800D03*
X1397400D03*
X1392584Y78798D03*
X1395000Y76200D03*
X1392584D03*
X1397400D03*
X1392149Y68006D03*
X1404200Y119200D03*
X1398600Y116500D03*
X1400300Y121500D03*
X1401200Y124300D03*
X1401300Y149600D03*
X1402500Y116300D03*
X1399100Y166900D03*
X1403400Y204766D03*
X1359500Y209200D03*
X1356926Y209100D03*
X1362000Y209300D03*
X1402870Y207918D03*
X1397211Y226041D03*
X1402400Y223600D03*
X1399852Y252353D03*
X1399978Y233775D03*
X1400066Y236274D03*
X1398600Y228700D03*
X1401565Y229435D03*
X1399600Y223600D03*
X1388518Y230789D03*
X1394881Y226997D03*
X1364260Y331619D03*
X1388450Y331250D03*
X1392400Y330800D03*
X1400400Y335400D03*
X1345700Y285300D03*
X1359200Y322200D03*
X1365246Y285931D03*
X1355800Y285000D03*
X1352400D03*
X1359000Y284900D03*
X1367200Y321600D03*
X1363700D03*
X1396470Y330014D03*
X1389500Y360500D03*
X1388300Y346200D03*
X1384300Y398900D03*
X1386800D03*
X1384252Y401343D03*
X1386752D03*
X1380900Y383164D03*
X1371600Y368700D03*
X1374344Y371431D03*
X1380200Y370400D03*
X1376979Y370536D03*
X1380200Y373100D03*
X1377103Y373428D03*
X1374300Y402053D03*
X1376800D03*
X1381752Y401343D03*
X1379252D03*
X1381800Y398900D03*
X1374300Y377885D03*
Y381485D03*
X1374268Y374285D03*
X1375100Y447500D03*
X1390100Y452500D03*
X1385100D03*
Y447500D03*
X1362560Y463478D03*
X1370100Y447500D03*
X1375100Y452500D03*
X1370100D03*
X1390100Y457500D03*
X1395100Y447500D03*
X1403027Y520231D03*
X1402950Y510650D03*
X1396035Y514863D03*
X1386241Y487323D03*
Y482623D03*
X1388719Y498745D03*
X1347546Y476897D03*
X1350500Y475100D03*
X1354462Y474141D03*
X1347196Y472941D03*
X1344761Y498282D03*
X1368441Y497523D03*
X1366309Y486618D03*
X1366341Y481823D03*
X1388741Y493623D03*
X1368441Y492723D03*
X1396158Y537595D03*
X1400980Y587086D03*
X1397980D03*
X1399721Y537509D03*
X1355548Y559959D03*
X1361926Y584037D03*
Y586537D03*
X1359100Y586200D03*
X1357400Y588400D03*
X1360100D03*
X1344613Y556376D03*
Y561376D03*
Y558876D03*
X1347700Y554100D03*
X1344613Y553876D03*
X1358439Y559959D03*
X1382200Y562700D03*
X1379000Y561500D03*
X1364426Y586637D03*
Y584137D03*
X1360500Y570900D03*
Y574700D03*
X1360261Y578873D03*
X1360247Y567390D03*
X1360261Y562373D03*
Y581373D03*
X1362000Y576700D03*
Y572800D03*
X1362100Y569100D03*
X1362000Y565600D03*
X1375961Y569473D03*
X1376000Y565700D03*
X1375961Y562273D03*
X1363761Y581373D03*
X1400980Y589586D03*
X1395060Y590630D03*
X1357726Y591037D03*
X1360226D03*
X1375600Y589700D03*
X1382100Y592800D03*
X1382000Y589500D03*
X1363761Y612573D03*
X1360261D03*
X1360200Y597800D03*
X1361600Y599900D03*
X1361500Y595700D03*
X1360100Y610100D03*
X1360200Y606300D03*
Y602000D03*
X1361900Y608200D03*
X1361500Y604200D03*
X1360261Y593573D03*
X1375961Y600673D03*
X1375861Y597073D03*
X1375961Y593473D03*
X1363761Y610073D03*
X1398010Y590040D03*
X1425081Y48412D03*
X1458569Y192143D03*
X1447999Y205645D03*
X1439700Y253100D03*
X1407274Y245652D03*
X1466006Y265300D03*
X1465063Y253544D03*
X1464700Y256100D03*
X1466404Y245350D03*
X1437800Y258300D03*
X1452200Y254500D03*
X1452728Y243306D03*
X1438500Y255400D03*
X1408376Y339882D03*
X1408250Y333000D03*
X1408348Y336436D03*
X1410489Y337988D03*
X1453900Y353350D03*
X1456000Y360700D03*
X1460400Y353000D03*
X1459111Y356353D03*
X1453251Y356676D03*
X1446700Y387900D03*
X1408225Y438233D03*
Y441000D03*
X1412484Y440748D03*
X1412375Y443545D03*
X1439000Y423000D03*
X1414107Y447267D03*
X1405950Y510650D03*
X1407884Y512751D03*
X1460661Y484891D03*
X1461267Y489790D03*
X1456602Y485864D03*
X1452188Y487223D03*
X1456590Y488976D03*
X1418241Y489523D03*
X1418441Y482523D03*
X1441842Y482924D03*
X1442041Y494423D03*
X1431690Y521530D03*
X1458060Y495020D03*
X1464553Y508872D03*
X1436358Y525142D03*
X1418341Y494423D03*
Y477323D03*
X1442141Y477623D03*
X1442041Y489223D03*
X1441252Y548631D03*
X1451150Y569900D03*
Y573200D03*
X1458629Y531604D03*
X1461500Y531500D03*
X1433100Y581770D03*
X1430570Y580890D03*
X1432590Y584550D03*
X1427500Y581100D03*
X1441409Y561117D03*
X1465700Y570500D03*
X1415173Y586332D03*
X1412673D03*
X1422920Y586250D03*
X1417920D03*
X1420420D03*
X1445145Y605727D03*
X1442525Y597279D03*
X1443654Y594749D03*
X1456277Y603454D03*
X1453628Y603368D03*
X1450720Y606067D03*
X1448071Y605981D03*
X1443473Y599944D03*
X1453451Y606114D03*
X1456100Y606200D03*
X1460200D03*
X1485242Y4589D03*
X1496660Y-10252D03*
X1501900Y-9124D03*
X1524557Y88336D03*
X1520314Y78880D03*
X1517162Y78784D03*
X1519599Y86117D03*
X1519580Y81313D03*
X1524744Y133656D03*
X1514600Y126650D03*
X1511800Y127050D03*
X1513879Y113349D03*
X1526728Y124168D03*
X1518438Y100926D03*
X1518376Y111499D03*
X1495848Y150600D03*
X1511660Y138510D03*
X1500643Y154819D03*
X1503466Y142486D03*
X1510184Y142614D03*
X1524900Y139100D03*
X1473354Y153246D03*
X1485210Y134837D03*
X1524000Y123300D03*
X1498810Y108290D03*
X1526310Y142190D03*
X1512500Y199837D03*
X1475401Y210017D03*
X1515060Y192443D03*
X1487716Y218650D03*
X1470382Y188372D03*
X1472758Y216495D03*
X1497493Y162078D03*
X1488900Y172576D03*
X1489015Y179832D03*
X1516616Y205537D03*
X1488300Y158300D03*
X1477388Y172988D03*
X1473888Y173721D03*
X1492597Y172636D03*
X1470950Y252846D03*
X1469004Y246287D03*
X1470556Y256900D03*
X1468450Y252900D03*
X1478500Y252000D03*
X1491265Y226492D03*
X1509814Y247215D03*
X1526150Y234300D03*
X1482004Y222483D03*
X1474096Y256706D03*
X1483457Y244568D03*
X1487500Y244500D03*
X1499681Y279910D03*
X1516549Y234278D03*
X1471604Y246287D03*
X1474520Y251740D03*
X1505946Y254432D03*
X1470276Y330774D03*
X1516138Y310749D03*
X1499829Y341250D03*
X1482550Y333600D03*
X1482585Y340856D03*
X1510851Y340113D03*
X1527537Y330048D03*
X1482386Y336926D03*
X1493290Y287984D03*
X1496900Y293900D03*
X1487000Y333300D03*
X1495445Y338724D03*
X1496400Y336376D03*
X1498600Y334800D03*
X1501175Y380894D03*
X1516775Y394414D03*
X1510925Y377514D03*
X1512875Y380894D03*
X1518725Y377514D03*
X1522625Y384274D03*
X1510925D03*
X1489475Y380894D03*
X1493375D03*
X1507200Y356000D03*
X1502970Y350610D03*
X1520675Y394414D03*
X1472940Y384030D03*
X1467597Y363000D03*
X1469000Y345850D03*
X1524575Y394414D03*
X1498309Y360005D03*
X1498246Y352305D03*
Y354905D03*
X1516775Y380894D03*
X1512875Y394414D03*
X1484600Y394100D03*
X1515328Y363389D03*
X1516775Y387654D03*
X1478163Y354940D03*
X1496000Y350000D03*
X1493375Y428214D03*
Y436786D03*
X1528100Y413700D03*
X1512350Y410450D03*
X1521800Y419900D03*
X1501175Y443546D03*
X1524575Y457066D03*
X1524950Y445100D03*
Y448250D03*
X1521800Y445100D03*
X1528147Y454546D03*
X1509200Y410450D03*
X1505075Y407934D03*
X1483375Y458375D03*
X1516700Y409900D03*
X1518650Y413600D03*
X1489475Y428214D03*
Y436786D03*
X1508975Y457066D03*
X1515389Y451400D03*
X1521800D03*
X1518650Y448250D03*
X1487525Y480726D03*
X1520675Y484106D03*
X1524575Y477346D03*
X1512875D03*
X1526525Y480726D03*
X1524575Y484106D03*
X1522625Y480726D03*
X1516775Y477346D03*
X1482200Y477800D03*
X1485100Y469900D03*
X1484200Y515700D03*
X1481700D03*
X1472500Y509810D03*
X1474400Y517200D03*
X1468649Y570012D03*
X1481200Y531200D03*
X1483700D03*
X1492750Y615903D03*
X1494100Y613280D03*
X1497800Y610000D03*
X1497097Y613043D03*
X1527050Y613000D03*
X1523450Y612900D03*
X1519850Y613000D03*
X1487912Y611632D03*
X1491512Y611732D03*
X1484312D03*
X1584748Y70840D03*
X1572586Y95639D03*
X1587359Y84348D03*
X1562850Y73642D03*
X1541520Y79387D03*
X1562575Y76231D03*
X1556810Y71760D03*
X1546370Y84180D03*
X1545250Y88360D03*
X1556200Y94800D03*
X1577269Y95344D03*
X1557981Y141470D03*
X1572634Y98546D03*
X1574197Y127915D03*
X1588000Y100500D03*
X1588500Y106788D03*
X1567968Y136682D03*
X1567981Y139607D03*
X1579310Y128604D03*
X1576606Y104392D03*
X1579290Y131104D03*
X1573153Y103721D03*
X1542100Y119200D03*
X1542900Y121700D03*
X1541421Y106742D03*
X1541390Y136498D03*
X1531726Y123800D03*
X1541351Y151900D03*
X1531985Y147000D03*
X1532923Y144518D03*
X1542685Y133321D03*
X1555676Y123283D03*
X1541765Y114000D03*
X1541831Y149030D03*
X1566486Y181270D03*
X1587549Y192000D03*
X1571501Y180031D03*
X1557787Y192236D03*
X1558000Y205100D03*
X1552063Y202031D03*
X1549693Y196707D03*
X1548178Y190880D03*
X1545910Y199977D03*
X1546000Y197400D03*
X1543100Y184128D03*
X1535065Y164300D03*
X1561538Y174649D03*
X1545023Y161675D03*
X1558042Y172448D03*
X1567000Y259560D03*
X1570272Y234889D03*
X1572730Y235931D03*
X1589592Y252472D03*
X1542690Y236050D03*
X1547869Y243356D03*
X1558700Y252000D03*
X1545802Y233529D03*
X1584568Y281339D03*
X1572336Y287063D03*
X1578790Y290920D03*
X1581077Y284825D03*
X1578577Y284799D03*
X1573790Y284895D03*
X1569926Y308064D03*
X1566910Y315117D03*
X1581940Y295820D03*
X1588551Y341410D03*
X1581834Y318591D03*
X1529734Y319714D03*
X1551250Y320303D03*
X1547398Y333823D03*
X1536027Y305048D03*
X1564411Y315210D03*
X1538206Y303741D03*
X1559500Y290300D03*
X1554800Y341100D03*
X1557550D03*
X1568524Y312885D03*
X1582800Y312100D03*
X1551875Y387654D03*
X1528475D03*
X1542300Y376717D03*
X1565525Y384274D03*
X1569425Y397794D03*
X1533719Y362783D03*
X1533790Y360283D03*
X1528475Y380894D03*
X1530425Y397794D03*
X1532375Y401174D03*
X1532367Y356530D03*
X1550639Y350200D03*
X1563575Y401174D03*
X1553825Y397794D03*
X1546025D03*
X1538500Y359363D03*
X1552500Y358500D03*
X1538397Y361861D03*
X1538478Y350694D03*
Y353294D03*
Y355894D03*
X1547975Y394414D03*
Y387654D03*
X1534325Y391034D03*
X1559675Y387654D03*
Y394414D03*
X1557725Y391034D03*
X1536275Y394414D03*
X1558980Y360130D03*
X1543300Y360900D03*
X1565525Y460446D03*
X1567475Y414694D03*
Y443546D03*
X1571375Y407934D03*
X1553825Y460446D03*
X1563575Y463826D03*
X1557725Y418074D03*
X1584200Y462610D03*
X1567475Y436786D03*
X1571375Y443546D03*
X1588632Y452151D03*
X1585920Y452368D03*
X1583208Y452185D03*
X1567475Y407934D03*
X1531250Y445100D03*
Y448250D03*
X1532349Y455200D03*
X1528475Y407934D03*
X1561625Y446926D03*
X1549950Y404490D03*
X1540700Y445100D03*
X1537550Y448250D03*
X1534400D03*
X1540700D03*
X1537550Y445100D03*
X1534400D03*
X1540700Y435650D03*
X1547754Y430351D03*
X1547755Y423570D03*
X1547754Y427884D03*
X1553825Y453686D03*
X1547000Y435650D03*
X1549925Y431594D03*
X1547755Y421138D03*
X1540653Y454588D03*
X1559595Y450631D03*
X1563575Y414694D03*
X1559675Y457066D03*
X1537550Y438800D03*
X1540700D03*
X1553825Y418074D03*
X1559675Y421454D03*
X1555775D03*
X1536275Y477346D03*
X1530425Y480726D03*
Y487486D03*
X1534325Y473966D03*
X1565000Y506329D03*
Y503329D03*
X1538225Y480726D03*
X1534325D03*
X1528475Y484106D03*
X1532375D03*
Y477346D03*
X1581730Y537170D03*
X1545200Y585724D03*
X1542600D03*
X1550990Y586588D03*
X1554358Y587258D03*
X1585155Y538574D03*
X1586700Y620100D03*
X1529067Y615784D03*
X1529697Y613384D03*
X1532270Y610764D03*
X1532160Y613408D03*
X1546075Y618145D03*
X1544050Y615296D03*
X1610004Y-17346D03*
X1605004D03*
X1597504D03*
X1607504D03*
X1592715Y70817D03*
X1591600Y75700D03*
X1640900Y66900D03*
X1627489Y74960D03*
X1602000Y84500D03*
X1596900D03*
X1610853Y63861D03*
X1621100Y69600D03*
X1630826Y88087D03*
X1628788Y97800D03*
X1593756Y129048D03*
X1598300Y116477D03*
X1632020Y97871D03*
X1600000Y104243D03*
X1592870Y217900D03*
X1595291Y166423D03*
X1626935Y217775D03*
X1637870Y195077D03*
X1644290Y196383D03*
X1634069Y197454D03*
X1627326Y182759D03*
X1610554Y184877D03*
X1611761Y213507D03*
X1644433Y185415D03*
X1641800Y184400D03*
X1608056Y184771D03*
X1603300Y185100D03*
X1604222Y268107D03*
X1591865Y237407D03*
X1627024Y253387D03*
X1637269Y264421D03*
X1599270Y246310D03*
X1600810Y266006D03*
X1609051Y243415D03*
X1628624Y225318D03*
X1600552Y261281D03*
X1632128Y225472D03*
X1609172Y339630D03*
X1625400Y327667D03*
X1603307Y393224D03*
X1608146Y380322D03*
Y376171D03*
X1608850Y343835D03*
X1598878Y380344D03*
Y376346D03*
X1640266Y365500D03*
Y360500D03*
X1630120Y418887D03*
X1621000Y452000D03*
X1591344Y452134D03*
X1593400Y432200D03*
X1639500Y435700D03*
X1640625Y429460D03*
X1630300Y452100D03*
X1634400Y412900D03*
X1630276Y449517D03*
X1639750Y445477D03*
X1639774Y439486D03*
X1639822Y453140D03*
X1596500Y455500D03*
X1615061Y463157D03*
X1650944Y505166D03*
X1648330Y504544D03*
X1641963Y495964D03*
X1649336Y511502D03*
X1641470Y506403D03*
X1644651Y505500D03*
X1645969Y514870D03*
X1601557Y479225D03*
X1633359Y472859D03*
X1633075Y470174D03*
X1639113Y496734D03*
X1598700Y479225D03*
X1639271Y491135D03*
X1612519Y586004D03*
X1590530Y610620D03*
X1617600Y619800D03*
X1619700Y617300D03*
X1612519Y590004D03*
X1613349Y603250D03*
X1603919Y596750D03*
X1603869Y608450D03*
X1613349Y599250D03*
X1603869Y604450D03*
X1603919Y592750D03*
X1650869Y614200D03*
Y609200D03*
X1680033Y-16711D03*
X1676819Y-16779D03*
X1695200Y11317D03*
X1704771Y11261D03*
X1700200Y11317D03*
X1709771Y11261D03*
X1693900Y73300D03*
X1679900Y74500D03*
X1678000Y81600D03*
X1708610Y85121D03*
X1709184Y88811D03*
X1696655Y77991D03*
X1704824Y90049D03*
X1676428Y74646D03*
X1670500Y81600D03*
X1659196Y70291D03*
X1661563Y72028D03*
X1668000Y81600D03*
X1708508Y39350D03*
X1699273Y39679D03*
X1712308Y39350D03*
X1703073Y39679D03*
X1680139Y99073D03*
X1664500Y99000D03*
X1678400Y103000D03*
X1655209Y181761D03*
X1674019Y175990D03*
X1674455Y172658D03*
X1655031Y184505D03*
X1654015Y217239D03*
X1688046Y174447D03*
X1660440Y200789D03*
X1673800Y201070D03*
X1713000Y185000D03*
X1705666Y198055D03*
X1676750Y206050D03*
X1667140Y182300D03*
X1673530Y209974D03*
X1707100Y188300D03*
X1664390Y201163D03*
X1659643Y213505D03*
X1671688Y182925D03*
X1670140Y257547D03*
X1670822Y254691D03*
X1688451Y249716D03*
X1679100Y302100D03*
Y304700D03*
Y299500D03*
Y297000D03*
X1654770Y399145D03*
X1652186Y365600D03*
Y360600D03*
X1654861Y396637D03*
X1660890Y397300D03*
X1660934Y387883D03*
X1664829Y379194D03*
X1664905Y376695D03*
X1667809Y427809D03*
X1667729Y424621D03*
X1668100Y418700D03*
X1678303Y442765D03*
X1681215Y451786D03*
X1669076Y438281D03*
X1667588Y434149D03*
X1667649Y430849D03*
X1667462Y440735D03*
X1669962D03*
X1675744Y456200D03*
X1664762Y443735D03*
X1669816Y443953D03*
Y446453D03*
X1673064Y446022D03*
X1679145Y461950D03*
X1673068Y448522D03*
X1669816Y448953D03*
X1681154Y449286D03*
X1664762Y440735D03*
X1676041Y458884D03*
X1660834Y404934D03*
X1672313Y497300D03*
X1687741Y466988D03*
X1705767Y482434D03*
X1698354Y486873D03*
X1681500Y482000D03*
X1699861Y520192D03*
X1697261D03*
X1671050Y483600D03*
Y481000D03*
X1651754Y488025D03*
X1672159Y494042D03*
X1701617Y482706D03*
X1680133Y535489D03*
X1699600Y578100D03*
X1710389Y577787D03*
X1660680Y586750D03*
X1701291Y602268D03*
X1699106Y618018D03*
X1658369Y606250D03*
X1652499Y593950D03*
X1660680Y590750D03*
X1658369Y602250D03*
X1652499Y597950D03*
X1714297Y11180D03*
X1756895Y30452D03*
X1723678Y11381D03*
X1756992Y20007D03*
X1763360Y24010D03*
X1761872Y-7220D03*
X1760693Y20045D03*
X1767069Y24010D03*
X1743152Y23197D03*
X1733168Y22312D03*
X1748152Y23197D03*
X1738168Y22312D03*
X1728678Y11381D03*
X1719297Y11180D03*
X1731350Y92140D03*
X1750250Y35925D03*
X1757772Y90174D03*
X1757395Y84794D03*
X1755400Y37700D03*
X1736700Y39600D03*
X1727383Y39465D03*
X1717958Y39880D03*
X1752000Y38865D03*
X1756895Y34252D03*
X1746550Y35925D03*
X1740598Y39486D03*
X1731183Y39465D03*
X1721758Y39880D03*
X1758100Y119100D03*
X1761300D03*
X1768886Y156173D03*
X1719250Y179150D03*
X1718820Y249032D03*
X1715078Y250231D03*
X1774451Y237712D03*
X1755554D03*
X1760554D03*
X1722251Y250532D03*
X1719089Y472104D03*
X1728700Y470200D03*
X1766100Y521124D03*
X1722347Y471811D03*
X1750800Y516100D03*
X1725694Y571814D03*
X1738434Y588986D03*
X1772578Y575993D03*
X1730759Y548162D03*
X1722500Y562000D03*
X1754897Y578750D03*
X1738216Y548239D03*
X1737958Y560500D03*
X1743200Y567300D03*
X1743100Y561700D03*
X1743000Y574500D03*
X1730774Y579960D03*
X1738088Y551000D03*
X1770719Y573964D03*
X1742381Y588530D03*
X1764912Y618718D03*
X1770600Y600800D03*
X1757319Y606953D03*
X1762062Y592055D03*
Y589555D03*
X1835600Y3900D03*
X1824564Y3441D03*
X1825870Y21587D03*
X1823300Y21700D03*
X1832842Y13500D03*
X1819800Y2100D03*
X1813913Y2287D03*
X1816723Y9781D03*
X1808603Y9300D03*
X1826414Y35486D03*
X1815637Y54775D03*
X1818396Y54752D03*
X1820457Y39128D03*
X1829580Y38620D03*
X1824130Y39703D03*
X1824240Y83680D03*
X1817186Y39929D03*
X1776828Y155211D03*
X1815883Y133277D03*
X1807509Y128500D03*
X1807166Y147401D03*
X1824990Y103620D03*
X1824509Y143653D03*
X1821348Y143437D03*
X1815026Y121478D03*
X1808226Y136171D03*
X1803509Y128500D03*
X1800792Y122691D03*
X1821350Y98270D03*
X1810100Y114700D03*
X1810245Y104500D03*
X1814900Y116900D03*
X1808313Y111705D03*
X1807818Y124179D03*
X1790100Y154000D03*
X1821261Y170012D03*
X1824200Y176900D03*
X1787000Y175500D03*
X1778900Y165800D03*
X1830415Y196567D03*
X1816125Y169492D03*
X1817282Y250498D03*
X1798384D03*
X1779451Y237712D03*
X1793384Y250498D03*
X1812282D03*
X1776695Y512640D03*
X1825700Y514900D03*
X1828100Y516300D03*
X1828000Y513200D03*
X1814852Y519901D03*
X1836396Y481349D03*
X1828200Y519000D03*
X1795200Y525700D03*
X1816800D03*
X1813500Y526500D03*
X1825900Y523500D03*
X1816052Y584101D03*
X1809309Y555713D03*
X1813456Y583500D03*
X1803752Y529301D03*
X1810052Y545103D03*
X1793660Y560570D03*
X1829176Y584287D03*
X1793452Y586701D03*
X1809600Y582800D03*
X1791500Y606500D03*
X1800378Y593527D03*
X1837900Y9700D03*
X1868286Y12848D03*
X1871163Y13186D03*
X1876792Y18461D03*
X1876881Y22181D03*
X1840400Y9700D03*
X1837500Y35700D03*
X1873956Y60299D03*
X1878800Y40200D03*
X1878997Y37546D03*
X1878000Y73950D03*
X1848208Y49427D03*
X1877103Y60791D03*
X1848100Y134750D03*
X1845469Y135500D03*
X1857110Y113600D03*
X1890974Y105600D03*
X1898102Y107325D03*
X1857020Y129619D03*
Y126619D03*
X1875425Y152925D03*
X1886299Y153928D03*
X1860969Y136369D03*
Y133769D03*
X1857919Y156123D03*
X1853317Y108197D03*
X1854942Y181655D03*
X1854900Y175900D03*
X1876700Y207600D03*
X1875700Y184800D03*
X1877880Y203780D03*
X1893238Y208042D03*
X1863750Y163750D03*
X1886200Y161000D03*
X1883930Y176137D03*
X1883800Y179100D03*
X1859604Y213206D03*
X1861497Y211481D03*
X1850876Y212946D03*
X1847699D03*
X1861243Y183100D03*
X1855000Y167100D03*
X1850723Y219250D03*
X1843449Y244425D03*
X1896529Y235080D03*
X1884651Y234975D03*
X1850220Y253500D03*
X1858420Y253700D03*
X1884400Y224100D03*
X1882200Y234400D03*
X1882345Y231837D03*
X1840149Y244425D03*
X1892274Y235080D03*
X1846517Y253500D03*
X1854720Y253700D03*
X1885000Y227500D03*
X1878100Y450200D03*
X1896700Y472600D03*
X1896800Y470200D03*
X1894100Y472600D03*
X1894200Y470200D03*
X1843750Y475724D03*
X1840750D03*
X1873632Y500904D03*
X1842764Y528136D03*
X1870100Y561150D03*
X1855750Y548000D03*
X1885100Y584300D03*
X1848900Y548200D03*
X1844018Y586482D03*
X1856040Y588704D03*
X1848900Y590750D03*
X1845000Y590800D03*
X1900256Y-14760D03*
Y-18911D03*
X1918113Y93576D03*
X1927918Y126156D03*
X1906414Y118004D03*
X1906467Y115305D03*
X1919702Y125920D03*
X1914500Y113300D03*
X1911440Y128840D03*
X1934544Y127957D03*
X1929736Y128337D03*
X1927064Y207564D03*
X1918489Y212513D03*
X1930500Y209464D03*
X1943500Y209500D03*
X1925000Y192000D03*
X1910123Y217349D03*
X1918143Y219848D03*
X1925835Y233735D03*
X1926100Y231200D03*
X1910340Y220741D03*
X1902907Y231294D03*
X1899816Y235035D03*
X1903020Y225776D03*
X1904724Y447930D03*
X1901574Y454422D03*
X1939845Y445055D03*
X1957212Y479521D03*
X1899100Y472600D03*
X1899200Y470200D03*
X1904200Y472700D03*
X1901700Y472600D03*
X1904300Y470300D03*
X1901800Y470200D03*
X1938300Y486250D03*
X1937300Y508900D03*
X1956300Y515900D03*
X1956606Y526671D03*
X1959300Y518000D03*
X1957063Y474769D03*
X1951900Y534900D03*
X1911000Y556700D03*
X1907500Y545600D03*
X1934400Y569400D03*
X1937200Y545100D03*
X1937300Y541600D03*
X1934200Y573700D03*
Y577700D03*
X1939700Y540900D03*
X1935400Y583000D03*
X1940800Y537300D03*
X1932800Y564300D03*
X1935400Y550800D03*
X1936900Y568000D03*
X1937800Y549700D03*
X1927000Y614500D03*
X1934350Y609250D03*
X1962800Y149300D03*
X1964270Y511410D03*
X1961700Y616700D03*
Y619500D03*
X1965400D03*
G54D31*
G01X-4350Y482100D02*
X-3388Y481138D01*
Y480778D01*
X-4236Y479930D01*
X-5664D01*
X-9734Y484000D01*
X-15355D01*
X-19810Y488455D01*
Y525433D01*
X-17628Y527615D01*
X-16656D01*
X-12400Y531871D01*
Y532300D01*
X-11700Y533000D01*
X-10683D01*
X-9287Y531604D01*
G01X-900Y482300D02*
X-2388Y480812D01*
Y480363D01*
X-3821Y478930D01*
X-6079D01*
X-10149Y483000D01*
X-15770D01*
X-20810Y488040D01*
Y525848D01*
X-18043Y528615D01*
X-17071D01*
X-13400Y532286D01*
Y532715D01*
X-12115Y534000D01*
X-10492D01*
X-9291Y535201D01*
G01X2589Y481983D02*
X3639Y483033D01*
Y485466D01*
X-11660Y500765D01*
Y520165D01*
X-12903Y521408D01*
Y527728D01*
X-10762Y529869D01*
X-8342D01*
X-7246Y530965D01*
Y536400D01*
X-7746Y536900D01*
X-12100D01*
X-12500Y536500D01*
X-17000D01*
X-21000Y540500D01*
Y567115D01*
X-11875Y576240D01*
X-7935D01*
X-5670Y573975D01*
Y570865D01*
X-6566Y569969D01*
Y568363D01*
G01X5689Y481983D02*
X4639Y483033D01*
Y485881D01*
X-10660Y501180D01*
Y520580D01*
X-11903Y521823D01*
Y527313D01*
X-10347Y528869D01*
X-7927D01*
X-6246Y530550D01*
Y536815D01*
X-7331Y537900D01*
X-12515D01*
X-12915Y537500D01*
X-16585D01*
X-20000Y540915D01*
Y566700D01*
X-11460Y575240D01*
X-8350D01*
X-6670Y573560D01*
Y571824D01*
X-7170Y571324D01*
X-9283D01*
G01X19964Y18793D02*
X17501Y16330D01*
X12686D01*
X9624Y19392D01*
X7538D01*
X4578Y22352D01*
X3310D01*
X2871Y22791D01*
G01X16550Y18300D02*
X15580Y17330D01*
X13101D01*
X10039Y20392D01*
X7953D01*
X2934Y25411D01*
Y26933D01*
G01X657700Y250172D02*
X658608Y251080D01*
Y252415D01*
X659693Y253500D01*
X669216D01*
X672516Y250200D01*
X678815D01*
X681720Y247295D01*
Y241779D01*
X699399Y224100D01*
X707315D01*
X709715Y221700D01*
X711256D01*
X713700Y224144D01*
G01X660588Y250312D02*
X659608Y251292D01*
Y252000D01*
X660108Y252500D01*
X668801D01*
X672101Y249200D01*
X678400D01*
X680720Y246880D01*
Y241364D01*
X698984Y223100D01*
X706900D01*
X709300Y220700D01*
X712956D01*
X713800Y221544D01*
G01X1335100Y427500D02*
Y428912D01*
X1335601Y429413D01*
X1336361D01*
X1337310Y428464D01*
Y417766D01*
X1334455Y414911D01*
Y392140D01*
X1336590Y390005D01*
Y374390D01*
X1319900Y357700D01*
Y351299D01*
X1316549Y347948D01*
Y318665D01*
X1321970Y313244D01*
Y300243D01*
X1321470Y299743D01*
X1320362D01*
X1319310Y300795D01*
G01X1335100Y432500D02*
Y430960D01*
X1335647Y430413D01*
X1336776D01*
X1338310Y428879D01*
Y417351D01*
X1335455Y414496D01*
Y392555D01*
X1337590Y390420D01*
Y373975D01*
X1320900Y357285D01*
Y350884D01*
X1317549Y347533D01*
Y319080D01*
X1322970Y313659D01*
Y299828D01*
X1321885Y298743D01*
X1321162D01*
X1319297Y296878D01*
G01X1546075Y618145D02*
X1546104D01*
Y618116D01*
X1546300Y617920D01*
Y615110D01*
X1550007Y611403D01*
X1557229D01*
X1559611Y609021D01*
X1565270D01*
X1568042Y606249D01*
Y600307D01*
X1569963Y598386D01*
X1573073D01*
X1576432Y595027D01*
Y547297D01*
X1585155Y538574D01*
G01X1544050Y615296D02*
X1544161D01*
Y614550D01*
X1548311Y610400D01*
X1556817D01*
X1559196Y608021D01*
X1564855D01*
X1567042Y605834D01*
Y599892D01*
X1569548Y597386D01*
X1572658D01*
X1575432Y594612D01*
Y546882D01*
X1581730Y540584D01*
Y537170D01*
G54D13*
X-14488Y434094D03*
G54D22*
X1884100Y493000D03*
X1891086Y612105D03*
Y592105D03*
X1904100Y493000D03*
G54D32*
G01X447800Y335900D02*
X448200Y336300D01*
Y339502D01*
X439949Y347753D01*
Y349139D01*
X434598Y354490D01*
X433110D01*
X431473Y352853D01*
X429730D01*
X428093Y354490D01*
X426350D01*
X424713Y352853D01*
X422970D01*
X422257Y353566D01*
X405437D01*
X403800Y355203D01*
X402312D01*
X400675Y353566D01*
X398677D01*
X397040Y355203D01*
X393073D01*
X392916Y355360D01*
G01X450700Y335550D02*
X450089Y336161D01*
Y343390D01*
X450297Y343598D01*
Y345341D01*
X449247Y346391D01*
X447958D01*
X442750Y351599D01*
Y353097D01*
X441045Y354802D01*
X439869D01*
X437918Y356753D01*
X436235D01*
X434598Y358390D01*
X432855D01*
X431218Y356753D01*
X429475D01*
X427838Y358390D01*
X426291D01*
X424654Y356753D01*
X418270D01*
X417557Y357466D01*
X405437D01*
X403800Y359103D01*
X402312D01*
X400518Y357309D01*
X396296D01*
G01X453200Y335550D02*
X453469Y335819D01*
Y341441D01*
X453677Y341649D01*
Y344173D01*
X446948Y350902D01*
X446629D01*
X445579Y351952D01*
Y353695D01*
X445787Y353903D01*
Y355391D01*
X444737Y356441D01*
X443306D01*
X441045Y358702D01*
X439869D01*
X438230Y360341D01*
X436547D01*
X434598Y362290D01*
X432855D01*
X431218Y360653D01*
X429475D01*
X427838Y362290D01*
X426191D01*
X424554Y360653D01*
X415785D01*
X415136Y361302D01*
X408684D01*
X406983Y363003D01*
X402312D01*
X400675Y361366D01*
X398991D01*
X397040Y359415D01*
X395609D01*
X393503Y357309D01*
X389537D01*
G01X1042524Y355360D02*
X1046746D01*
X1048540Y353566D01*
X1050028D01*
X1051665Y355203D01*
X1054561D01*
X1056198Y353566D01*
X1069457D01*
X1072438Y356547D01*
X1074178D01*
X1076235Y354490D01*
X1077701D01*
X1079338Y352853D01*
X1080826D01*
X1082463Y354490D01*
X1084460D01*
X1086097Y352853D01*
X1087585D01*
X1089222Y354490D01*
X1091220D01*
X1092857Y352853D01*
X1093852D01*
X1099982Y346723D01*
Y343675D01*
X1099697Y343390D01*
Y341902D01*
X1099573Y341778D01*
Y337183D01*
X1099391Y337001D01*
G01X1045904Y357309D02*
X1050126D01*
X1051920Y359103D01*
X1057611D01*
X1059368Y357346D01*
X1068845D01*
X1071899Y360400D01*
X1074199D01*
X1076004Y358595D01*
X1077496D01*
X1079338Y356753D01*
X1080826D01*
X1082463Y358390D01*
X1084460D01*
X1086097Y356753D01*
X1087585D01*
X1089222Y358390D01*
X1090965D01*
X1092602Y356753D01*
X1094286D01*
X1096237Y354802D01*
X1097668D01*
X1099617Y352853D01*
X1100793D01*
X1102155Y351491D01*
Y350003D01*
X1101947Y349795D01*
Y347838D01*
X1103285Y346500D01*
Y341902D01*
X1102300Y340917D01*
Y336700D01*
G01X1105800Y336830D02*
Y339088D01*
X1106665Y339953D01*
Y344765D01*
X1105327Y346103D01*
Y347591D01*
X1105535Y347799D01*
Y349795D01*
X1105327Y350003D01*
Y351744D01*
X1105535Y351952D01*
Y353440D01*
X1104173Y354802D01*
X1102997D01*
X1101046Y356753D01*
X1099617D01*
X1097668Y358702D01*
X1096237D01*
X1094286Y360653D01*
X1092857D01*
X1091220Y362290D01*
X1089222D01*
X1087585Y360653D01*
X1086097D01*
X1084460Y362290D01*
X1082777D01*
X1080826Y364241D01*
X1079650D01*
X1077701Y366190D01*
X1075958D01*
X1074268Y364500D01*
X1066996D01*
X1063755Y361259D01*
X1057153D01*
X1055409Y363003D01*
X1051920D01*
X1050283Y361366D01*
X1048852D01*
X1046825Y359339D01*
X1045148D01*
X1043118Y357309D01*
X1039145D01*
G54D14*
X30500Y-42250D03*
Y-52250D03*
X12290Y264640D03*
X18450Y267010D03*
X22970Y244400D03*
X28720Y244450D03*
X17120Y244220D03*
X24200Y267060D03*
X50500Y-42250D03*
X70500D03*
X90500D03*
X50500Y-52250D03*
X70500D03*
X90500D03*
X100500Y-42250D03*
Y-52250D03*
X457246Y-52301D03*
Y-42301D03*
X477246Y-52301D03*
Y-42301D03*
X497246Y-52301D03*
Y-42301D03*
X517246Y-52301D03*
Y-42301D03*
X527246Y-52301D03*
Y-42301D03*
X788984Y-52057D03*
Y-42057D03*
X808984Y-52057D03*
Y-42057D03*
X828984Y-52057D03*
Y-42057D03*
X848984Y-52057D03*
Y-42057D03*
X858984Y-52057D03*
Y-42057D03*
X1125583Y-52285D03*
Y-42285D03*
X1145583Y-52285D03*
Y-42285D03*
X1382258Y-52257D03*
Y-42257D03*
X1402258Y-52257D03*
Y-42257D03*
X1412258Y-52257D03*
Y-42257D03*
G54D23*
X1894689Y518328D03*
G54D33*
G01X501452Y387796D02*
X502606Y387131D01*
X502700Y386780D01*
G03X502817Y384684I2132J-932D01*
G02X502836Y383143I-1365J-787D01*
G01X502817Y383109D01*
X502792Y383067D01*
G03X502817Y380784I2040J-1119D01*
G02X502836Y379243I-1365J-787D01*
G01X502817Y379209D01*
X502792Y379167D01*
G03X502817Y376884I2040J-1119D01*
G02X502836Y375343I-1365J-787D01*
G01X502817Y375309D01*
G03X502792Y373026I2015J-1164D01*
G01X502817Y372984D01*
G03X504762Y371821I2015J1162D01*
G01X504903D01*
G02X506197Y371034I-71J-1574D01*
G03X508161Y369871I2015J1163D01*
G01X508271D01*
G02X509577Y369084I-59J-1575D01*
G03X511507Y367922I2015J1163D01*
G01X511636D01*
G02X512957Y367134I-44J-1575D01*
G03X514902Y365971I2015J1162D01*
G01X515031D01*
G02X516337Y365184I-59J-1575D01*
G03X518267Y364022I2015J1163D01*
G01X518352D01*
G02X519703Y363257I0J-1575D01*
G01X519716Y363234D01*
G03X521661Y362071I2015J1162D01*
G01X521801D01*
G03X523746Y363234I-70J2325D01*
G02X525067Y364022I1365J-787D01*
G01X525196D01*
G03X527126Y365184I-85J2325D01*
G02X528432Y365971I1365J-788D01*
G01X528561D01*
G03X530506Y367134I-70J2325D01*
G02X531827Y367922I1365J-787D01*
G01X531956D01*
G03X533886Y369084I-85J2325D01*
G02X535192Y369871I1365J-788D01*
G01X535310D01*
G02X536616Y369084I-59J-1575D01*
G03X538546Y367922I2015J1163D01*
G01X538675D01*
G02X539996Y367134I-44J-1575D01*
G03X541941Y365971I2015J1162D01*
G01X542081D01*
G03X544026Y367134I-70J2325D01*
G02X545347Y367922I1365J-787D01*
G01X545476D01*
G03X547406Y369084I-85J2325D01*
G02X548712Y369871I1365J-788D01*
G01X548841D01*
G03X550786Y371034I-70J2325D01*
G02X552080Y371821I1365J-787D01*
G01X552221D01*
G03X554166Y372984I-70J2325D01*
G01X554805Y374085D01*
X561237Y376750D01*
X562030Y377543D01*
Y394071D01*
X562230Y394271D01*
Y394358D01*
G01X511592Y385847D02*
Y384516D01*
X511849Y384259D01*
G02X513607Y380784I-257J-2312D01*
G03X513588Y379243I1365J-787D01*
G01X513607Y379209D01*
X513632Y379167D01*
G02X513607Y376884I-2040J-1119D01*
G03X513588Y375343I1365J-787D01*
G01X513607Y375309D01*
G02X513632Y373026I-2015J-1164D01*
G01X513607Y372984D01*
G03X514928Y370622I1365J-787D01*
G01X515023D01*
G02X516987Y369459I-51J-2326D01*
G03X518294Y368673I1364J789D01*
G03X519703Y369437I57J1576D01*
G01X519716Y369460D01*
G02X519861Y369680I2012J-1168D01*
G02X521661Y370622I1871J-1384D01*
G01X521782D01*
G02X523746Y369459I-51J-2326D01*
G03X525052Y368672I1365J788D01*
G01X525170D01*
G03X526476Y369459I-59J1575D01*
G02X528440Y370622I2015J-1163D01*
G01X528535D01*
G03X529856Y371410I-44J1575D01*
G02X531786Y372572I2015J-1163D01*
G01X531942D01*
G03X533236Y373359I-71J1574D01*
G02X535181Y374522I2015J-1162D01*
G01X535321D01*
G02X537266Y373359I-70J-2325D01*
G03X538560Y372572I1365J787D01*
G01X538716D01*
G02X540646Y371410I-85J-2325D01*
G03X543376I1365J787D01*
G02X545306Y372572I2015J-1163D01*
G01X545462D01*
G03X546756Y373359I-71J1574D01*
G02X548701Y374522I2015J-1162D01*
G01X548842D01*
G03X550136Y375309I-71J1574D01*
G02X552100Y376472I2015J-1163D01*
G01X552210D01*
G03X553516Y377259I-59J1575D01*
G02X555527Y378420I2011J-1160D01*
G01X555534D01*
G03X555784Y378440I0J1576D01*
G01X555841D01*
G03X556677Y378844I0J1067D01*
G01X556761Y378950D01*
G03X557040Y380795I-1471J1166D01*
G02X557008Y383037I2172J1152D01*
G01X557040Y383097D01*
G03Y384695I-1509J799D01*
G02X557017Y386955I2172J1152D01*
G01X557040Y386998D01*
G03X557142Y388363I-1509J799D01*
G03X557040Y388595I-1610J-570D01*
G02X556694Y389986I2622J1391D01*
G01Y390799D01*
X556409Y391084D01*
Y391784D01*
X556694Y392069D01*
Y392882D01*
X556296Y393280D01*
Y393980D01*
X556694Y394378D01*
Y395246D01*
X556296Y395644D01*
Y396344D01*
X556694Y396742D01*
Y397939D01*
X557429Y398674D01*
Y400961D01*
X557138Y401252D01*
Y401952D01*
X557429Y402243D01*
Y403212D01*
X557229Y403412D01*
Y403499D01*
G01X518352Y378047D02*
Y376716D01*
X518579Y376489D01*
G03X519703Y377237I-226J1559D01*
G01X519716Y377260D01*
G02X521817Y378421I2015J-1164D01*
G02X523746Y377259I-86J-2325D01*
G03X525052Y376472I1365J788D01*
G01X525170D01*
G03X526476Y377259I-59J1575D01*
G02X528406Y378421I2015J-1163D01*
G01X528535D01*
G03X529856Y379209I-44J1575D01*
G02X531801Y380372I2015J-1162D01*
G01X531930D01*
G03X533236Y381159I-59J1575D01*
G02X535166Y382321I2015J-1163D01*
G01X535336D01*
G02X537266Y381159I-85J-2325D01*
G03X538572Y380372I1365J788D01*
G01X538701D01*
G02X540646Y379209I-70J-2325D01*
G03X541967Y378421I1365J787D01*
G01X542055D01*
G03X543376Y379209I-44J1575D01*
G02X545321Y380372I2015J-1162D01*
G01X545440D01*
G03X546761Y381160I-44J1575D01*
G02X548706Y382323I2015J-1162D01*
G01X548835D01*
G03X549028Y382343I-66J1574D01*
G03X550161Y384651I-252J1556D01*
G01X550142Y384685D01*
G02X550117Y386968I2015J1164D01*
G01X550142Y387010D01*
G03Y388584I-1365J787D01*
G02Y390910I2015J1163D01*
G03X550161Y392451I-1365J787D01*
G01X550142Y392485D01*
X550117Y392527D01*
G02X550142Y394810I2040J1119D01*
G03X550161Y396351I-1365J787D01*
G01X550142Y396385D01*
G02X549987Y396949I949J564D01*
G01Y397673D01*
X549613Y398047D01*
Y398747D01*
X549987Y399121D01*
Y401500D01*
G02X550357Y402883I2768J0D01*
G03X550564Y403794I-1365J789D01*
G01X550562Y403822D01*
Y404738D01*
X550164Y405136D01*
Y405836D01*
X550562Y406234D01*
Y406934D01*
X550164Y407332D01*
Y408032D01*
X550562Y408430D01*
Y410306D01*
X550068Y410800D01*
X549587D01*
X549091Y411296D01*
Y411777D01*
X548597Y412271D01*
X548116D01*
X547620Y412767D01*
Y413248D01*
X547126Y413742D01*
X546645D01*
X546149Y414238D01*
Y414719D01*
X544439Y416429D01*
X544155D01*
X544094Y416490D01*
Y416491D01*
G01X561080Y394358D02*
Y394271D01*
X561280Y394071D01*
Y392829D01*
X560989Y392538D01*
Y391838D01*
X561280Y391547D01*
Y390798D01*
X560940Y390458D01*
Y389758D01*
X561280Y389418D01*
Y388718D01*
X560940Y388378D01*
Y387678D01*
X561280Y387338D01*
Y386638D01*
X560882Y386240D01*
Y385540D01*
X561280Y385142D01*
Y384442D01*
X560882Y384044D01*
Y383344D01*
X561280Y382946D01*
Y382246D01*
X560882Y381848D01*
Y381148D01*
X561280Y380750D01*
Y380009D01*
X560939Y379668D01*
Y378968D01*
X561280Y378627D01*
Y377854D01*
X560812Y377386D01*
X559978Y377041D01*
X559621Y377189D01*
X558973Y376921D01*
X558825Y376563D01*
X558131Y376276D01*
X557771Y376425D01*
X557123Y376158D01*
X556974Y375796D01*
X556266Y375504D01*
X555922Y375646D01*
X555274Y375378D01*
X555131Y375032D01*
X554282Y374681D01*
X553516Y373359D01*
G02X552222Y372572I-1365J787D01*
G01X552081D01*
G03X550136Y371409I70J-2325D01*
G02X548815Y370621I-1365J787D01*
G01X548686D01*
G03X546756Y369459I85J-2325D01*
G02X545450Y368672I-1365J788D01*
G01X545321D01*
G03X543376Y367509I70J-2325D01*
G02X542055Y366721I-1365J787D01*
G01X541967D01*
G02X540646Y367509I44J1575D01*
G03X538701Y368672I-2015J-1162D01*
G01X538572D01*
G02X537266Y369459I59J1575D01*
G03X535302Y370622I-2015J-1163D01*
G01X535200D01*
G03X533236Y369459I51J-2326D01*
G02X531930Y368672I-1365J788D01*
G01X531801D01*
G03X529856Y367509I70J-2325D01*
G02X528535Y366721I-1365J787D01*
G01X528406D01*
G03X526476Y365559I85J-2325D01*
G02X525170Y364772I-1365J788D01*
G01X525041D01*
G03X523096Y363609I70J-2325D01*
G02X521775Y362821I-1365J787D01*
G01X521731D01*
G02X520380Y363586I0J1575D01*
G01X520367Y363609D01*
G03X518422Y364772I-2015J-1162D01*
G01X518293D01*
G02X516987Y365559I59J1575D01*
G03X515057Y366721I-2015J-1163D01*
G01X514928D01*
G02X513607Y367509I44J1575D01*
G03X511662Y368672I-2015J-1162D01*
G01X511533D01*
G02X510227Y369459I59J1575D01*
G03X508263Y370622I-2015J-1163D01*
G01X508168D01*
G02X506847Y371410I44J1575D01*
G03X504917Y372572I-2015J-1163D01*
G01X504761D01*
G02X503467Y373359I71J1574D01*
G02Y374933I1365J787D01*
G03Y377259I-2015J1163D01*
G02X503448Y378800I1365J787D01*
G01X503467Y378834D01*
X503492Y378876D01*
G03X503467Y381159I-2040J1119D01*
G02X503448Y382700I1365J787D01*
G01X503467Y382734D01*
X503492Y382776D01*
G03X503467Y385059I-2040J1119D01*
G02X503368Y386428I1366J787D01*
G01X503678Y386512D01*
X504832Y385847D01*
G01X558379Y403499D02*
Y403412D01*
X558179Y403212D01*
Y398363D01*
X557444Y397628D01*
Y389987D01*
G03X557703Y388947I2218J0D01*
G02X557989Y387866I-2171J-1153D01*
G02X557703Y386646I-2457J-67D01*
G03Y385048I1509J-799D01*
G02X557735Y382806I-2172J-1152D01*
G01X557703Y382746D01*
G03Y381148I1509J-799D01*
G02X557739Y381067I-828J-417D01*
G02X557349Y378484I-2449J-951D01*
G01X557265Y378378D01*
G02X555841Y377690I-1424J1130D01*
G01X555839D01*
G02X555616Y377671I-309J2306D01*
G01X555605D01*
G02X555535Y377670I-68J2325D01*
G01X555527D01*
G03X554166Y376884I0J-1571D01*
G02X552223Y375722I-2015J1163D01*
G01X552143D01*
X552107Y375721D01*
G03X550786Y374933I44J-1575D01*
G02X548856Y373771I-2015J1163D01*
G01X548700D01*
G03X547406Y372984I71J-1574D01*
G02X545461Y371821I-2015J1162D01*
G01X545320D01*
G03X544026Y371034I71J-1574D01*
G02X539996I-2015J1163D01*
G03X538702Y371821I-1365J-787D01*
G01X538561D01*
G02X536616Y372984I70J2325D01*
G03X535322Y373771I-1365J-787D01*
G01X535180D01*
G03X533886Y372984I71J-1574D01*
G02X531941Y371821I-2015J1162D01*
G01X531800D01*
G03X530506Y371034I71J-1574D01*
G02X528542Y369871I-2015J1163D01*
G01X528432D01*
G03X527126Y369084I59J-1575D01*
G02X525196Y367922I-2015J1163D01*
G01X525026D01*
G02X523096Y369084I85J2325D01*
G03X521766Y369871I-1364J-788D01*
G03X521684I-41J-1575D01*
G03X520465Y369233I48J-1575D01*
G03X520380Y369106I777J-612D01*
G02X518266Y367922I-2028J1141D01*
G02X516337Y369084I86J2325D01*
G03X515031Y369871I-1365J-788D01*
G01X514921D01*
G02X512932Y373317I51J2326D01*
G01X512957Y373359D01*
G03Y374933I-1365J787D01*
G02Y377259I2015J1163D01*
G03X512976Y378800I-1365J787D01*
G01X512957Y378834D01*
X512932Y378876D01*
G02X512957Y381159I2040J1119D01*
G03X511820Y383506I-1365J787D01*
G01X511592Y383278D01*
Y381947D01*
G01X544908Y417304D02*
X544969Y417243D01*
Y416961D01*
X551312Y410617D01*
Y403852D01*
G02X551007Y402508I-2320J-180D01*
G03X550738Y401500I1749J-1007D01*
G01X550737Y401501D01*
Y396949D01*
G03X550787Y396768I353J0D01*
G01X550792Y396760D01*
X550817Y396718D01*
G02X550792Y394435I-2040J-1119D01*
G03X550773Y392894I1365J-787D01*
G01X550792Y392860D01*
X550817Y392818D01*
G02X550792Y390535I-2040J-1119D01*
G03X550773Y388994I1365J-787D01*
G01X550792Y388960D01*
G02X550817Y386677I-2015J-1164D01*
G01X550792Y386635D01*
G03Y385061I1365J-787D01*
G01X550816Y385018D01*
G02X549148Y381601I-2040J-1120D01*
G02X548861Y381573I-369J2297D01*
G01X548732D01*
G03X547411Y380785I44J-1575D01*
G02X545466Y379622I-2015J1162D01*
G01X545347D01*
G03X544026Y378834I44J-1575D01*
G02X542081Y377671I-2015J1162D01*
G01X541941D01*
G02X539996Y378834I70J2325D01*
G03X538675Y379622I-1365J-787D01*
G01X538546D01*
G02X536616Y380784I85J2325D01*
G03X535310Y381571I-1365J-788D01*
G01X535192D01*
G03X533886Y380784I59J-1575D01*
G02X531956Y379622I-2015J1163D01*
G01X531827D01*
G03X530506Y378834I44J-1575D01*
G02X528561Y377671I-2015J1162D01*
G01X528432D01*
G03X527126Y376884I59J-1575D01*
G02X525198Y375722I-2015J1163D01*
G02X525024I-87J2325D01*
G02X523096Y376884I87J2325D01*
G03X521789Y377671I-1365J-788D01*
G03X520380Y376906I-58J-1573D01*
G01X520367Y376883D01*
G02X518609Y375734I-2015J1164D01*
G01X518352Y375477D01*
Y374146D01*
G01X566881Y366601D02*
X566820Y366540D01*
X566537D01*
X556219Y356222D01*
X552066D01*
G02X550136Y357384I85J2325D01*
G03X548830Y358171I-1365J-788D01*
G01X548712D01*
G03X547406Y357384I59J-1575D01*
G02X545476Y356222I-2015J1163D01*
G01X545347D01*
G03X544026Y355434I44J-1575D01*
G02X542081Y354271I-2015J1162D01*
G01X541941D01*
G02X539996Y355434I70J2325D01*
G03X538675Y356222I-1365J-787D01*
G01X538546D01*
G02X536616Y357384I85J2325D01*
G03X535310Y358171I-1365J-788D01*
G01X535192D01*
G03X533886Y357384I59J-1575D01*
G02X531956Y356222I-2015J1163D01*
G01X531827D01*
G03X530506Y355434I44J-1575D01*
G02X528561Y354271I-2015J1162D01*
G01X528432D01*
G03X527126Y353484I59J-1575D01*
G02X525196Y352322I-2015J1163D01*
G01X525067D01*
G03X523746Y351534I44J-1575D01*
G02X519716I-2015J1162D01*
G01X519703Y351557D01*
G03X518352Y352322I-1351J-810D01*
G01X518267D01*
G02X516337Y353484I85J2325D01*
G03X515031Y354271I-1365J-788D01*
G01X514902D01*
G02X512957Y355434I70J2325D01*
G03X511636Y356222I-1365J-787D01*
G01X511507D01*
G02X509577Y357384I85J2325D01*
G03X508271Y358171I-1365J-788D01*
G01X508142D01*
G02X506197Y359334I70J2325D01*
G03X504876Y360122I-1365J-787D01*
G01X504747D01*
G02X502817Y361284I85J2325D01*
G03X501511Y362071I-1365J-788D01*
G01X501382D01*
G02X499437Y363234I70J2325D01*
G03X498116Y364022I-1365J-787D01*
G01X497987D01*
G02X496057Y365184I85J2325D01*
G03X494751Y365971I-1365J-788D01*
G01X494622D01*
G02X492677Y369459I70J2325D01*
G03X492696Y371000I-1365J787D01*
G01X492677Y371034D01*
G02X492652Y373317I2015J1164D01*
G01X492677Y373359D01*
G03Y374933I-1365J787D01*
G02Y377259I2015J1163D01*
G03X492696Y378800I-1365J787D01*
G01X492677Y378834D01*
X492652Y378876D01*
G02X492677Y381159I2040J1119D01*
G03X492696Y382700I-1365J787D01*
G01X492677Y382734D01*
X492652Y382776D01*
G02X492677Y385059I2040J1119D01*
G03X492696Y386600I-1365J787D01*
G01X492677Y386634D01*
X492652Y386676D01*
G02X492677Y388959I2040J1119D01*
G03X492696Y390500I-1365J787D01*
G01X492677Y390534D01*
X492652Y390576D01*
G02X494641Y394022I2040J1120D01*
G01X494736D01*
G03X496057Y394810I-44J1575D01*
G02X497987Y395972I2015J-1163D01*
G01X498143D01*
G03X499437Y396759I-71J1574D01*
G02X503467I2015J-1162D01*
G03X504761Y395972I1365J787D01*
G01X504903D01*
G03X506069Y396571I-72J1574D01*
G01X505986Y396881D01*
X504832Y397546D01*
G01Y393647D02*
G03X501365Y394021I-3015J-11696D01*
G03X499437Y392859I87J-2325D01*
G02X498131Y392072I-1365J788D01*
G01X498002D01*
G03X496057Y388584I70J-2325D01*
G02X496076Y387043I-1365J-787D01*
G01X496057Y387009D01*
X496032Y386967D01*
G03X496057Y384684I2040J-1119D01*
G02X496076Y383143I-1365J-787D01*
G01X496057Y383109D01*
X496032Y383067D01*
G03X496057Y380784I2040J-1119D01*
G02X496076Y379243I-1365J-787D01*
G01X496057Y379209D01*
X496032Y379167D01*
G03X496057Y376884I2040J-1119D01*
G02X496076Y375343I-1365J-787D01*
G01X496057Y375309D01*
G03X496032Y373026I2015J-1164D01*
G01X496057Y372984D01*
G02Y371410I-1365J-787D01*
G03X497987Y367922I2015J-1163D01*
G01X498116D01*
G02X499437Y367134I-44J-1575D01*
G03X501382Y365971I2015J1162D01*
G01X501511D01*
G02X502817Y365184I-59J-1575D01*
G03X504747Y364022I2015J1163D01*
G01X504876D01*
G02X506197Y363234I-44J-1575D01*
G03X508142Y362071I2015J1162D01*
G01X508271D01*
G02X509577Y361284I-59J-1575D01*
G03X511507Y360122I2015J1163D01*
G01X511636D01*
G02X512957Y359334I-44J-1575D01*
G03X514902Y358171I2015J1162D01*
G01X515031D01*
G02X516337Y357384I-59J-1575D01*
G03X518267Y356222I2015J1163D01*
G01X518352D01*
G02X519703Y355457I0J-1575D01*
G01X519716Y355434D01*
G03X523746I2015J1162D01*
G02X525067Y356222I1365J-787D01*
G01X525196D01*
G03X527126Y357384I-85J2325D01*
G02X528432Y358171I1365J-788D01*
G01X528561D01*
G03X530506Y359334I-70J2325D01*
G02X531827Y360122I1365J-787D01*
G01X531956D01*
G03X533886Y361284I-85J2325D01*
G02X535192Y362071I1365J-788D01*
G01X535310D01*
G02X536616Y361284I-59J-1575D01*
G03X538546Y360122I2015J1163D01*
G01X538675D01*
G02X539996Y359334I-44J-1575D01*
G03X541941Y358171I2015J1162D01*
G01X542081D01*
G03X544026Y359334I-70J2325D01*
G02X545347Y360122I1365J-787D01*
G01X545476D01*
G03X547406Y361284I-85J2325D01*
G02X548712Y362071I1365J-788D01*
G01X548825D01*
G03X550786Y363234I-54J2325D01*
G02X552150Y364022I1364J-786D01*
G01X554396D01*
X558294Y367920D01*
X562776D01*
X564150Y369294D01*
X564431D01*
X564492Y369355D01*
G01X511592Y393647D02*
X510438Y392981D01*
X510344Y392629D01*
G02X508282Y389371I-2131J-933D01*
G01X508153D01*
G03X506847Y388584I59J-1575D01*
G02X504917Y387422I-2015J1163D01*
G01X504747D01*
G02X502817Y388584I85J2325D01*
G03X501511Y389371I-1365J-788D01*
G01X501393D01*
G03X500068Y387043I59J-1575D01*
G01X500087Y387009D01*
X500112Y386967D01*
G02X500087Y384684I-2040J-1119D01*
G03X500068Y383143I1365J-787D01*
G01X500087Y383109D01*
X500112Y383067D01*
G02X500087Y380784I-2040J-1119D01*
G03X500068Y379243I1365J-787D01*
G01X500087Y379209D01*
X500112Y379167D01*
G02X500087Y376884I-2040J-1119D01*
G03X500068Y375343I1365J-787D01*
G01X500087Y375309D01*
G02X500112Y373026I-2015J-1164D01*
G01X500087Y372984D01*
G03X501408Y370622I1365J-787D01*
G01X501503D01*
G02X503467Y369459I-51J-2326D01*
G03X504773Y368672I1365J788D01*
G01X504902D01*
G02X506847Y367509I-70J-2325D01*
G03X508168Y366721I1365J787D01*
G01X508297D01*
G02X510227Y365559I-85J-2325D01*
G03X511533Y364772I1365J788D01*
G01X511662D01*
G02X513607Y363609I-70J-2325D01*
G03X514928Y362821I1365J787D01*
G01X515057D01*
G02X516987Y361659I-85J-2325D01*
G03X518293Y360872I1365J788D01*
G01X518422D01*
G02X520367Y359709I-70J-2325D01*
G01X520380Y359686D01*
G03X521684Y358921I1351J810D01*
G03X523096Y359709I47J1575D01*
G02X525041Y360872I2015J-1162D01*
G01X525170D01*
G03X526476Y361659I-59J1575D01*
G02X528406Y362821I2015J-1163D01*
G01X528535D01*
G03X529856Y363609I-44J1575D01*
G02X531801Y364772I2015J-1162D01*
G01X531930D01*
G03X533236Y365559I-59J1575D01*
G02X535166Y366721I2015J-1163D01*
G01X535336D01*
G02X537266Y365559I-85J-2325D01*
G03X538572Y364772I1365J788D01*
G01X538701D01*
G02X540646Y363609I-70J-2325D01*
G03X541967Y362821I1365J787D01*
G01X542055D01*
G03X543376Y363609I-44J1575D01*
G02X545321Y364772I2015J-1162D01*
G01X545450D01*
G03X546756Y365559I-59J1575D01*
G02X548686Y366721I2015J-1163D01*
G02X548741Y366722I55J-1497D01*
G01X548844D01*
G03X550138Y367509I-71J1574D01*
G02X552083Y368672I2015J-1162D01*
G01X552224D01*
G03X553518Y369459I-71J1574D01*
G02X555482Y370622I2015J-1163D01*
G01X555592D01*
G03X556898Y371409I-59J1575D01*
G02X558909Y372570I2011J-1160D01*
G01X560577D01*
X561071Y373064D01*
Y373618D01*
X561567Y374114D01*
X562121D01*
X562623Y374616D01*
Y375154D01*
X563119Y375650D01*
X563657D01*
X564130Y376123D01*
Y376823D01*
X563732Y377221D01*
Y377921D01*
X564130Y378319D01*
Y379019D01*
X563732Y379417D01*
Y380117D01*
X564130Y380515D01*
Y381215D01*
X563732Y381613D01*
Y382313D01*
X564130Y382711D01*
Y383411D01*
X563732Y383809D01*
Y384509D01*
X564130Y384907D01*
Y386277D01*
X563930Y386477D01*
Y386564D01*
G01X566067Y367414D02*
Y367415D01*
X566006Y367354D01*
Y367070D01*
X563673Y364737D01*
X563109D01*
X562614Y364242D01*
Y363678D01*
X562120Y363184D01*
X561556D01*
X561061Y362689D01*
Y362125D01*
X560567Y361631D01*
X560003D01*
X559508Y361136D01*
Y360572D01*
X559014Y360078D01*
X558450D01*
X557955Y359583D01*
Y359019D01*
X557461Y358525D01*
X556897D01*
X556402Y358030D01*
Y357466D01*
X555908Y356972D01*
X554908D01*
X554510Y357370D01*
X553810D01*
X553412Y356972D01*
X552092D01*
G02X550786Y357759I59J1575D01*
G03X548856Y358921I-2015J-1163D01*
G01X548686D01*
G03X546756Y357759I85J-2325D01*
G02X545450Y356972I-1365J788D01*
G01X545321D01*
G03X543376Y355809I70J-2325D01*
G02X542058Y355021I-1365J787D01*
G02X541964I-47J1575D01*
G02X540646Y355809I47J1575D01*
G03X538701Y356972I-2015J-1162D01*
G01X538572D01*
G02X537266Y357759I59J1575D01*
G03X535336Y358921I-2015J-1163D01*
G01X535166D01*
G03X533236Y357759I85J-2325D01*
G02X531930Y356972I-1365J788D01*
G01X531801D01*
G03X529856Y355809I70J-2325D01*
G02X528535Y355021I-1365J787D01*
G01X528406D01*
G03X526476Y353859I85J-2325D01*
G02X525170Y353072I-1365J788D01*
G01X525041D01*
G03X523096Y351909I70J-2325D01*
G02X520380Y351886I-1365J786D01*
G01X520367Y351909D01*
G03X518422Y353072I-2015J-1162D01*
G01X518293D01*
G02X516987Y353859I59J1575D01*
G03X515057Y355021I-2015J-1163D01*
G01X514928D01*
G02X513607Y355809I44J1575D01*
G03X511662Y356972I-2015J-1162D01*
G01X511533D01*
G02X510227Y357759I59J1575D01*
G03X508297Y358921I-2015J-1163D01*
G01X508168D01*
G02X506847Y359709I44J1575D01*
G03X504902Y360872I-2015J-1162D01*
G01X504773D01*
G02X503467Y361659I59J1575D01*
G03X501537Y362821I-2015J-1163D01*
G01X501408D01*
G02X500087Y363609I44J1575D01*
G03X498142Y364772I-2015J-1162D01*
G01X498013D01*
G02X496707Y365559I59J1575D01*
G03X494777Y366721I-2015J-1163D01*
G01X494648D01*
G02X493327Y369084I44J1575D01*
G03Y371410I-2015J1163D01*
G02Y372984I1365J787D01*
G01X493352Y373026D01*
G03X493327Y375309I-2040J1119D01*
G01X493308Y375343D01*
G02X493327Y376884I1384J754D01*
G03X493352Y379167I-2015J1164D01*
G01X493327Y379209D01*
X493308Y379243D01*
G02X493327Y380784I1384J754D01*
G03X493352Y383067I-2015J1164D01*
G01X493327Y383109D01*
X493308Y383143D01*
G02X493327Y384684I1384J754D01*
G03X493352Y386967I-2015J1164D01*
G01X493327Y387009D01*
X493308Y387043D01*
G02X493327Y388584I1384J754D01*
G03X493352Y390867I-2015J1164D01*
G01X493327Y390909D01*
X493308Y390943D01*
G02X494633Y393271I1384J753D01*
G01X494743D01*
G03X496707Y394434I-51J2326D01*
G02X498001Y395221I1365J-787D01*
G01X498142D01*
G03X500087Y396384I-70J2325D01*
G02X502817I1365J-787D01*
G03X504762Y395221I2015J1162D01*
G01X504902D01*
G03X506706Y396167I-69J2325D01*
G01X507058Y396262D01*
X508212Y395597D01*
G01X504832Y389747D02*
Y390957D01*
G03X504568Y391594I-901J0D01*
G01X503867Y392295D01*
G03X501511Y393271I-2356J-2356D01*
G01X501393D01*
G03X500087Y392484I59J-1575D01*
G02X498157Y391322I-2015J1163D01*
G01X498028D01*
G03X496707Y388959I44J-1575D01*
G02X496732Y386676I-2015J-1164D01*
G01X496707Y386634D01*
X496688Y386600D01*
G03X496707Y385059I1384J-754D01*
G02X496732Y382776I-2015J-1164D01*
G01X496707Y382734D01*
X496688Y382700D01*
G03X496707Y381159I1384J-754D01*
G02X496732Y378876I-2015J-1164D01*
G01X496707Y378834D01*
X496688Y378800D01*
G03X496707Y377259I1384J-754D01*
G02Y374933I-2015J-1163D01*
G03Y373359I1365J-787D01*
G01X496732Y373317D01*
G02X496707Y371034I-2040J-1119D01*
G01X496688Y371000D01*
G03X498013Y368672I1384J-753D01*
G01X498142D01*
G02X500087Y367509I-70J-2325D01*
G03X501408Y366721I1365J787D01*
G01X501537D01*
G02X503467Y365559I-85J-2325D01*
G03X504773Y364772I1365J788D01*
G01X504902D01*
G02X506847Y363609I-70J-2325D01*
G03X508168Y362821I1365J787D01*
G01X508297D01*
G02X510227Y361659I-85J-2325D01*
G03X511533Y360872I1365J788D01*
G01X511662D01*
G02X513607Y359709I-70J-2325D01*
G03X514928Y358921I1365J787D01*
G01X515057D01*
G02X516987Y357759I-85J-2325D01*
G03X518293Y356972I1365J788D01*
G01X518422D01*
G02X520367Y355809I-70J-2325D01*
G01X520380Y355786D01*
G03X523096Y355809I1351J810D01*
G02X525041Y356972I2015J-1162D01*
G01X525170D01*
G03X526476Y357759I-59J1575D01*
G02X528406Y358921I2015J-1163D01*
G01X528535D01*
G03X529856Y359709I-44J1575D01*
G02X531801Y360872I2015J-1162D01*
G01X531930D01*
G03X533236Y361659I-59J1575D01*
G02X535166Y362821I2015J-1163D01*
G01X535336D01*
G02X537266Y361659I-85J-2325D01*
G03X538572Y360872I1365J788D01*
G01X538701D01*
G02X540646Y359709I-70J-2325D01*
G03X541964Y358921I1365J787D01*
G03X542058I47J1575D01*
G03X543376Y359709I-47J1575D01*
G02X545321Y360872I2015J-1162D01*
G01X545450D01*
G03X546756Y361659I-59J1575D01*
G02X548686Y362821I2015J-1163D01*
G01X548815D01*
G03X550136Y363609I-44J1575D01*
G02X552149Y364772I2013J-1161D01*
G01X554085D01*
X554578Y365265D01*
Y365746D01*
X555074Y366242D01*
X555555D01*
X556049Y366736D01*
Y367217D01*
X556545Y367713D01*
X557026D01*
X557983Y368670D01*
X560309D01*
X560576Y368937D01*
X561276D01*
X561543Y368670D01*
X562464D01*
X563618Y369824D01*
Y370108D01*
X563679Y370169D01*
G01X508212Y391696D02*
X509366Y392362D01*
X509676Y392278D01*
G02X508256Y390121I-1465J-582D01*
G01X508127D01*
G03X506197Y388959I85J-2325D01*
G02X504891Y388172I-1365J788D01*
G01X504773D01*
G02X503467Y388959I59J1575D01*
G03X501537Y390121I-2015J-1163D01*
G01X501367D01*
G03X499412Y386676I85J-2325D01*
G01X499437Y386634D01*
X499456Y386600D01*
G02X499437Y385059I-1384J-754D01*
G03X499412Y382776I2015J-1164D01*
G01X499437Y382734D01*
X499456Y382700D01*
G02X499437Y381159I-1384J-754D01*
G03X499412Y378876I2015J-1164D01*
G01X499437Y378834D01*
X499456Y378800D01*
G02X499437Y377259I-1384J-754D01*
G03Y374933I2015J-1163D01*
G02Y373359I-1365J-787D01*
G01X499412Y373317D01*
G03X501401Y369871I2040J-1120D01*
G01X501511D01*
G02X502817Y369084I-59J-1575D01*
G03X504747Y367922I2015J1163D01*
G01X504876D01*
G02X506197Y367134I-44J-1575D01*
G03X508142Y365971I2015J1162D01*
G01X508271D01*
G02X509577Y365184I-59J-1575D01*
G03X511507Y364022I2015J1163D01*
G01X511636D01*
G02X512957Y363234I-44J-1575D01*
G03X514902Y362071I2015J1162D01*
G01X515031D01*
G02X516337Y361284I-59J-1575D01*
G03X518267Y360122I2015J1163D01*
G01X518352D01*
G02X519703Y359357I0J-1575D01*
G01X519716Y359334D01*
G03X521662Y358171I2015J1162D01*
G03X523746Y359334I69J2325D01*
G02X525067Y360122I1365J-787D01*
G01X525196D01*
G03X527126Y361284I-85J2325D01*
G02X528432Y362071I1365J-788D01*
G01X528561D01*
G03X530506Y363234I-70J2325D01*
G02X531827Y364022I1365J-787D01*
G01X531956D01*
G03X533886Y365184I-85J2325D01*
G02X535192Y365971I1365J-788D01*
G01X535310D01*
G02X536616Y365184I-59J-1575D01*
G03X538546Y364022I2015J1163D01*
G01X538675D01*
G02X539996Y363234I-44J-1575D01*
G03X541941Y362071I2015J1162D01*
G01X542081D01*
G03X544026Y363234I-70J2325D01*
G02X545347Y364022I1365J-787D01*
G01X545476D01*
G03X547406Y365184I-85J2325D01*
G02X548702Y365971I1365J-788D01*
G01X548843D01*
G03X550788Y367134I-70J2325D01*
G02X552082Y367921I1365J-787D01*
G01X552238D01*
G03X554168Y369083I-85J2325D01*
G02X555489Y369871I1365J-787D01*
G01X555525Y369872D01*
X555605D01*
G03X557548Y371034I-72J2325D01*
G02X558909Y371820I1361J-785D01*
G01X560888D01*
X564880Y375812D01*
Y386277D01*
X565080Y386477D01*
Y386564D01*
G01X1493375Y436786D02*
X1492044D01*
X1491788Y437042D01*
G03X1490638Y438801I-2312J-256D01*
G02X1489850Y440122I787J1365D01*
G01Y440251D01*
G03X1488688Y442181I-2325J-85D01*
G01X1488108Y442515D01*
G02X1487763Y443521I1367J1031D01*
G01Y446098D01*
X1485750Y448111D01*
Y455024D01*
X1483980Y456794D01*
X1482265D01*
X1477919Y461140D01*
Y466182D01*
X1478119Y466382D01*
Y466469D01*
G01X1476969D02*
Y466382D01*
X1477169Y466182D01*
Y460829D01*
X1481954Y456044D01*
X1483669D01*
X1485000Y454713D01*
Y447800D01*
X1487013Y445787D01*
Y443516D01*
G03X1487611Y441936I2462J29D01*
G01X1488312Y441531D01*
G02X1489100Y440210I-787J-1365D01*
G01Y440081D01*
G03X1490262Y438151I2325J85D01*
G02X1491034Y437014I-787J-1365D01*
G01X1490806Y436786D01*
X1489475D01*
G01X518352Y405347D02*
Y404016D01*
X518095Y403759D01*
G03X516337Y402609I257J-2312D01*
G02X513607I-1365J787D01*
G03X511592Y403772I-2013J-1161D01*
G01X509376D01*
X509176Y403972D01*
X509089D01*
G01X518352Y401447D02*
Y402778D01*
X518124Y403006D01*
G03X516987Y402234I228J-1559D01*
G02X512957I-2015J1161D01*
G03X511593Y403022I-1364J-786D01*
G01X509376D01*
X509176Y402822D01*
X509089D01*
G01X548120Y417511D02*
X548181Y417450D01*
X548463D01*
X549279Y416634D01*
Y416070D01*
X549774Y415575D01*
X550338D01*
X550832Y415081D01*
Y414517D01*
X551327Y414022D01*
X551891D01*
X552385Y413528D01*
Y412964D01*
X552880Y412469D01*
X553444D01*
X553938Y411975D01*
Y410695D01*
X553540Y410297D01*
Y409597D01*
X553938Y409199D01*
Y408499D01*
X553540Y408101D01*
Y407401D01*
X553938Y407003D01*
Y406303D01*
X553540Y405905D01*
Y405205D01*
X553938Y404807D01*
Y404058D01*
X553589Y403709D01*
Y403009D01*
X553938Y402660D01*
Y401911D01*
X553941Y401875D01*
G02X553737Y400932I-1569J-154D01*
G03X553209Y398960I3421J-1973D01*
G01Y397847D01*
X552907Y397545D01*
Y396845D01*
X553209Y396543D01*
Y395731D01*
X553208Y395728D01*
G03X553492Y394476I2323J-131D01*
G01X553517Y394434D01*
X553536Y394400D01*
G02X553517Y392859I-1384J-754D01*
G03X553492Y390576I2015J-1164D01*
G01X553517Y390534D01*
X553536Y390500D01*
G02X553517Y388959I-1384J-754D01*
G03Y386633I2015J-1163D01*
G02Y385059I-1365J-787D01*
G01X553492Y385017D01*
G03X553517Y382734I2040J-1119D01*
G01X553536Y382700D01*
G02X552403Y380392I-1385J-752D01*
G02X552210Y380372I-259J1554D01*
G01X552081D01*
G03X550136Y379209I70J-2325D01*
G02X548815Y378421I-1365J787D01*
G01X548686D01*
G03X546756Y377259I85J-2325D01*
G02X545450Y376472I-1365J788D01*
G01X545340D01*
G03X543376Y375309I51J-2326D01*
G02X542082Y374522I-1365J787D01*
G01X541940D01*
G02X540646Y375309I71J1574D01*
G03X538682Y376472I-2015J-1163D01*
G01X538572D01*
G02X537266Y377259I59J1575D01*
G03X535336Y378421I-2015J-1163D01*
G01X535166D01*
G03X533236Y377259I85J-2325D01*
G02X531930Y376472I-1365J788D01*
G01X531820D01*
G03X529856Y375309I51J-2326D01*
G02X528562Y374522I-1365J787D01*
G01X528421D01*
G03X526476Y373359I70J-2325D01*
G02X525182Y372572I-1365J787D01*
G01X525040D01*
G02X523746Y373359I71J1574D01*
G03X521801Y374522I-2015J-1162D01*
G01X521661D01*
G03X519716Y373359I70J-2325D01*
G02X518400Y372572I-1364J787D01*
G01X518281D01*
G02X516987Y373359I71J1574D01*
G02Y374933I1365J787D01*
G03Y377259I-2015J1163D01*
G02X516968Y378800I1365J787D01*
G01X516987Y378834D01*
X517012Y378876D01*
G03X516987Y381159I-2040J1119D01*
G02X516968Y382700I1365J787D01*
G01X516987Y382734D01*
X517012Y382776D01*
G03X517104Y384829I-2039J1120D01*
G01X517198Y385181D01*
X518352Y385847D01*
G01Y381947D02*
X519505Y381282D01*
X519857Y381377D01*
G02X521816Y382321I1874J-1384D01*
G02X523746Y381159I-85J-2325D01*
G03X525052Y380372I1365J788D01*
G01X525170D01*
G03X526476Y381159I-59J1575D01*
G02X528406Y382321I2015J-1163D01*
G01X528535D01*
G03X529856Y383109I-44J1575D01*
G02X531801Y384272I2015J-1162D01*
G01X531930D01*
G03X533236Y385059I-59J1575D01*
G02X535166Y386221I2015J-1163D01*
G01X535336D01*
G02X537266Y385059I-85J-2325D01*
G03X538572Y384272I1365J788D01*
G01X538701D01*
G02X540646Y383109I-70J-2325D01*
G03X541967Y382321I1365J787D01*
G01X542055D01*
G03X543376Y383109I-44J1575D01*
G01X543395Y383143D01*
G03X543376Y384684I-1384J754D01*
G02X545321Y388172I2015J1163D01*
G01X545450D01*
G03X545643Y388192I-66J1574D01*
G03X546776Y390500I-252J1556D01*
G01X546757Y390534D01*
G02X546732Y392817I2015J1164D01*
G01X546757Y392859D01*
G03Y394433I-1365J787D01*
G01X546752Y394443D01*
X546731Y394480D01*
G02X546757Y396759I2041J1116D01*
G03X547036Y397798I-1794J1039D01*
G01Y399286D01*
X546745Y399577D01*
Y400277D01*
X547036Y400568D01*
Y402232D01*
G03X546951Y402553I-653J-1D01*
G02X546977Y404832I2041J1116D01*
G03X547183Y405750I-1365J788D01*
G01X547181Y405781D01*
Y406593D01*
X546922Y406852D01*
Y407552D01*
X547181Y407811D01*
Y409065D01*
X546687Y409559D01*
X546206D01*
X545710Y410055D01*
Y410536D01*
X545216Y411030D01*
X544735D01*
X544239Y411526D01*
Y412007D01*
X543745Y412501D01*
X543264D01*
X542768Y412997D01*
Y413478D01*
X542274Y413972D01*
X541793D01*
X541297Y414468D01*
Y414949D01*
X527996Y428250D01*
X526326D01*
X526126Y428050D01*
X526039D01*
G01X548934Y418325D02*
X548995Y418264D01*
Y417980D01*
X554688Y412287D01*
Y401948D01*
G02X554387Y400557I-2316J-227D01*
G03X553959Y398959I2771J-1598D01*
G01Y395713D01*
X553958Y395691D01*
X553959D01*
G03X554148Y394843I1573J-94D01*
G01X554167Y394809D01*
X554192Y394767D01*
G02X554167Y392484I-2040J-1119D01*
G03X554148Y390943I1365J-787D01*
G01X554167Y390909D01*
X554192Y390867D01*
G02X554167Y388584I-2040J-1119D01*
G03X554148Y387043I1365J-787D01*
G01X554167Y387009D01*
G02X554192Y384726I-2015J-1164D01*
G01X554167Y384684D01*
G03Y383110I1365J-787D01*
G01X554191Y383067D01*
G02X552523Y379650I-2040J-1120D01*
G02X552236Y379622I-369J2297D01*
G01X552107D01*
G03X550786Y378834I44J-1575D01*
G02X548841Y377671I-2015J1162D01*
G01X548712D01*
G03X547406Y376884I59J-1575D01*
G02X545442Y375721I-2015J1163D01*
G01X545347D01*
G03X544026Y374933I44J-1575D01*
G02X542096Y373771I-2015J1163D01*
G01X541926D01*
G02X539996Y374933I85J2325D01*
G03X538675Y375721I-1365J-787D01*
G01X538580D01*
G02X536616Y376884I51J2326D01*
G03X535310Y377671I-1365J-788D01*
G01X535192D01*
G03X533886Y376884I59J-1575D01*
G02X531922Y375721I-2015J1163D01*
G01X531827D01*
G03X530506Y374933I44J-1575D01*
G02X528576Y373771I-2015J1163D01*
G01X528420D01*
G03X527126Y372984I71J-1574D01*
G02X525181Y371821I-2015J1162D01*
G01X525041D01*
G02X523096Y372984I70J2325D01*
G03X521802Y373771I-1365J-787D01*
G01X521683D01*
G03X520367Y372984I48J-1574D01*
G02X518422Y371821I-2015J1162D01*
G01X518282D01*
G02X516337Y372984I70J2325D01*
G01X516312Y373026D01*
G02X516337Y375309I2040J1119D01*
G01X516356Y375343D01*
G03X516337Y376884I-1384J754D01*
G02X516312Y379167I2015J1164D01*
G01X516337Y379209D01*
X516356Y379243D01*
G03X516337Y380784I-1384J754D01*
G02X516312Y383067I2015J1164D01*
G01X516337Y383109D01*
X516356Y383143D01*
G03X516436Y384478I-1385J753D01*
G01X516126Y384562D01*
X514972Y383896D01*
G01X526039Y429200D02*
X526126D01*
X526326Y429000D01*
X528307D01*
X547931Y409376D01*
Y405812D01*
G02X547627Y404457I-2319J-191D01*
G03X547608Y402916I1365J-787D01*
G02X547786Y402232I-1225J-684D01*
G01Y397797D01*
G02X547407Y396384I-2824J0D01*
G03X547388Y394843I1365J-787D01*
G01X547407Y394809D01*
G02X547432Y392526I-2015J-1164D01*
G01X547407Y392484D01*
G03Y390910I1365J-787D01*
G01X547431Y390867D01*
G02X545763Y387450I-2040J-1120D01*
G02X545476Y387422I-369J2297D01*
G01X545347D01*
G03X544026Y385059I44J-1575D01*
G02X544051Y382776I-2015J-1164D01*
G01X544026Y382734D01*
G02X542081Y381571I-2015J1162D01*
G01X541941D01*
G02X539996Y382734I70J2325D01*
G03X538675Y383522I-1365J-787D01*
G01X538546D01*
G02X536616Y384684I85J2325D01*
G03X535310Y385471I-1365J-788D01*
G01X535192D01*
G03X533886Y384684I59J-1575D01*
G02X531956Y383522I-2015J1163D01*
G01X531827D01*
G03X530506Y382734I44J-1575D01*
G02X528561Y381571I-2015J1162D01*
G01X528432D01*
G03X527126Y380784I59J-1575D01*
G02X525196Y379622I-2015J1163D01*
G01X525026D01*
G02X523096Y380784I85J2325D01*
G03X521789Y381570I-1364J-788D01*
G03X520495Y380971I-57J-1574D01*
G01X520578Y380661D01*
X521731Y379996D01*
G01X513092Y409057D02*
X513179D01*
X513379Y408857D01*
X519794D01*
X523274Y405378D01*
X523566Y404870D01*
X524056Y404736D01*
X525111Y405347D01*
G01X512230Y410506D02*
X512317D01*
X512517Y410706D01*
X513738D01*
X514013Y410431D01*
X514713D01*
X514988Y410706D01*
X515753D01*
X516093Y410366D01*
X516793D01*
X517133Y410706D01*
X517833D01*
X518173Y410366D01*
X518873D01*
X519213Y410706D01*
X519913D01*
X520253Y410366D01*
X520953D01*
X521293Y410706D01*
X521993D01*
X522499Y410200D01*
Y409720D01*
X522995Y409224D01*
X523475D01*
X523969Y408730D01*
Y408249D01*
X524465Y407753D01*
X524946D01*
X526700Y405999D01*
Y404948D01*
X526589Y404755D01*
X526588Y404753D01*
X526475Y404559D01*
G03X526451Y402276I2016J-1163D01*
G01X526476Y402234D01*
X526495Y402200D01*
G02X526575Y400865I-1385J-753D01*
G01X526265Y400781D01*
X525600Y401165D01*
X525111Y401447D01*
G01X528491Y395597D02*
X529645Y396262D01*
X529739Y396613D01*
G02X529856Y398709I2132J932D01*
G01X529875Y398743D01*
G03X529856Y400284I-1384J754D01*
G02X529831Y402567I2015J1164D01*
G01X529856Y402609D01*
X529875Y402643D01*
G03X529856Y404183I-1384J753D01*
G01X529220Y405284D01*
Y407093D01*
X528657Y407656D01*
X528176D01*
X527680Y408152D01*
Y408633D01*
X527186Y409127D01*
X526705D01*
X526209Y409623D01*
Y410104D01*
X525699Y410614D01*
X525251D01*
X524755Y411110D01*
Y411558D01*
X522738Y413575D01*
X520158D01*
X519958Y413375D01*
X519871D01*
G01X535251Y399496D02*
Y398165D01*
X535023Y397937D01*
G02X533886Y400284I228J1559D01*
G03X533911Y402567I-2015J1164D01*
G01X533886Y402609D01*
X533867Y402643D01*
G02X533886Y404184I1384J754D01*
G01X534043Y404456D01*
X534045Y404459D01*
X534301Y404904D01*
Y406399D01*
X523541Y417159D01*
X521147D01*
X520947Y417359D01*
X520860D01*
G01X531871Y393647D02*
X533025Y392981D01*
X533377Y393076D01*
G02X535200Y394022I1873J-1380D01*
G01X535246D01*
X535247Y394021D01*
X535292D01*
G03X536614Y394804I-41J1576D01*
G01X536620Y394816D01*
X536621Y394817D01*
G03X536980Y396318I-2957J1501D01*
G01Y397393D01*
G03X536931Y399301I-37171J0D01*
G03X536642Y400240I-2004J-103D01*
G01X536641D01*
G02X536587Y402559I1989J1206D01*
G01X536955Y403234D01*
X536956Y403235D01*
Y404233D01*
X535750Y405439D01*
Y407974D01*
X535192Y408532D01*
X534628D01*
X534133Y409027D01*
Y409591D01*
X533639Y410085D01*
X533075D01*
X532580Y410580D01*
Y411144D01*
X532086Y411638D01*
X531522D01*
X531027Y412133D01*
Y412697D01*
X530533Y413191D01*
X529969D01*
X529474Y413686D01*
Y414250D01*
X528980Y414744D01*
X528416D01*
X527921Y415239D01*
Y415803D01*
X524582Y419142D01*
X521951D01*
X521751Y418942D01*
X521664D01*
G01X523118Y423396D02*
X523205D01*
X523405Y423196D01*
X525064D01*
X541070Y407190D01*
Y401881D01*
G02X540642Y400283I-3197J0D01*
G03X540623Y398742I1365J-787D01*
G01X540642Y398708D01*
G02X540667Y396425I-2015J-1164D01*
G02X540647Y396384I-306J124D01*
G03Y394810I1365J-787D01*
G01X540671Y394767D01*
G02X539003Y391350I-2040J-1120D01*
G02X538716Y391322I-369J2297D01*
G01X538587D01*
G03X537167Y389165I45J-1575D01*
G01X537477Y389081D01*
X538631Y389747D01*
G01X524063Y424917D02*
X524150D01*
X524350Y425117D01*
X526548D01*
X538681Y412984D01*
Y412551D01*
X539177Y412055D01*
X539610D01*
X540120Y411545D01*
Y411064D01*
X540616Y410568D01*
X541097D01*
X541591Y410074D01*
Y409593D01*
X542087Y409097D01*
X542568D01*
X543062Y408603D01*
Y407699D01*
X542803Y407440D01*
Y406740D01*
X543062Y406481D01*
Y405684D01*
X542722Y405344D01*
Y404644D01*
X543062Y404304D01*
Y403604D01*
X542722Y403264D01*
Y402564D01*
X543062Y402224D01*
Y401524D01*
G03X543391Y400249I2635J0D01*
G02X543376Y398709I-1369J-757D01*
G03X543351Y396426I2015J-1164D01*
G01X543376Y396384D01*
G02Y394810I-1365J-787D01*
G03Y392484I2015J-1163D01*
G02X543395Y390943I-1365J-787D01*
G01X543376Y390909D01*
G02X542055Y390121I-1365J787D01*
G01X541926D01*
G03X539971Y386676I85J-2325D01*
G01X539996Y386634D01*
X540015Y386600D01*
G02X540095Y385265I-1385J-753D01*
G01X539785Y385181D01*
X538631Y385847D01*
G01X521731Y403396D02*
X522793Y404010D01*
X522920Y404488D01*
X522673Y404917D01*
X520954Y406636D01*
X520473D01*
X519978Y407131D01*
Y407612D01*
X519483Y408107D01*
X518783D01*
X518443Y407767D01*
X517743D01*
X517403Y408107D01*
X516703D01*
X516363Y407767D01*
X515663D01*
X515323Y408107D01*
X513379D01*
X513179Y407907D01*
X513092D01*
G01X528491Y399496D02*
X527337Y400162D01*
X527243Y400514D01*
G03X527151Y402567I-2131J933D01*
G01X527126Y402609D01*
X527107Y402643D01*
G02X527126Y404184I1384J754D01*
G01X527450Y404746D01*
Y406310D01*
X522304Y411456D01*
X512517D01*
X512317Y411656D01*
X512230D01*
G01X531871Y397546D02*
X530717Y396881D01*
X530407Y396965D01*
G02X530506Y398333I1464J582D01*
G03Y400659I-2015J1163D01*
G02X530487Y402200I1365J787D01*
G01X530531Y402279D01*
X530534Y402284D01*
G03X530506Y404558I-2043J1112D01*
G01X529970Y405486D01*
Y407404D01*
X523049Y414325D01*
X520158D01*
X519958Y414525D01*
X519871D01*
G01X535251Y395597D02*
Y396928D01*
X534996Y397183D01*
G02X534914Y397193I241J2314D01*
G02X533236Y400659I337J2302D01*
G03X533255Y402200I-1365J787D01*
G01X533236Y402234D01*
X533211Y402276D01*
G02X533236Y404559I2040J1119D01*
G01X533393Y404831D01*
X533395Y404834D01*
X533551Y405105D01*
Y406088D01*
X523230Y416409D01*
X521147D01*
X520947Y416209D01*
X520860D01*
G01X535251Y391696D02*
X534097Y392362D01*
X534014Y392672D01*
G02X535192Y393271I1238J-976D01*
G01X535301D01*
G03X537266Y394433I-50J2326D01*
G01X537290Y394477D01*
X537285Y394467D01*
G03X537730Y396319I-3621J1849D01*
G01Y397393D01*
G03X537681Y399340I-37922J20D01*
G03X537280Y400635I-2753J-143D01*
G02X537247Y402200I1351J811D01*
G01X537706Y403043D01*
Y404544D01*
X536500Y405750D01*
Y408285D01*
X524893Y419892D01*
X521951D01*
X521751Y420092D01*
X521664D01*
G01X523118Y422246D02*
X523205D01*
X523405Y422446D01*
X524753D01*
X536474Y410725D01*
Y410245D01*
X536970Y409749D01*
X537450D01*
X538077Y409122D01*
Y408642D01*
X538573Y408146D01*
X539053D01*
X540320Y406879D01*
Y404186D01*
X540012Y403878D01*
Y403178D01*
X540320Y402870D01*
Y401880D01*
G02X539992Y400658I-2447J2D01*
G03X539964Y398383I2015J-1162D01*
G01X539992Y398332D01*
G02Y396758I-1365J-787D01*
G02X539972Y396717I-438J188D01*
G03X539997Y394434I2040J-1119D01*
G01X540016Y394400D01*
G02X538883Y392092I-1385J-752D01*
G02X538690Y392072I-259J1554D01*
G01X538561D01*
G03X536499Y388814I69J-2325D01*
G01X536405Y388462D01*
X535251Y387796D01*
G01X524063Y426067D02*
X524150D01*
X524350Y425867D01*
X526859D01*
X543812Y408914D01*
Y401530D01*
G03X544047Y400616I1895J0D01*
G02X544026Y398333I-2033J-1123D01*
G03Y396759I1365J-787D01*
G01X544051Y396717D01*
G02X544026Y394434I-2040J-1119D01*
G01X544007Y394400D01*
G03X544026Y392859I1384J-754D01*
G02Y390534I-2015J-1162D01*
G02X542081Y389371I-2015J1162D01*
G01X541952D01*
G03X540627Y387043I59J-1575D01*
G01X540646Y387009D01*
X540671Y386967D01*
G02X540763Y384914I-2039J-1120D01*
G01X540857Y384562D01*
X542011Y383896D01*
G01X564589Y334771D02*
X561934D01*
G03X561083Y333995I657J-1575D01*
G02X559610Y332790I-2172J1152D01*
G01X558541Y332711D01*
G03X557697Y331964I670J-1608D01*
G02X556428Y330871I-2166J1232D01*
G01X555472D01*
G03X554166Y330084I59J-1575D01*
G02X552236Y328922I-2015J1163D01*
G01X552107D01*
G03X550786Y328134I44J-1575D01*
G02X548841Y326971I-2015J1162D01*
G01X548712D01*
G03X547406Y326184I59J-1575D01*
G02X545442Y325021I-2015J1163D01*
G01X545347D01*
G03X544026Y324233I44J-1575D01*
G02X542096Y323071I-2015J1163D01*
G01X541967D01*
G03X540646Y322283I44J-1575D01*
G02X538716Y321121I-2015J1163D01*
G01X538560D01*
G03X537266Y320334I71J-1574D01*
G02X535321Y319171I-2015J1162D01*
G01X535192D01*
G03X533886Y318384I59J-1575D01*
G02X531956Y317222I-2015J1163D01*
G01X531827D01*
G03X530506Y316434I44J-1575D01*
G02X528561Y315271I-2015J1162D01*
G01X528432D01*
G03X527126Y314484I59J-1575D01*
G02X525196Y313322I-2015J1163D01*
G01X525067D01*
G03X523746Y312534I44J-1575D01*
G02X521801Y311371I-2015J1162D01*
G01X521683D01*
G03X520367Y310584I48J-1574D01*
G02X518437Y309422I-2015J1163D01*
G01X518308D01*
G03X516987Y308634I44J-1575D01*
G02X515023Y307471I-2015J1163D01*
G01X514913D01*
G03X513588Y305143I59J-1575D01*
G01X513607Y305109D01*
X513632Y305067D01*
G02X513607Y302784I-2040J-1119D01*
G03X513588Y301243I1365J-787D01*
G01X513607Y301209D01*
X513632Y301167D01*
G02X513607Y298884I-2040J-1119D01*
G03X513588Y297343I1365J-787D01*
G01X513607Y297309D01*
X513632Y297267D01*
G02X513607Y294984I-2040J-1119D01*
G03Y293408I1365J-788D01*
G02X513632Y291125I-2015J-1164D01*
G01X513607Y291083D01*
G03Y289509I1365J-787D01*
G01X513632Y289467D01*
G02X511677Y286022I-2040J-1120D01*
G01X511548D01*
G03X510227Y285234I44J-1575D01*
G02X508282Y284071I-2015J1162D01*
G01X508153D01*
G03X506847Y283284I59J-1575D01*
G02X504917Y282122I-2015J1163D01*
G01X504788D01*
G03X503467Y281334I44J-1575D01*
G02X501522Y280171I-2015J1162D01*
G01X501393D01*
G03X500087Y279384I59J-1575D01*
G02X498157Y278222I-2015J1163D01*
G01X498028D01*
G03X496707Y277434I44J-1575D01*
G02X494762Y276271I-2015J1162D01*
G01X494633D01*
G03X493327Y275484I59J-1575D01*
G02X491397Y274322I-2015J1163D01*
G01X491268D01*
G03X489947Y273534I44J-1575D01*
G02X488002Y272371I-2015J1162D01*
G01X487873D01*
G03X486567Y271584I59J-1575D01*
G02X484637Y270422I-2015J1163D01*
G01X484508D01*
G03X483224Y269692I45J-1573D01*
G01X482538Y268592D01*
G02X481796Y268180I-742J461D01*
G01X479929D01*
X478283Y269826D01*
X475395D01*
X472545Y272676D01*
X460471D01*
X459484Y271689D01*
X437712D01*
X434036Y268013D01*
X368718D01*
X367490Y266785D01*
X366577Y264669D01*
G02X365439Y263702I-1547J667D01*
G03X364976Y263352I182J-721D01*
G01X364512Y262547D01*
G02X362567Y261384I-2015J1162D01*
G01X362438D01*
G03X361132Y260597I59J-1575D01*
G02X359202Y259435I-2015J1163D01*
G01X359073D01*
G03X357752Y258647I44J-1575D01*
G02X355807Y257484I-2015J1162D01*
G01X355678D01*
G03X354372Y256697I59J-1575D01*
G02X352442Y255535I-2015J1163D01*
G01X352357D01*
G03X351006Y254770I0J-1575D01*
G01X350993Y254747D01*
G02X349235Y253597I-2015J1162D01*
G01X348978Y253340D01*
Y252009D01*
G01Y255909D02*
Y254578D01*
X349205Y254351D01*
G03X350329Y255099I-226J1559D01*
G01X350342Y255122D01*
G02X352287Y256285I2015J-1162D01*
G01X352416D01*
G03X353722Y257072I-59J1575D01*
G02X355652Y258234I2015J-1163D01*
G01X355781D01*
G03X357102Y259022I-44J1575D01*
G02X359047Y260185I2015J-1162D01*
G01X359176D01*
G03X360482Y260972I-59J1575D01*
G02X362412Y262134I2015J-1163D01*
G01X362540D01*
X362541Y262133D01*
X362554D01*
G03X363863Y262921I-57J1576D01*
G01X364327Y263726D01*
G02X365256Y264429I1294J-745D01*
G03X365889Y264966I-226J908D01*
G01X366858Y267214D01*
X368407Y268762D01*
X433725D01*
X438388Y273425D01*
X472856D01*
X475706Y270575D01*
X478594D01*
X480198Y268971D01*
X481683D01*
X481685Y268969D01*
G03X482053Y269239I-154J595D01*
G01X482584Y270091D01*
G02X484482Y271172I1967J-1248D01*
G01X484611D01*
G03X485917Y271959I-59J1575D01*
G02X487847Y273121I2015J-1163D01*
G01X487976D01*
G03X489297Y273909I-44J1575D01*
G02X491242Y275072I2015J-1162D01*
G01X491371D01*
G03X492677Y275859I-59J1575D01*
G02X494607Y277021I2015J-1163D01*
G01X494736D01*
G03X496057Y277809I-44J1575D01*
G02X498002Y278972I2015J-1162D01*
G01X498131D01*
G03X499437Y279759I-59J1575D01*
G02X501367Y280921I2015J-1163D01*
G01X501496D01*
G03X502817Y281709I-44J1575D01*
G02X504762Y282872I2015J-1162D01*
G01X504891D01*
G03X506197Y283659I-59J1575D01*
G02X508127Y284821I2015J-1163D01*
G01X508256D01*
G03X509577Y285609I-44J1575D01*
G02X511522Y286772I2015J-1162D01*
G01X511651D01*
G03X512976Y289100I-59J1575D01*
G01X512957Y289134D01*
G02Y291458I2015J1162D01*
G01X512976Y291492D01*
G03X512957Y293033I-1384J754D01*
G02Y295359I2015J1163D01*
G03X512976Y296900I-1365J787D01*
G01X512957Y296934D01*
X512932Y296976D01*
G02X512957Y299259I2040J1119D01*
G03X512976Y300800I-1365J787D01*
G01X512957Y300834D01*
X512932Y300876D01*
G02X512957Y303159I2040J1119D01*
G03X512976Y304700I-1365J787D01*
G01X512957Y304734D01*
X512932Y304776D01*
G02X514921Y308222I2040J1120D01*
G01X515016D01*
G03X516337Y309010I-44J1575D01*
G02X518267Y310172I2015J-1163D01*
G01X518352D01*
G03X519703Y310937I0J1575D01*
G01X519716Y310960D01*
G02X521646Y312122I2015J-1163D01*
G01X521802D01*
G03X523096Y312909I-71J1574D01*
G02X525041Y314072I2015J-1162D01*
G01X525170D01*
G03X526476Y314859I-59J1575D01*
G02X528406Y316021I2015J-1163D01*
G01X528535D01*
G03X529856Y316809I-44J1575D01*
G02X531801Y317972I2015J-1162D01*
G01X531930D01*
G03X533236Y318759I-59J1575D01*
G02X535166Y319921I2015J-1163D01*
G01X535295D01*
G03X536616Y320709I-44J1575D01*
G02X538561Y321872I2015J-1162D01*
G01X538702D01*
G03X539996Y322659I-71J1574D01*
G02X541926Y323821I2015J-1163D01*
G01X542055D01*
G03X543376Y324609I-44J1575D01*
G02X545340Y325772I2015J-1163D01*
G01X545450D01*
G03X546756Y326559I-59J1575D01*
G02X548686Y327721I2015J-1163D01*
G01X548815D01*
G03X550136Y328509I-44J1575D01*
G02X552081Y329672I2015J-1162D01*
G01X552210D01*
G03X553516Y330459I-59J1575D01*
G02X555446Y331621I2015J-1163D01*
G01X556274D01*
G03X557045Y332335I-743J1575D01*
G02X558373Y333450I2166J-1232D01*
G01X559458Y333530D01*
G03X560419Y334348I-547J1617D01*
G02X561791Y335521I2172J-1152D01*
G01X564189D01*
G01X345598Y261760D02*
Y260429D01*
X345826Y260201D01*
G03X346963Y260972I-228J1560D01*
G02X348893Y262134I2015J-1163D01*
G01X348978D01*
G03X350342Y264496I0J1575D01*
G02X350307Y266762I2015J1164D01*
G01X350342Y266818D01*
Y266822D01*
G03X350931Y269044I-3809J2199D01*
G03Y269051I-4399J4D01*
G01Y309613D01*
X356102Y314784D01*
X360405D01*
X364483Y318862D01*
X436200D01*
X445151Y327813D01*
X453932D01*
X458873Y332754D01*
Y335365D01*
X462422Y338914D01*
X467790D01*
X468889Y340013D01*
X469062Y340287D01*
G02X470948Y341370I1970J-1247D01*
G03X471336Y341400I66J1676D01*
G03X472398Y342159I-303J1547D01*
G02X474328Y343321I2015J-1163D01*
G01X474413D01*
G03X475764Y344086I0J1575D01*
G01X475777Y344109D01*
G02X477722Y345272I2015J-1162D01*
G01X477862D01*
G02X479807Y344109I-70J-2325D01*
G03X482537I1365J787D01*
G02X484482Y345272I2015J-1162D01*
G01X484622D01*
G02X486567Y344109I-70J-2325D01*
G03X489297I1365J787D01*
G02X491242Y345272I2015J-1162D01*
G01X491382D01*
G02X493327Y344109I-70J-2325D01*
G03X496057I1365J787D01*
G02X498002Y345272I2015J-1162D01*
G01X498142D01*
G02X500087Y344109I-70J-2325D01*
G03X502817I1365J787D01*
G02X504762Y345272I2015J-1162D01*
G01X504902D01*
G02X506847Y344109I-70J-2325D01*
G03X509577I1365J787D01*
G02X511522Y345272I2015J-1162D01*
G01X511662D01*
G02X513607Y344109I-70J-2325D01*
G03X516337I1365J787D01*
G02X520367I2015J-1162D01*
G01X520393Y344064D01*
G03X523096Y344109I1338J832D01*
G02X527126I2015J-1162D01*
G03X529856I1365J787D01*
G02X531801Y345272I2015J-1162D01*
G01X531941D01*
G02X533886Y344109I-70J-2325D01*
G03X536616I1365J787D01*
G02X538561Y345272I2015J-1162D01*
G01X538701D01*
G02X540646Y344109I-70J-2325D01*
G03X543376I1365J787D01*
G02X545321Y345272I2015J-1162D01*
G01X545461D01*
G02X547406Y344109I-70J-2325D01*
G03X550136I1365J787D01*
G02X554166I2015J-1162D01*
G03X556896I1365J787D01*
G01X557294Y344798D01*
G02X561083Y344098I1617J-1851D01*
G03X561936Y343321I1508J798D01*
G01X563603D01*
G01X563624Y339423D02*
X563622Y339421D01*
X561936D01*
G02X561083Y340198I655J1575D01*
G03X559709Y341372I-2172J-1151D01*
G01X558841D01*
G03X556896Y340209I70J-2325D01*
G02X554166I-1365J787D01*
G03X552221Y341372I-2015J-1162D01*
G01X552081D01*
G03X550136Y340209I70J-2325D01*
G02X547406I-1365J787D01*
G03X545461Y341372I-2015J-1162D01*
G01X545321D01*
G03X543376Y340209I70J-2325D01*
G02X540646I-1365J787D01*
G03X538701Y341372I-2015J-1162D01*
G01X538561D01*
G03X536616Y340209I70J-2325D01*
G02X533886I-1365J787D01*
G03X531941Y341372I-2015J-1162D01*
G01X531801D01*
G03X529856Y340209I70J-2325D01*
G02X527126I-1365J787D01*
G03X525181Y341372I-2015J-1162D01*
G01X525041D01*
G03X523096Y340209I70J-2325D01*
G02X520380Y340186I-1365J787D01*
G01X520367Y340209D01*
G03X518422Y341372I-2015J-1162D01*
G01X518282D01*
G03X516337Y340209I70J-2325D01*
G02X513607I-1365J787D01*
G03X511662Y341372I-2015J-1162D01*
G01X511522D01*
G03X509577Y340209I70J-2325D01*
G02X506847I-1365J787D01*
G03X504902Y341372I-2015J-1162D01*
G01X504762D01*
G03X502817Y340209I70J-2325D01*
G02X500087I-1365J787D01*
G03X498142Y341372I-2015J-1162D01*
G01X498002D01*
G03X496057Y340209I70J-2325D01*
G02X493327I-1365J787D01*
G03X491382Y341372I-2015J-1162D01*
G01X491242D01*
G03X489297Y340209I70J-2325D01*
G02X486567I-1365J787D01*
G03X484622Y341372I-2015J-1162D01*
G01X484482D01*
G03X482537Y340209I70J-2325D01*
G02X479807I-1365J787D01*
G03X477862Y341372I-2015J-1162D01*
G01X477722D01*
G03X475777Y340209I70J-2325D01*
G01X475764Y340186D01*
G02X474413Y339421I-1351J810D01*
G01X474328D01*
G03X472442Y338338I84J-2330D01*
G01X472189Y337938D01*
X471642Y337391D01*
X463019D01*
X460961Y335333D01*
Y330615D01*
X447613Y317267D01*
X365307D01*
X358924Y310884D01*
X355918D01*
X353214Y308180D01*
Y268953D01*
G03X353722Y266447I3994J-495D01*
G01X353741Y266413D01*
G02X353722Y264872I-1384J-754D01*
G03X353697Y262589I2015J-1164D01*
G01X353722Y262547D01*
X353741Y262513D01*
G02X352416Y260185I-1384J-753D01*
G01X352287D01*
G03X350483Y259239I69J-2325D01*
G01X350131Y259144D01*
X348978Y259809D01*
G01X564003Y342571D02*
X561793D01*
G02X560419Y343745I798J2325D01*
G03X557872Y344300I-1508J-798D01*
G01X557546Y343734D01*
G02X553516I-2015J1162D01*
G03X550786I-1365J-787D01*
G02X546756I-2015J1162D01*
G03X544026I-1365J-787D01*
G02X542081Y342571I-2015J1162D01*
G01X541941D01*
G02X539996Y343734I70J2325D01*
G03X537266I-1365J-787D01*
G02X535321Y342571I-2015J1162D01*
G01X535181D01*
G02X533236Y343734I70J2325D01*
G03X530506I-1365J-787D01*
G02X528561Y342571I-2015J1162D01*
G01X528421D01*
G02X526476Y343734I70J2325D01*
G03X523746I-1365J-787D01*
G02X519716I-2015J1162D01*
G01X519690Y343779D01*
G03X516987Y343734I-1338J-832D01*
G02X515042Y342571I-2015J1162D01*
G01X514902D01*
G02X512957Y343734I70J2325D01*
G03X510227I-1365J-787D01*
G02X508282Y342571I-2015J1162D01*
G01X508142D01*
G02X506197Y343734I70J2325D01*
G03X503467I-1365J-787D01*
G02X501522Y342571I-2015J1162D01*
G01X501382D01*
G02X499437Y343734I70J2325D01*
G03X496707I-1365J-787D01*
G02X494762Y342571I-2015J1162D01*
G01X494622D01*
G02X492677Y343734I70J2325D01*
G03X489947I-1365J-787D01*
G02X488002Y342571I-2015J1162D01*
G01X487862D01*
G02X485917Y343734I70J2325D01*
G03X483187I-1365J-787D01*
G02X481242Y342571I-2015J1162D01*
G01X481102D01*
G02X479157Y343734I70J2325D01*
G03X476441Y343757I-1365J-787D01*
G01X476428Y343734D01*
G02X474483Y342571I-2015J1162D01*
G01X474354D01*
G03X473048Y341784I59J-1575D01*
G02X471393Y340648I-2012J1158D01*
G02X470974Y340620I-369J2370D01*
G03X469703Y339889I60J-1574D01*
G01X469414Y339432D01*
X468147Y338165D01*
X462733D01*
X459622Y335054D01*
Y331541D01*
X455145Y327064D01*
X445462D01*
X436511Y318113D01*
X364794D01*
X360716Y314035D01*
X356413D01*
X351680Y309302D01*
Y269057D01*
G02X350993Y266447I-5148J-40D01*
G03Y264873I1364J-787D01*
G02X349048Y261384I-2014J-1164D01*
G01X348919D01*
G03X347613Y260597I59J-1575D01*
G02X345854Y259447I-2015J1162D01*
G01X345598Y259191D01*
Y257860D01*
G01X563624Y338671D02*
X561793D01*
G02X560419Y339845I798J2325D01*
G03X559566Y340622I-1508J-798D01*
G01X558867D01*
G03X557546Y339834I44J-1575D01*
G02X555601Y338671I-2015J1162D01*
G01X555461D01*
G02X553516Y339834I70J2325D01*
G03X550786I-1365J-787D01*
G02X548841Y338671I-2015J1162D01*
G01X548701D01*
G02X546756Y339834I70J2325D01*
G03X544026I-1365J-787D01*
G02X542081Y338671I-2015J1162D01*
G01X541941D01*
G02X539996Y339834I70J2325D01*
G03X537266I-1365J-787D01*
G02X535321Y338671I-2015J1162D01*
G01X535181D01*
G02X533236Y339834I70J2325D01*
G03X530506I-1365J-787D01*
G02X528561Y338671I-2015J1162D01*
G01X528421D01*
G02X526476Y339834I70J2325D01*
G03X523746I-1365J-787D01*
G02X521801Y338671I-2015J1162D01*
G01X521661D01*
G02X519716Y339834I70J2325D01*
G01X519703Y339857D01*
G03X516987Y339834I-1351J-810D01*
G02X515042Y338671I-2015J1162D01*
G01X514902D01*
G02X512957Y339834I70J2325D01*
G03X510227I-1365J-787D01*
G02X508282Y338671I-2015J1162D01*
G01X508142D01*
G02X506197Y339834I70J2325D01*
G03X503467I-1365J-787D01*
G02X501522Y338671I-2015J1162D01*
G01X501382D01*
G02X499437Y339834I70J2325D01*
G03X496707I-1365J-787D01*
G02X494762Y338671I-2015J1162D01*
G01X494622D01*
G02X492677Y339834I70J2325D01*
G03X489947I-1365J-787D01*
G02X488002Y338671I-2015J1162D01*
G01X487862D01*
G02X485917Y339834I70J2325D01*
G03X483187I-1365J-787D01*
G02X481242Y338671I-2015J1162D01*
G01X481102D01*
G02X479157Y339834I70J2325D01*
G03X476441Y339857I-1365J-787D01*
G01X476428Y339834D01*
G02X474483Y338671I-2015J1162D01*
G01X474354D01*
G03X473083Y337940I60J-1574D01*
G01X472794Y337483D01*
X471953Y336642D01*
X468048D01*
X447924Y316518D01*
X365618D01*
X359235Y310135D01*
X356413D01*
X353963Y307685D01*
Y268904D01*
G03X354371Y266821I3245J-446D01*
G01X354374Y266817D01*
X354375D01*
X354397Y266780D01*
G02X354372Y264497I-2040J-1119D01*
G03X354353Y262956I1365J-787D01*
G01X354372Y262922D01*
X354397Y262880D01*
G02X352442Y259435I-2040J-1120D01*
G01X352357D01*
G03X351121Y258835I1J-1575D01*
G01X351204Y258525D01*
X352357Y257860D01*
G01X496500Y234900D02*
X496915Y235315D01*
X498884D01*
X499802Y234397D01*
G01X503815Y235315D02*
X505985D01*
G01X510716Y235316D02*
X510941D01*
G01X498072Y214247D02*
X497649Y213824D01*
G03X497214Y212581I1073J-1073D01*
G02X496822Y210917I-2522J-284D01*
G01X496708Y210741D01*
Y208892D01*
X498600Y207000D01*
Y206000D01*
X498800Y205800D01*
G01X1203172Y213108D02*
Y213195D01*
X1203372Y213395D01*
Y215273D01*
X1203054Y215591D01*
Y216547D01*
X1203372Y216865D01*
Y218491D01*
X1203124Y218934D01*
G03X1201803Y219722I-1365J-787D01*
G01X1201674D01*
G02X1199719Y223167I85J2325D01*
G01X1199744Y223209D01*
X1199763Y223243D01*
G03X1198438Y225571I-1384J753D01*
G01X1198309D01*
G02X1196364Y226734I70J2325D01*
G03X1195043Y227522I-1365J-787D01*
G01X1194914D01*
G02X1192984Y228684I85J2325D01*
G03X1192241Y229344I-1365J-788D01*
G03X1191619Y227896I-311J-724D01*
G01X1207129Y216837D02*
Y216924D01*
X1206929Y217124D01*
Y218544D01*
X1207154Y218934D01*
G03X1205209Y222421I-2015J1162D01*
G01X1205095D01*
G02X1203774Y224784I44J1575D01*
G03X1201829Y228272I-2015J1163D01*
G01X1201700D01*
G02X1200394Y229059I59J1575D01*
G03X1198430Y230222I-2015J-1163D01*
G01X1198335D01*
G02X1197142Y230822I45J1575D01*
G01X1197225Y231132D01*
X1198379Y231797D01*
G01X494692Y212296D02*
X495846Y212962D01*
X496178Y212872D01*
X496477Y212355D01*
G02X496192Y211325I-1785J-60D01*
G01X495958Y210963D01*
Y208581D01*
X497850Y206689D01*
Y206000D01*
X497650Y205800D01*
G01X1204322Y213108D02*
Y213195D01*
X1204122Y213395D01*
Y218687D01*
X1203774Y219309D01*
G03X1201829Y220472I-2015J-1162D01*
G01X1201700D01*
G02X1200375Y222800I59J1575D01*
G01X1200394Y222834D01*
X1200419Y222876D01*
G03X1198464Y226321I-2040J1120D01*
G01X1198335D01*
G02X1197014Y227109I44J1575D01*
G03X1195069Y228272I-2015J-1162D01*
G01X1194940D01*
G02X1193634Y229059I59J1575D01*
G01X1193373Y229511D01*
G03X1191619Y231797I-9559J-5518D01*
G01X1205979Y216837D02*
Y216924D01*
X1206179Y217124D01*
Y218747D01*
X1206504Y219309D01*
G03X1205183Y221671I-1365J787D01*
G01X1205069D01*
G02X1203124Y225159I70J2325D01*
G03X1201803Y227522I-1365J788D01*
G01X1201674D01*
G02X1199744Y228684I85J2325D01*
G03X1198438Y229471I-1365J-788D01*
G01X1198328D01*
G02X1196505Y230417I50J2326D01*
G01X1196153Y230512D01*
X1194999Y229847D01*
G01X1174719D02*
G03X1173814Y230222I-905J-905D01*
G01X1171269D01*
G03X1169324Y229060I70J-2326D01*
G01X1169311Y229037D01*
G02X1167960Y228272I-1351J810D01*
G01X1167890D01*
G03X1165945Y224784I70J-2325D01*
G02X1165964Y223243I-1365J-787D01*
G01X1165945Y223209D01*
X1165920Y223167D01*
G03X1165945Y220884I2040J-1119D01*
G02X1165964Y219343I-1365J-787D01*
G01X1165945Y219309D01*
X1165920Y219267D01*
G03X1165945Y216984I2040J-1119D01*
G02X1165964Y215443I-1365J-787D01*
G01X1165945Y215409D01*
X1165920Y215367D01*
G03X1165945Y213084I2040J-1119D01*
G02X1164651Y210722I-1365J-788D01*
G01X1164510D01*
G03X1162540Y209517I69J-2325D01*
G03X1162565Y207234I2040J-1119D01*
G01X1162791Y206843D01*
Y204974D01*
X1162591Y204687D01*
G01X527823Y194117D02*
X527543D01*
X526440Y195220D01*
Y195736D01*
X525965Y196211D01*
X525449D01*
X525025Y196635D01*
Y197151D01*
X524551Y197625D01*
X524035D01*
X523537Y198123D01*
Y200300D01*
X523937Y200700D01*
Y201300D01*
X523537Y201700D01*
Y202617D01*
G02X523545Y202714I1574J-81D01*
G02X523746Y203334I1567J-165D01*
G03Y205660I-2015J1163D01*
G02Y207234I1365J787D01*
G03X523771Y209517I-2015J1164D01*
G01X523746Y209559D01*
G02Y211134I1364J788D01*
G02X524883Y211905I1364J-788D01*
G01X525111Y211677D01*
Y210346D01*
G01X1167960Y225947D02*
X1168377Y225529D01*
G02X1169011Y224000I-1529J-1530D01*
G03X1169289Y222894I2327J-3D01*
G01X1169324Y222834D01*
G02Y221260I-1364J-787D01*
G03X1169289Y218994I2015J-1164D01*
G01X1169324Y218934D01*
G02Y217360I-1364J-787D01*
G03X1169289Y215094I2015J-1164D01*
G01X1169324Y215034D01*
G03X1171269Y213871I2015J1162D01*
G01X1171398D01*
G02X1172704Y213084I-59J-1575D01*
G02X1172723Y211543I-1365J-787D01*
G01X1172704Y211509D01*
G02X1171410Y210722I-1365J787D01*
G01X1171269D01*
G03X1169324Y209559I70J-2325D01*
G02X1168008Y208772I-1364J787D01*
G01X1167975Y208771D01*
X1167873D01*
G03X1165624Y206436I87J-2335D01*
G01Y204402D01*
X1165424Y204202D01*
Y204115D01*
G01X520907Y202056D02*
Y202143D01*
X520679Y202371D01*
Y202880D01*
X521079Y203280D01*
Y203780D01*
X520679Y204180D01*
Y204680D01*
X521079Y205080D01*
Y205580D01*
X520679Y205980D01*
Y206480D01*
G03X520367Y207610I-2327J-34D01*
G02Y209184I1364J787D01*
G01X520392Y209226D01*
G03X520367Y211509I-2040J1119D01*
G02X520268Y212877I1364J786D01*
G01X520578Y212961D01*
X521000Y212718D01*
X521731Y212296D01*
G01X1174719Y222047D02*
X1174926Y222240D01*
G03X1173851Y223392I-537J576D01*
G01X1173647Y223202D01*
G03X1173354Y221259I1072J-1155D01*
G02X1173379Y218976I-2015J-1164D01*
G01X1173354Y218934D01*
X1173335Y218900D01*
G03X1174660Y216572I1384J-753D01*
G01X1174789D01*
G02X1176734Y213084I-70J-2325D01*
G03X1176715Y211543I1365J-787D01*
G01X1176734Y211509D01*
G02X1174789Y208021I-2015J-1163D01*
G01X1174648D01*
G03X1173354Y207234I71J-1574D01*
G02X1171424Y206072I-2015J1163D01*
G01X1171291D01*
G03X1169975Y205285I48J-1574D01*
G01Y203751D01*
X1170175Y203551D01*
Y203464D01*
G01X516301Y200882D02*
Y200969D01*
X516501Y201169D01*
Y201896D01*
X515893Y204830D01*
Y205745D01*
G02X515954Y206707I7795J-11D01*
G02X516146Y207277I1512J-192D01*
G01X516337Y207609D01*
X516338Y207610D01*
G03X516436Y208978I-1366J785D01*
G01X516438D01*
X516126Y209062D01*
X514972Y208397D01*
G01X1174719Y233746D02*
X1175141Y233325D01*
G02X1175772Y231800I-1525J-1524D01*
G03X1176084Y230634I2327J-2D01*
G01X1176103Y230600D01*
G02X1176084Y229059I-1384J-754D01*
G03X1176059Y226776I2015J-1164D01*
G01X1176084Y226734D01*
X1176103Y226700D01*
G02X1176084Y225159I-1384J-754D01*
G03X1176059Y222876I2015J-1164D01*
G01X1176084Y222834D01*
X1176103Y222800D01*
G02X1176084Y221259I-1384J-754D01*
G03X1178029Y217771I2015J-1163D01*
G01X1178158D01*
G02X1179483Y215443I-59J-1575D01*
G01X1179464Y215409D01*
X1179439Y215367D01*
G03X1181428Y211921I2040J-1120D01*
G01X1181523D01*
G02X1181550Y208772I-43J-1575D01*
G01X1181394D01*
G03X1179464Y207610I85J-2325D01*
G02X1178143Y206822I-1365J787D01*
G01X1178048D01*
G03X1176084Y205659I51J-2326D01*
G02X1174788Y204872I-1365J788D01*
G01X1174646D01*
G03X1172724Y204040I92J-2848D01*
G01X1172349Y203664D01*
Y201513D01*
X1172149Y201313D01*
Y201226D01*
G01X514046Y203996D02*
Y204083D01*
X513917Y204212D01*
Y206487D01*
G03X513607Y207609I-2325J-39D01*
G01Y207610D01*
G02Y209184I1365J787D01*
G01X513632Y209226D01*
G03X513607Y211509I-2040J1119D01*
G01X513588Y211543D01*
G02X513607Y213084I1383J754D01*
G02X514744Y213855I1364J-788D01*
G01X514875Y213874D01*
G02X515435Y212758I95J-651D01*
G01X514972Y212296D01*
G01X1181479Y229847D02*
X1181906Y230274D01*
G03X1181332Y231418I-477J477D01*
G01X1181251Y231406D01*
G03X1180327Y230922I228J-1559D01*
G03X1180114Y229059I1152J-1075D01*
G02X1180139Y226776I-2015J-1164D01*
G01X1180114Y226734D01*
X1180095Y226700D01*
G03X1180114Y225159I1384J-754D01*
G02X1180139Y222876I-2015J-1164D01*
G01X1180114Y222834D01*
X1180095Y222800D01*
G03X1181420Y220472I1384J-753D01*
G01X1181549D01*
G02X1183494Y219309I-70J-2325D01*
G03X1184815Y218521I1365J787D01*
G01X1184944D01*
G02X1186899Y215076I-85J-2325D01*
G01X1186874Y215034D01*
X1186855Y215000D01*
G03X1186874Y213459I1384J-754D01*
G02Y211133I-2015J-1163D01*
G03Y209559I1365J-787D01*
G01X1186899Y209517D01*
G02X1184910Y206071I-2040J-1120D01*
G01X1184800D01*
G03X1183494Y205284I59J-1575D01*
G02X1181564Y204122I-2015J1163D01*
G01X1181435D01*
G03X1180114Y203334I44J-1575D01*
G02X1178169Y202171I-2015J1162D01*
G01X1178040D01*
G03X1176734Y201384I59J-1575D01*
G01Y200084D01*
X1176934Y199884D01*
Y199797D01*
G01X509002Y205003D02*
X509179Y205180D01*
Y210820D01*
X509580Y211513D01*
X509596Y211543D01*
G03X509577Y213084I-1384J754D01*
G02X509266Y214303I2015J1163D01*
G03X508673Y215736I-2026J1D01*
G01X508212Y216196D01*
G01X1184859Y227896D02*
X1183705Y227231D01*
X1183611Y226880D01*
G02X1183494Y224784I-2132J-932D01*
G03X1184815Y222421I1365J-788D01*
G01X1184944D01*
G02X1186874Y221259I-85J-2325D01*
G03X1188180Y220472I1365J788D01*
G01X1188309D01*
G02X1190254Y216984I-70J-2325D01*
G03X1190235Y215443I1365J-787D01*
G01X1190254Y215409D01*
X1190279Y215367D01*
G02X1190254Y213084I-2040J-1119D01*
G03X1190235Y211543I1365J-787D01*
G01X1190254Y211509D01*
G02X1190279Y209226I-2015J-1164D01*
G01X1190254Y209184D01*
G03Y207610I1365J-787D01*
G02Y205284I-2015J-1163D01*
G01X1190015Y204869D01*
G02X1188239Y204072I-1775J1579D01*
G03X1186853Y203290I1J-1621D01*
G01X1186670Y202988D01*
X1185719Y202183D01*
X1182422Y200231D01*
X1180794Y198604D01*
Y197053D01*
X1180994Y196766D01*
G01X505677Y205358D02*
X505886Y205567D01*
Y209913D01*
X505529Y210270D01*
Y211037D01*
X505886Y211394D01*
Y212301D01*
G02X506197Y213459I2326J-4D01*
G03X506216Y215000I-1365J787D01*
G01X506197Y215034D01*
X506172Y215076D01*
G02X506197Y217359I2040J1119D01*
G03X504876Y219722I-1365J788D01*
G01X504747D01*
G02X502958Y220667I84J2325D01*
G03X502088Y220733I-463J-341D01*
G01X501452Y220096D01*
G01X1184859Y231797D02*
X1185320Y231335D01*
G02X1185913Y229905I-1430J-1431D01*
G03X1186224Y228684I2326J-58D01*
G02X1186243Y227143I-1365J-787D01*
G01X1186224Y227109D01*
X1186199Y227067D01*
G03X1188154Y223622I2040J-1120D01*
G01X1188283D01*
G02X1189604Y222834I-44J-1575D01*
G03X1191549Y221671I2015J1162D01*
G01X1191678D01*
G02X1193003Y219343I-59J-1575D01*
G01X1192984Y219309D01*
X1192959Y219267D01*
G03X1194914Y215822I2040J-1120D01*
G01X1195043D01*
G02X1195058Y212672I-44J-1575D01*
G01X1194948D01*
G03X1192959Y209226I51J-2326D01*
G01X1193359Y208534D01*
Y206503D01*
X1191672Y202687D01*
X1183689Y193337D01*
Y192208D01*
X1183489Y192008D01*
Y191921D01*
G01X503962Y205301D02*
Y205488D01*
X503778Y205672D01*
Y206330D01*
X504078Y206630D01*
Y207150D01*
X503778Y207450D01*
Y207950D01*
X504078Y208250D01*
Y208870D01*
X503778Y209170D01*
Y212299D01*
G03X503467Y213459I-2326J-2D01*
G02X503559Y215176I1365J788D01*
G02X504604Y215806I1273J-929D01*
G02X504878Y215822I229J-1565D01*
G01X505063Y215558D01*
X504832Y214247D01*
G01X1191619Y235696D02*
X1191261Y235338D01*
G03X1190566Y233703I1679J-1679D01*
G02X1190279Y232626I-2326J43D01*
G01X1190254Y232584D01*
G03Y231010I1365J-787D01*
G02Y228684I-2015J-1163D01*
G03X1191575Y226321I1365J-788D01*
G01X1191704D01*
G02X1193634Y225159I-85J-2325D01*
G03X1194940Y224372I1365J788D01*
G01X1195069D01*
G02X1197014Y220884I-70J-2325D01*
G03X1198335Y218521I1365J-788D01*
G01X1198451D01*
G02X1200394Y217359I-72J-2325D01*
G01X1200860Y216550D01*
Y211976D01*
X1196205Y202418D01*
X1194630Y199800D01*
X1193167Y197369D01*
X1193236Y197094D01*
X1193191Y197020D01*
G01X500246Y205672D02*
X500406Y205832D01*
Y209808D01*
X499587Y210895D01*
G02X499353Y213313I1865J1401D01*
G01X499437Y213459D01*
G03X499456Y215000I-1365J787D01*
G01X499437Y215034D01*
X499412Y215076D01*
G02X499125Y216200I2039J1119D01*
G03X498493Y217726I-2158J0D01*
G01X498072Y218147D01*
G01X1154440Y237647D02*
X1155605Y234983D01*
G03X1155805Y234533I2214J715D01*
G02X1154511Y232172I-1365J-787D01*
G01X1154355D01*
G03X1152425Y228684I85J-2325D01*
G02X1152444Y227143I-1365J-787D01*
G01X1152425Y227109D01*
X1152400Y227067D01*
G03X1152425Y224784I2040J-1119D01*
G02X1151104Y222421I-1365J-788D01*
G01X1150975D01*
G03X1149045Y221259I85J-2325D01*
G02X1147739Y220472I-1365J788D01*
G01X1147610D01*
G03X1147595Y215822I69J-2325D01*
G01X1147724D01*
G02X1149061Y215005I-44J-1575D01*
G02X1149045Y213460I-1381J-758D01*
G01Y213459D01*
X1148568Y212633D01*
X1147046Y212157D01*
X1145484Y210919D01*
Y208056D01*
X1145284Y207856D01*
Y207769D01*
G01X545100Y200700D02*
X544815D01*
X543319Y202196D01*
Y202747D01*
X542753Y203314D01*
X542201D01*
X541636Y203879D01*
Y205898D01*
X540646Y207610D01*
G03X538718Y208771I-2014J-1163D01*
G01X538631D01*
X538630Y208772D01*
X538560D01*
G02X537266Y211133I71J1574D01*
G03Y213459I-2015J1163D01*
G02X537247Y215000I1365J787D01*
G01X537266Y215034D01*
X537291Y215076D01*
G03X537266Y217359I-2040J1119D01*
G02X537167Y218728I1366J787D01*
G01X537477Y218812D01*
X538631Y218147D01*
G01X1161200Y233746D02*
X1161800Y234400D01*
X1161700Y235000D01*
X1161600Y235300D01*
X1160972Y235305D01*
G03X1160561Y235186I229J-1559D01*
G03X1159835Y234534I638J-1441D01*
G03Y232959I1365J-787D01*
G01X1159860Y232917D01*
G02X1157871Y229471I-2040J-1120D01*
G01X1157761D01*
G03X1156436Y227143I59J-1575D01*
G01X1156455Y227109D01*
X1156480Y227067D01*
G02X1156455Y224784I-2040J-1119D01*
G03X1156436Y223243I1365J-787D01*
G01X1156455Y223209D01*
X1156480Y223167D01*
G02X1154525Y219722I-2040J-1120D01*
G01X1154396D01*
G03X1153075Y217359I44J-1575D01*
G02X1153100Y215076I-2015J-1164D01*
G01X1153075Y215034D01*
X1153056Y215000D01*
G03X1153075Y213459I1384J-754D01*
G01X1153427Y212848D01*
Y211197D01*
X1152425Y210195D01*
Y208752D01*
X1152625Y208465D01*
G01X541116Y192984D02*
X540950Y193292D01*
X540933Y193301D01*
X539929Y193810D01*
X536122Y201582D01*
X536335Y203194D01*
X536620Y203666D01*
G03X536758Y205039I-1369J831D01*
G01X536616Y205284D01*
G03X535310Y206071I-1365J-788D01*
G01X535200D01*
G02X533841Y210247I51J2326D01*
G01X535251Y212296D01*
G01X1157820Y227896D02*
X1158281Y227436D01*
G02X1158874Y226003I-1433J-1432D01*
G03X1159185Y224784I2326J-56D01*
G02X1159204Y223243I-1365J-787D01*
G01X1159185Y223209D01*
X1159160Y223167D01*
G03X1159185Y220884I2040J-1119D01*
G02X1157864Y218521I-1365J-788D01*
G01X1157735D01*
G03X1155780Y215076I85J-2325D01*
G01X1155805Y215034D01*
X1155824Y215000D01*
G02X1155641Y213226I-1384J-754D01*
G01X1155085Y212670D01*
Y209658D01*
X1154885Y209458D01*
Y209371D01*
G01X534388Y200588D02*
X534200Y200776D01*
Y203165D01*
X533886Y203709D01*
G03X531941Y204872I-2015J-1162D01*
G01X531812D01*
G02X530487Y207200I59J1575D01*
G01X530506Y207234D01*
G03X530531Y209517I-2015J1164D01*
G01X530506Y209559D01*
G02X530296Y210385I1364J786D01*
G02X530407Y210927I1574J-40D01*
G01X530717Y211011D01*
X531871Y210346D01*
G01X1161200Y229847D02*
X1162354Y230512D01*
X1162664Y230428D01*
G02X1162565Y229059I-1465J-582D01*
G03X1162540Y226776I2015J-1164D01*
G01X1162565Y226734D01*
X1162584Y226700D01*
G02X1162565Y225159I-1384J-754D01*
G03X1162540Y222876I2015J-1164D01*
G01X1162565Y222834D01*
X1162584Y222800D01*
G02X1162565Y221259I-1384J-754D01*
G03X1162540Y218976I2015J-1164D01*
G01X1162565Y218934D01*
X1162584Y218900D01*
G02X1162565Y217359I-1384J-754D01*
G03X1162540Y215076I2015J-1164D01*
G01X1162565Y215034D01*
X1162584Y215000D01*
G02X1161259Y212672I-1384J-753D01*
G01X1161149D01*
G03X1159185Y211509I51J-2326D01*
G01X1158450Y210236D01*
Y206515D01*
X1158279Y206344D01*
Y206300D01*
G01X533377Y192124D02*
X533345Y192156D01*
X533083D01*
X532248Y192991D01*
Y193385D01*
X531547Y194086D01*
X531153D01*
X530658Y194581D01*
Y195039D01*
X530021Y195676D01*
X529563D01*
X529068Y196171D01*
Y196721D01*
X528523Y197266D01*
X527973D01*
X527435Y197804D01*
Y200033D01*
X527798Y200396D01*
Y201095D01*
X527435Y201458D01*
Y202642D01*
G03X527126Y203709I-2324J-95D01*
G01X527107Y203743D01*
G02X527126Y205284I1384J754D01*
G03Y207610I-2015J1163D01*
G02Y209184I1365J787D01*
G01X527151Y209226D01*
G03X527126Y211509I-2040J1119D01*
G01X527107Y211543D01*
G02X528432Y213871I1384J753D01*
G01X528561D01*
G03X530506Y215034I-70J2325D01*
G02X531827Y215822I1365J-787D01*
G01X532464D01*
G02X533000Y215600I0J-758D01*
G01X533248Y215352D01*
G02X532791Y214248I-458J-457D01*
G01X531871Y214247D01*
G01X1171339Y227896D02*
X1172413D01*
G03Y229471I0J787D01*
G01X1171339D01*
G03X1169988Y228706I0J-1575D01*
G01X1169975Y228683D01*
G02X1168058Y227522I-2015J1164D01*
G01X1167916D01*
G03X1166595Y225159I44J-1575D01*
G02X1166620Y222876I-2015J-1164D01*
G01X1166595Y222834D01*
X1166576Y222800D01*
G03X1166595Y221259I1384J-754D01*
G02X1166620Y218976I-2015J-1164D01*
G01X1166595Y218934D01*
X1166576Y218900D01*
G03X1166595Y217359I1384J-754D01*
G02X1166620Y215076I-2015J-1164D01*
G01X1166595Y215034D01*
X1166576Y215000D01*
G03X1166595Y213459I1384J-754D01*
G02X1164665Y209971I-2015J-1163D01*
G01X1164509D01*
G03X1163199Y209155I71J-1574D01*
G03X1163215Y207610I1381J-758D01*
G01X1163541Y207046D01*
Y205023D01*
X1163741Y204736D01*
G01X527010Y193303D02*
Y193586D01*
X527011Y193587D01*
X522787Y197812D01*
Y202650D01*
G02X522798Y202793I2324J-107D01*
G02X523096Y203710I2313J-245D01*
G03Y205284I-1365J787D01*
G02Y207610I2015J1163D01*
G03Y209184I-1365J787D01*
G01X523071Y209226D01*
G02X523096Y211509I2040J1119D01*
G01X523359Y211964D01*
G02X525111Y214247I9553J-5517D01*
G01X1171339Y223996D02*
X1170186Y224661D01*
X1169876Y224577D01*
G03X1169765Y223998I1464J-581D01*
G03X1169975Y223209I1575J-3D01*
G01X1170010Y223149D01*
G02X1169975Y220883I-2050J-1102D01*
G03Y219309I1364J-787D01*
G01X1170010Y219249D01*
G02X1169975Y216983I-2050J-1102D01*
G03Y215409I1364J-787D01*
G01X1169988Y215386D01*
G03X1171339Y214621I1351J810D01*
G01X1171424D01*
G02X1173354Y213459I-85J-2325D01*
G02Y211133I-2015J-1163D01*
G02X1171424Y209971I-2015J1163D01*
G01X1171291D01*
G03X1169975Y209184I48J-1574D01*
G02X1168030Y208021I-2015J1162D01*
G01X1167889D01*
G03X1166374Y206436I71J-1585D01*
G01Y204402D01*
X1166574Y204202D01*
Y204115D01*
G01X519757Y201956D02*
X519929Y202128D01*
Y206244D01*
X519926Y206469D01*
G03X519716Y207234I-1574J-21D01*
G02X519691Y209517I2015J1164D01*
G01X519716Y209559D01*
G03Y211133I-1364J787D01*
G01X519691Y211175D01*
G02X519599Y213230I2039J1121D01*
G01X519505Y213582D01*
X518352Y214247D01*
G01Y210345D02*
X517930Y209925D01*
G03X517299Y208400I1525J-1524D01*
G02X516987Y207234I-2327J-2D01*
G01X516796Y206902D01*
G03X516699Y206613I671J-386D01*
G03X516643Y205744I6988J-887D01*
G01Y204907D01*
X517251Y201973D01*
Y201169D01*
X517451Y200969D01*
Y200882D01*
G01X1169025Y203464D02*
Y203551D01*
X1169225Y203751D01*
Y205466D01*
G02X1171269Y206823I2115J-968D01*
G01X1171410D01*
G03X1172704Y207610I-71J1574D01*
G02X1174634Y208772I2015J-1163D01*
G01X1174790D01*
G03X1176084Y211133I-71J1574D01*
G02Y213459I2015J1163D01*
G03X1174763Y215822I-1365J788D01*
G01X1174634D01*
G02X1172679Y219267I85J2325D01*
G01X1172704Y219309D01*
X1172723Y219343D01*
G03X1172704Y220884I-1384J754D01*
G02X1173137Y223752I2015J1163D01*
G02Y223754I1670J1D01*
G01Y223753D01*
X1173670Y224247D01*
G03X1174719Y225947I-2541J2742D01*
G01X1178099Y231797D02*
X1176945Y232462D01*
X1176635Y232378D01*
G03X1176524Y231799I1465J-581D01*
G03X1176734Y231010I1576J-3D01*
G02Y228684I-2015J-1163D01*
G03X1176715Y227143I1365J-787D01*
G01X1176734Y227109D01*
X1176759Y227067D01*
G02X1176734Y224784I-2040J-1119D01*
G03X1176715Y223243I1365J-787D01*
G01X1176734Y223209D01*
X1176759Y223167D01*
G02X1176734Y220884I-2040J-1119D01*
G03X1178055Y218521I1365J-788D01*
G01X1178184D01*
G02X1180139Y215076I-85J-2325D01*
G01X1180114Y215034D01*
X1180095Y215000D01*
G03X1181420Y212672I1384J-753D01*
G01X1181530D01*
G02X1181549Y208021I-52J-2326D01*
G01X1181408D01*
G03X1180114Y207234I71J-1574D01*
G02X1178150Y206071I-2015J1163D01*
G01X1178040D01*
G03X1176734Y205284I59J-1575D01*
G02X1174804Y204122I-2015J1163D01*
G01X1174660D01*
G03X1173255Y203509I79J-2098D01*
G01X1173099Y203353D01*
Y201513D01*
X1173299Y201313D01*
Y201226D01*
G01X512896Y203996D02*
X513167Y204267D01*
Y206480D01*
G03X512957Y207234I-1575J-32D01*
G02X512932Y209517I2015J1164D01*
G01X512957Y209559D01*
G03Y211133I-1365J787D01*
G02Y213459I2015J1163D01*
G01X513215Y213906D01*
G02X514972Y216196I9573J-5526D01*
G01X1181479Y233746D02*
G02X1181148Y232905I-1233J0D01*
G01X1179777Y231435D01*
G03X1179464Y228684I1702J-1587D01*
G02X1179483Y227143I-1365J-787D01*
G01X1179464Y227109D01*
X1179439Y227067D01*
G03X1179464Y224784I2040J-1119D01*
G02X1179483Y223243I-1365J-787D01*
G01X1179464Y223209D01*
X1179439Y223167D01*
G03X1181394Y219722I2040J-1120D01*
G01X1181523D01*
G02X1182844Y218934I-44J-1575D01*
G03X1184789Y217771I2015J1162D01*
G01X1184918D01*
G02X1186243Y215443I-59J-1575D01*
G01X1186224Y215409D01*
X1186199Y215367D01*
G03X1186224Y213084I2040J-1119D01*
G02X1186243Y211543I-1365J-787D01*
G01X1186224Y211509D01*
G03X1186199Y209226I2015J-1164D01*
G01X1186224Y209184D01*
G02X1184903Y206822I-1365J-787D01*
G01X1184808D01*
G03X1182844Y205659I51J-2326D01*
G02X1181538Y204872I-1365J788D01*
G01X1181409D01*
G03X1179464Y203709I70J-2325D01*
G02X1178143Y202921I-1365J787D01*
G01X1178014D01*
G03X1175984Y201565I85J-2325D01*
G01Y200084D01*
X1175784Y199884D01*
Y199797D01*
G01X510152Y205003D02*
Y205190D01*
X509929Y205413D01*
Y210618D01*
X510251Y211175D01*
G03X510227Y213459I-2039J1121D01*
G02X510017Y214285I1365J787D01*
G02X510128Y214828I1575J-39D01*
G01X510438Y214912D01*
X511592Y214247D01*
G01X1181479Y225947D02*
X1182633Y226612D01*
X1182943Y226528D01*
G02X1182844Y225159I-1465J-582D01*
G03X1184789Y221671I2015J-1163D01*
G01X1184918D01*
G02X1186224Y220884I-59J-1575D01*
G03X1188154Y219722I2015J1163D01*
G01X1188283D01*
G02X1189604Y217359I-44J-1575D01*
G03X1189579Y215076I2015J-1164D01*
G01X1189604Y215034D01*
X1189623Y215000D01*
G02X1189604Y213459I-1384J-754D01*
G03Y211133I2015J-1163D01*
G02Y209559I-1365J-787D01*
G01X1189579Y209517D01*
G03X1189604Y207234I2040J-1119D01*
G01X1189623Y207200D01*
G02X1189604Y205659I-1384J-754D01*
G01X1189407Y205317D01*
G02X1188239Y204822I-1168J1131D01*
G03X1186211Y203680I0J-2372D01*
G01X1186091Y203482D01*
X1185282Y202796D01*
X1181958Y200829D01*
X1180044Y198915D01*
Y196990D01*
X1179844Y196702D01*
G01X506827Y205358D02*
X506636Y205549D01*
Y212300D01*
G02X506847Y213084I1576J-4D01*
G03X506872Y215367I-2015J1164D01*
G01X506847Y215409D01*
X506828Y215443D01*
G02X506847Y216984I1384J754D01*
G03X504902Y220472I-2015J1163D01*
G01X504773D01*
G02X503595Y221071I60J1575D01*
G01X503678Y221381D01*
X504832Y222047D01*
G01X1188239Y229847D02*
X1187085Y230512D01*
X1186775Y230428D01*
G03X1186664Y229886I1464J-582D01*
G03X1186874Y229059I1575J-40D01*
G02X1186899Y226776I-2015J-1164D01*
G01X1186874Y226734D01*
X1186855Y226700D01*
G03X1188180Y224372I1384J-753D01*
G01X1188309D01*
G02X1190254Y223209I-70J-2325D01*
G03X1191575Y222421I1365J787D01*
G01X1191704D01*
G02X1193659Y218976I-85J-2325D01*
G01X1193634Y218934D01*
X1193615Y218900D01*
G03X1194940Y216572I1384J-753D01*
G01X1195069D01*
G02X1195050Y211921I-71J-2325D01*
G01X1194955D01*
G03X1193624Y209578I44J-1575D01*
G01X1194109Y208736D01*
Y206344D01*
X1192314Y202283D01*
X1184439Y193060D01*
Y192208D01*
X1184639Y192008D01*
Y191921D01*
G01X502812Y205301D02*
X503028Y205517D01*
Y212298D01*
G03X502817Y213084I-1576J-2D01*
G02X502953Y215619I2015J1163D01*
G01X504832Y218147D01*
G01X1188239Y233746D02*
X1189393Y234411D01*
X1189703Y234327D01*
G02X1189814Y233717I-1464J-582D01*
G02X1189604Y232959I-1575J28D01*
G01X1189579Y232917D01*
G03X1189604Y230634I2040J-1119D01*
G01X1189623Y230600D01*
G02X1189604Y229059I-1384J-754D01*
G03X1191549Y225571I2015J-1163D01*
G01X1191678D01*
G02X1192984Y224784I-59J-1575D01*
G03X1194914Y223622I2015J1163D01*
G01X1195043D01*
G02X1196364Y221259I-44J-1575D01*
G03X1198309Y217771I2015J-1163D01*
G01X1198438D01*
G02X1199744Y216984I-59J-1575D01*
G01X1200110Y216349D01*
Y212149D01*
X1195547Y202780D01*
X1192523Y197755D01*
X1192250Y197688D01*
X1192206Y197614D01*
G01X501396Y205672D02*
Y205859D01*
X501156Y206099D01*
Y210059D01*
X500187Y211346D01*
G02X500018Y212964I1265J950D01*
G01X500087Y213084D01*
G03X500112Y215367I-2015J1164D01*
G01X500087Y215409D01*
X500068Y215443D01*
G02X499877Y216199I1385J752D01*
G02X499988Y216778I1576J-2D01*
G01X500298Y216862D01*
X501452Y216196D01*
G01X1151060Y227896D02*
X1150649Y228307D01*
G03X1149493Y227729I-482J-481D01*
G01X1149501Y227671D01*
G03X1149676Y227143I1560J224D01*
G01X1149695Y227109D01*
X1149720Y227067D01*
G02X1147765Y223622I-2040J-1120D01*
G01X1147636D01*
G03X1146315Y222834I44J-1575D01*
G02X1144354Y221671I-2015J1162D01*
G01X1143549D01*
X1142602Y220724D01*
Y207497D01*
X1142802Y207210D01*
G01X551200Y200311D02*
Y200593D01*
X544416Y207377D01*
X543376Y209184D01*
G03X542082Y209971I-1365J-787D01*
G01X541926D01*
G02X539996Y213459I85J2325D01*
G03X540015Y215000I-1365J787D01*
G01X539996Y215034D01*
X539971Y215076D01*
G02X539996Y217359I2040J1119D01*
G01X540257Y217810D01*
G02X542011Y220096I9566J-5524D01*
G01X1157820Y235696D02*
X1156666Y236362D01*
X1156356Y236278D01*
G03X1156320Y235213I1465J-583D01*
G03X1156436Y234943I1500J485D01*
G01X1156455Y234909D01*
G02X1154510Y231421I-2015J-1163D01*
G01X1154369D01*
G03X1153075Y229059I71J-1574D01*
G02X1153100Y226776I-2015J-1164D01*
G01X1153075Y226734D01*
X1153056Y226700D01*
G03X1153075Y225159I1384J-754D01*
G02X1151130Y221671I-2015J-1163D01*
G01X1151001D01*
G03X1149695Y220884I59J-1575D01*
G02X1147765Y219722I-2015J1163D01*
G01X1147636D01*
G03X1147621Y216572I43J-1575D01*
G01X1147750D01*
G02X1149720Y215367I-69J-2325D01*
G02X1149695Y213084I-2040J-1119D01*
G01X1149072Y212004D01*
X1147403Y211482D01*
X1146234Y210556D01*
Y208056D01*
X1146434Y207856D01*
Y207769D01*
G01X544286Y199887D02*
Y200168D01*
X540886Y203568D01*
Y205696D01*
X539996Y207234D01*
G03X538702Y208021I-1365J-787D01*
G01X538561D01*
G02X536616Y211509I70J2325D01*
G01X536635Y211543D01*
G03X536616Y213084I-1384J754D01*
G02X536591Y215367I2015J1164D01*
G01X536616Y215409D01*
X536635Y215443D01*
G03X536616Y216984I-1384J754D01*
G02X536304Y218133I2015J1164D01*
G03X535661Y219687I-2197J1D01*
G01X535251Y220096D01*
G01X1161200Y237647D02*
X1160256Y235873D01*
G03X1159185Y234909I944J-2126D01*
G03X1159160Y232626I2015J-1164D01*
G01X1159185Y232584D01*
G02X1157864Y230222I-1365J-787D01*
G01X1157769D01*
G03X1155780Y226776I51J-2326D01*
G01X1155805Y226734D01*
X1155824Y226700D01*
G02X1155805Y225159I-1384J-754D01*
G03X1155780Y222876I2015J-1164D01*
G01X1155805Y222834D01*
X1155824Y222800D01*
G02X1154499Y220472I-1384J-753D01*
G01X1154370D01*
G03X1152425Y216984I70J-2325D01*
G02X1152444Y215443I-1365J-787D01*
G01X1152425Y215409D01*
X1152400Y215367D01*
G03X1152425Y213084I2040J-1119D01*
G01X1152677Y212647D01*
Y211508D01*
X1151675Y210506D01*
Y208752D01*
X1151475Y208465D01*
G01X541620Y194019D02*
X541273Y193970D01*
X540493Y194365D01*
X540109Y195149D01*
X540288Y195671D01*
X539936Y196390D01*
X539413Y196569D01*
X539062Y197287D01*
X539241Y197809D01*
X538889Y198528D01*
X538366Y198707D01*
X538015Y199425D01*
X538194Y199947D01*
X537842Y200666D01*
X537319Y200845D01*
X536896Y201710D01*
X537058Y202940D01*
X537262Y203278D01*
G03X537439Y205362I-2011J1220D01*
G01X537266Y205659D01*
G03X535302Y206822I-2015J-1163D01*
G01X535207D01*
G02X534296Y209650I44J1575D01*
G02X535023Y209956I955J-1253D01*
G01X535500Y209800D01*
Y208646D01*
X535251Y208397D01*
G01X1161200Y225947D02*
X1160046Y226612D01*
X1159736Y226528D01*
G03X1159625Y225985I1464J-582D01*
G03X1159835Y225159I1575J-39D01*
G02X1159860Y222876I-2015J-1164D01*
G01X1159835Y222834D01*
X1159816Y222800D01*
G03X1159835Y221259I1384J-754D01*
G02X1157890Y217771I-2015J-1163D01*
G01X1157761D01*
G03X1156436Y215443I59J-1575D01*
G01X1156455Y215409D01*
X1156480Y215367D01*
G02X1156213Y212740I-2040J-1120D01*
G02X1156191Y212715I-1757J1524D01*
G01X1155835Y212359D01*
Y209658D01*
X1156035Y209458D01*
Y209371D01*
G01X533238Y200588D02*
Y200639D01*
X533450Y200851D01*
Y202964D01*
X533236Y203334D01*
G03X531928Y204122I-1365J-787D01*
G01X531786D01*
G02X529856Y207610I85J2325D01*
G03Y209184I-1365J787D01*
G01X529831Y209226D01*
G02X529544Y210404I2039J1121D01*
G03X528951Y211837I-2026J1D01*
G01X528491Y212296D01*
G01X1164580Y231797D02*
X1164192Y231410D01*
G03X1163527Y229803I1607J-1606D01*
G02X1163215Y228684I-2326J46D01*
G03X1163196Y227143I1365J-787D01*
G01X1163215Y227109D01*
X1163240Y227067D01*
G02X1163215Y224784I-2040J-1119D01*
G03X1163196Y223243I1365J-787D01*
G01X1163215Y223209D01*
X1163240Y223167D01*
G02X1163215Y220884I-2040J-1119D01*
G03X1163196Y219343I1365J-787D01*
G01X1163215Y219309D01*
X1163240Y219267D01*
G02X1163215Y216984I-2040J-1119D01*
G03X1163196Y215443I1365J-787D01*
G01X1163215Y215409D01*
X1163240Y215367D01*
G02X1161251Y211921I-2040J-1120D01*
G01X1161156D01*
G03X1159835Y211133I44J-1575D01*
G01Y211134D01*
X1159200Y210035D01*
Y206529D01*
X1159429Y206300D01*
G01X532563Y191310D02*
Y191615D01*
X526685Y197493D01*
Y202625D01*
G03X526476Y203334I-1574J-79D01*
G01X526451Y203376D01*
G02X526476Y205659I2040J1119D01*
G03X526495Y207200I-1365J787D01*
G01X526476Y207234D01*
G02X526451Y209517I2015J1164D01*
G01X526476Y209559D01*
G03Y211133I-1365J787D01*
G02X528406Y214621I2015J1163D01*
G01X528535D01*
G03X529856Y215409I-44J1575D01*
G02X531801Y216572I2015J-1162D01*
G01X534343D01*
G02X535251Y216196I0J-1284D01*
G01X522600Y253200D02*
X524128Y251672D01*
X525181D01*
G02X527126Y250509I-70J-2325D01*
G03X528447Y249721I1365J787D01*
G01X528576D01*
G02X530531Y246276I-85J-2325D01*
G01X530506Y246234D01*
X530487Y246200D01*
G03X530506Y244659I1384J-754D01*
G02X530531Y242376I-2015J-1164D01*
G01X530506Y242334D01*
X530487Y242300D01*
G03X530506Y240759I1384J-754D01*
G01X530924Y240035D01*
X533057Y239293D01*
G01X547100Y230600D02*
X547421D01*
X547800Y230221D01*
X547801Y230222D01*
X548822D01*
G02X550786Y229059I-51J-2326D01*
G03X552092Y228272I1365J788D01*
G01X552210D01*
G03X553516Y229059I-59J1575D01*
G02X557546I2015J-1163D01*
G03X558852Y228272I1365J788D01*
G01X559872D01*
X561200Y229600D01*
G01X562163Y323177D02*
X559742Y321871D01*
X558416D01*
X558413Y321872D01*
G03X557039Y320698I798J-2325D01*
G02X556064Y319875I-1508J798D01*
G01X554995Y319796D01*
G03X553666Y318682I837J-2348D01*
G03X553321Y317198I2319J-1321D01*
G03X553612Y316515I947J0D01*
G02X553659Y314848I-1448J-875D01*
G02X552808Y314072I-1508J799D01*
G01X552081D01*
G03X550136Y312909I70J-2325D01*
G02X548842Y312122I-1365J787D01*
G01X548686D01*
G03X546756Y310960I85J-2325D01*
G02X545435Y310172I-1365J787D01*
G01X545306D01*
G03X543376Y309010I85J-2325D01*
G02X542055Y308222I-1365J787D01*
G01X541960D01*
G03X539996Y307059I51J-2326D01*
G02X538690Y306272I-1365J788D01*
G01X538561D01*
G03X536616Y305109I70J-2325D01*
G02X535295Y304321I-1365J787D01*
G01X535166D01*
G03X533236Y303159I85J-2325D01*
G02X531930Y302372I-1365J788D01*
G01X531801D01*
G03X529856Y301209I70J-2325D01*
G02X528535Y300421I-1365J787D01*
G01X528406D01*
G03X526476Y299259I85J-2325D01*
G02X525170Y298472I-1365J788D01*
G01X525041D01*
G03X523096Y297309I70J-2325D01*
G02X521775Y296521I-1365J787D01*
G01X521633D01*
G03X519716Y295360I98J-2325D01*
G01X519685Y295306D01*
G02X518352Y294571I-1333J841D01*
G01X518301D01*
G03X516312Y291125I51J-2326D01*
G01X516337Y291083D01*
G02Y289509I-1365J-787D01*
G01X516312Y289467D01*
G03X516337Y287184I2040J-1119D01*
G02X516356Y285643I-1365J-787D01*
G01X516337Y285609D01*
X516312Y285567D01*
G03X516337Y283284I2040J-1119D01*
G02X516356Y281743I-1365J-787D01*
G01X516337Y281709D01*
X516312Y281667D01*
G03X516337Y279384I2040J-1119D01*
G02X516356Y277843I-1365J-787D01*
G01X516337Y277809D01*
G03Y275483I2015J-1163D01*
G02Y273909I-1365J-787D01*
G01X516312Y273867D01*
G03X516337Y271584I2040J-1119D01*
G02X516347Y270028I-1365J-787D01*
G01X516084Y269557D01*
G03X515766Y268334I2193J-1223D01*
G01Y260440D01*
X510736Y255410D01*
G03X509577Y252084I856J-2163D01*
G02X508256Y249721I-1365J-788D01*
G01X508127D01*
G03X506338Y248776I84J-2325D01*
G01X505986Y248681D01*
X504832Y249347D01*
G01X508212Y247396D02*
X507058Y248062D01*
X506975Y248372D01*
G02X508153Y248971I1238J-976D01*
G01X508282D01*
G03X510227Y252459I-70J2325D01*
G02X511143Y254757I1365J787D01*
G01X511157D01*
X516516Y260116D01*
Y268334D01*
G02X516987Y269634I3897J-677D01*
G01X517012Y269676D01*
G03X516987Y271959I-2040J1119D01*
G02X516968Y273500I1365J787D01*
G01X516987Y273534D01*
X517012Y273576D01*
G03X516987Y275859I-2040J1119D01*
G02Y277433I1365J787D01*
G03Y279759I-2015J1163D01*
G02X516968Y281300I1365J787D01*
G01X516987Y281334D01*
X517012Y281376D01*
G03X516987Y283659I-2040J1119D01*
G02X516968Y285200I1365J787D01*
G01X516987Y285234D01*
X517012Y285276D01*
G03X516987Y287559I-2040J1119D01*
G02X516968Y289100I1365J787D01*
G01X516987Y289134D01*
G03Y291458I-2015J1162D01*
G01X516968Y291492D01*
G02X518333Y293821I1384J753D01*
G01X518422D01*
G03X520367Y294983I-70J2326D01*
G01X520380Y295006D01*
G02X521731Y295771I1351J-810D01*
G01X521801D01*
G03X523746Y296934I-70J2325D01*
G02X525067Y297722I1365J-787D01*
G01X525196D01*
G03X527126Y298884I-85J2325D01*
G02X528432Y299671I1365J-788D01*
G01X528561D01*
G03X530506Y300834I-70J2325D01*
G02X531827Y301622I1365J-787D01*
G01X531956D01*
G03X533886Y302784I-85J2325D01*
G02X535192Y303571I1365J-788D01*
G01X535321D01*
G03X537266Y304734I-70J2325D01*
G02X538587Y305522I1365J-787D01*
G01X538716D01*
G03X540646Y306684I-85J2325D01*
G02X541952Y307471I1365J-788D01*
G01X542062D01*
G03X544026Y308634I-51J2326D01*
G02X545347Y309422I1365J-787D01*
G01X545476D01*
G03X547406Y310584I-85J2325D01*
G02X548700Y311371I1365J-787D01*
G01X548841D01*
G03X550786Y312534I-70J2325D01*
G02X552107Y313322I1365J-787D01*
G01X552951D01*
G03X554323Y314495I-800J2325D01*
G03X554255Y317078I-2321J1231D01*
G02X554317Y318310I1249J555D01*
G02X555165Y319057I1514J-864D01*
G01X556214Y319135D01*
G03X557703Y320345I-683J2361D01*
G02X558553Y321121I1508J-798D01*
G01X560212D01*
X570596Y326728D01*
G01X561100Y226200D02*
X559778Y227522D01*
X558826D01*
G02X556896Y228684I85J2325D01*
G03X555590Y229471I-1365J-788D01*
G01X555472D01*
G03X554166Y228684I59J-1575D01*
G02X552236Y227522I-2015J1163D01*
G01X552066D01*
G02X550136Y228684I85J2325D01*
G03X548830Y229471I-1365J-788D01*
G01X547421D01*
G01X531434Y235365D02*
X530272Y236527D01*
Y239666D01*
X529856Y240384D01*
G02X529831Y242667I2015J1164D01*
G01X529856Y242709D01*
X529875Y242743D01*
G03X529856Y244284I-1384J754D01*
G02X529831Y246567I2015J1164D01*
G01X529856Y246609D01*
X529875Y246643D01*
G03X528550Y248971I-1384J753D01*
G01X528421D01*
G02X526476Y250134I70J2325D01*
G03X525155Y250922I-1365J-787D01*
G01X524022D01*
X523400Y250300D01*
G01X535251Y243496D02*
X535250Y244150D01*
G03X533917Y244405I-691J0D01*
G01X533787Y244078D01*
G03X533779Y242935I1465J-582D01*
G03X535207Y241921I1473J561D01*
G01X535336D01*
G02X537266Y240759I-85J-2325D01*
G03X538572Y239972I1365J788D01*
G01X538701D01*
G02X540646Y238809I-70J-2325D01*
G03X541967Y238021I1365J787D01*
G01X542096D01*
G02X544026Y236859I-85J-2325D01*
G03X545332Y236072I1365J788D01*
G01X545442D01*
G02X547406Y234909I-51J-2326D01*
G03X548700Y234122I1365J787D01*
G01X548841D01*
G02X550786Y232959I-70J-2325D01*
G03X552080Y232172I1365J787D01*
G01X552222D01*
G03X553516Y232959I-71J1574D01*
G02X555849Y234307I2333J-1346D01*
G01X560698D01*
X560951Y234054D01*
X565598D01*
X566763Y235219D01*
X574728D01*
X576871Y237362D01*
X578549D01*
X578749Y237562D01*
X578836D01*
G01X1208423Y303841D02*
Y303754D01*
X1208223Y303554D01*
Y292773D01*
X1207321Y291871D01*
X1204895D01*
G02X1204426Y291944I-1J1538D01*
G03X1202482Y292247I-1944J-6086D01*
G01X1201759D01*
G01X538631Y272747D02*
Y271416D01*
X538859Y271188D01*
G03X539996Y271959I-228J1560D01*
G02X541926Y273121I2015J-1163D01*
G01X542055D01*
G03X543376Y273909I-44J1575D01*
G02X545321Y275072I2015J-1162D01*
G01X545462D01*
G03X546756Y275859I-71J1574D01*
G02X548686Y277021I2015J-1163D01*
G01X548815D01*
G03X550136Y277809I-44J1575D01*
G02X554166I2015J-1163D01*
G03X555487Y277021I1365J787D01*
G01X557913D01*
X558113Y277221D01*
G01X1218827Y255280D02*
X1218740D01*
X1218540Y255480D01*
X1217039D01*
X1215713Y256806D01*
X1211956D01*
G03X1210534Y255984I1J-1643D01*
G02X1208591Y254822I-2015J1163D01*
G01X1206042D01*
G02X1205139Y255196I0J1277D01*
G01X1208519Y249347D02*
Y250678D01*
X1208763Y250922D01*
X1209319D01*
G03X1210691Y252095I-800J2325D01*
G02X1211542Y252871I1508J-799D01*
G01X1213266D01*
X1213770Y252367D01*
X1216394D01*
X1216594Y252167D01*
X1216681D01*
G01X560927Y283072D02*
X560840D01*
X560640Y282872D01*
X558413D01*
G03X557039Y281698I798J-2325D01*
G02X556186Y280921I-1508J798D01*
G01X555487D01*
G02X554166Y281709I44J1575D01*
G03X552221Y282872I-2015J-1162D01*
G01X552081D01*
G03X550136Y281709I70J-2325D01*
G02X548815Y280921I-1365J787D01*
G01X548686D01*
G03X546756Y279759I85J-2325D01*
G02X545450Y278972I-1365J788D01*
G01X545340D01*
G03X543376Y277809I51J-2326D01*
G02X542055Y277021I-1365J787D01*
G01X541926D01*
G03X539996Y275859I85J-2325D01*
G02X538702Y275072I-1365J787D01*
G01X538561D01*
G03X536616Y273909I70J-2325D01*
G02X535295Y273121I-1365J787D01*
G01X535166D01*
G03X534478Y272990I86J-2325D01*
G02X531871Y272747I-1787J5065D01*
G01X538631Y276646D02*
X537477Y275981D01*
X537167Y276065D01*
G02X537266Y277433I1464J582D01*
G03Y279759I-2015J1163D01*
G02X538587Y282122I1365J788D01*
G01X538716D01*
G03X540671Y285567I-85J2325D01*
G01X540646Y285609D01*
X540627Y285643D01*
G02X540646Y287184I1384J754D01*
G03X540671Y289467I-2015J1164D01*
G01X540646Y289509D01*
X540627Y289543D01*
G02X541952Y291871I1384J753D01*
G01X542081D01*
G03X544026Y293034I-70J2325D01*
G02X545347Y293822I1365J-787D01*
G01X545476D01*
G03X547406Y294984I-85J2325D01*
G02X548712Y295771I1365J-788D01*
G01X548841D01*
G03X550786Y296934I-70J2325D01*
G02X552107Y297722I1365J-787D01*
G01X552951D01*
G03X554323Y298895I-800J2325D01*
G02X555174Y299671I1508J-799D01*
G01X558241D01*
X558551Y299981D01*
X559057D01*
X559553Y300477D01*
Y300983D01*
X560049Y301479D01*
X560555D01*
X561051Y301975D01*
Y302481D01*
X561547Y302977D01*
X562053D01*
X562549Y303473D01*
Y303979D01*
X562791Y304221D01*
X563597D01*
X563963Y303855D01*
X564663D01*
X565029Y304221D01*
X566214D01*
X566414Y304021D01*
X566501D01*
G01X1219163Y236641D02*
X1219076D01*
X1218876Y236441D01*
X1214980D01*
X1213400Y238021D01*
X1211230D01*
G02X1210997Y238959I0J498D01*
G01X1211000Y238961D01*
X1211400Y239173D01*
X1212199Y239596D01*
G01X535251Y278596D02*
G03X534300Y280000I-3321J-1225D01*
G02X533211Y281376I3518J3903D01*
G02X535166Y284821I2040J1120D01*
G01X535295D01*
G03X536616Y287184I-44J1575D01*
G02X536591Y289467I2015J1164D01*
G01X536616Y289509D01*
X536635Y289543D01*
G03X536616Y291084I-1384J754D01*
G02X538561Y294572I2015J1163D01*
G01X538690D01*
G03X539996Y295359I-59J1575D01*
G02X541926Y296521I2015J-1163D01*
G01X542055D01*
G03X543376Y297309I-44J1575D01*
G02X545321Y298472I2015J-1162D01*
G01X545450D01*
G03X546756Y299259I-59J1575D01*
G02X548686Y300421I2015J-1163D01*
G01X548815D01*
G03X550136Y301209I-44J1575D01*
G02X552081Y302372I2015J-1162D01*
G01X552808D01*
G03X553659Y303148I-657J1575D01*
G02X555031Y304321I2172J-1152D01*
G01X557610D01*
X561280Y307991D01*
X570792D01*
X570992Y308191D01*
X571079D01*
G01X1219811Y232931D02*
X1219724D01*
X1219524Y233131D01*
X1213669D01*
X1213429Y233371D01*
X1211401D01*
G02X1211250Y233429I805J2322D01*
G02X1210027Y234545I949J2268D01*
G03X1209176Y235321I-1508J-799D01*
G01X1208468D01*
G02X1206504Y236484I51J2326D01*
G03X1205367Y237255I-1365J-789D01*
G01X1205139Y237027D01*
Y235696D01*
G01X538631Y241547D02*
Y242878D01*
X538859Y243106D01*
G02X539996Y242334I-228J-1559D01*
G03X541941Y241171I2015J1162D01*
G01X542070D01*
G02X543376Y240384I-59J-1575D01*
G03X545306Y239222I2015J1163D01*
G01X545435D01*
G02X546756Y238434I-44J-1575D01*
G03X548701Y237271I2015J1162D01*
G01X548830D01*
G02X550136Y236484I-59J-1575D01*
G03X552079Y235322I2015J1163D01*
G01X561314D01*
X563281Y237289D01*
X565000D01*
X565852Y236437D01*
X573249D01*
X576262Y239450D01*
X578768D01*
X578968Y239250D01*
X579055D01*
G01X538631Y261047D02*
X537477Y261712D01*
X537394Y262022D01*
G02X538587Y262622I1238J-975D01*
G01X538716D01*
G03X540646Y263784I-85J2325D01*
G02X541952Y264571I1365J-788D01*
G01X542081D01*
G03X544026Y265734I-70J2325D01*
G02X545347Y266522I1365J-787D01*
G01X545476D01*
G03X547406Y267684I-85J2325D01*
G02X548712Y268471I1365J-788D01*
G01X548830D01*
G02X550136Y267684I-59J-1575D01*
G03X552066Y266522I2015J1163D01*
G01X552236D01*
G03X554166Y267684I-85J2325D01*
G02X555472Y268471I1365J-788D01*
G01X555590D01*
G02X556896Y267684I-59J-1575D01*
G03X558827Y266522I2015J1163D01*
G01X559922D01*
X560439Y267039D01*
X560953D01*
X561449Y267535D01*
Y268049D01*
X564632Y271232D01*
X565518D01*
X565718Y271032D01*
X565805D01*
G01X1224693Y265806D02*
X1224606D01*
X1224406Y265606D01*
X1222453D01*
X1217703Y260856D01*
X1207279D01*
X1205139Y262996D01*
G01X531871Y245447D02*
G02X532225Y244901I-1101J-1101D01*
G01X533077Y242667D01*
G03X535181Y241171I2173J829D01*
G01X535310D01*
G02X536616Y240384I-59J-1575D01*
G03X538546Y239222I2015J1163D01*
G01X538675D01*
G02X539996Y238434I-44J-1575D01*
G03X541941Y237271I2015J1162D01*
G01X542070D01*
G02X543376Y236484I-59J-1575D01*
G03X545340Y235321I2015J1163D01*
G01X545435D01*
G02X546756Y234533I-44J-1575D01*
G03X548686Y233371I2015J1163D01*
G01X548842D01*
G02X550136Y232584I-71J-1574D01*
G03X552081Y231421I2015J1162D01*
G01X552082Y231422D01*
X552238D01*
G03X554166Y232584I-87J2324D01*
G02X555850Y233557I1684J-970D01*
G01X560387D01*
X560640Y233304D01*
X565909D01*
X567074Y234469D01*
X575039D01*
X577182Y236612D01*
X578549D01*
X578749Y236412D01*
X578836D01*
G01X1207273Y303841D02*
Y303754D01*
X1207473Y303554D01*
Y301557D01*
X1207101Y301185D01*
Y300485D01*
X1207473Y300113D01*
Y299413D01*
X1207101Y299041D01*
Y298341D01*
X1207473Y297969D01*
Y297269D01*
X1207101Y296897D01*
Y296197D01*
X1207473Y295825D01*
Y293084D01*
X1207010Y292621D01*
X1204895D01*
G02X1204655Y292659I2J787D01*
G02X1204895Y294196I240J750D01*
G01X1205439D01*
G01X538631Y264947D02*
X539847Y267752D01*
G02X541926Y269221I2164J-856D01*
G01X542055D01*
G03X543376Y270009I-44J1575D01*
G02X545321Y271172I2015J-1162D01*
G01X545450D01*
G03X546756Y271959I-59J1575D01*
G02X548686Y273121I2015J-1163D01*
G01X548815D01*
G03X550136Y273909I-44J1575D01*
G02X552081Y275072I2015J-1162D01*
G01X552221D01*
G02X554166Y273909I-70J-2325D01*
G03X555487Y273121I1365J787D01*
G01X555616D01*
G02X557546Y271959I-85J-2325D01*
G03X558842Y271172I1365J788D01*
G01X559571D01*
X562642Y274243D01*
X564887D01*
X566774Y276130D01*
X566835Y276474D01*
G01X1208519Y257147D02*
X1208058D01*
G03Y255572I0J-787D01*
G01X1208578D01*
G03X1209884Y256359I-59J1575D01*
G02X1211955Y257556I2073J-1196D01*
G01X1216024D01*
X1217350Y256230D01*
X1218540D01*
X1218740Y256430D01*
X1218827D01*
G01X558113Y276071D02*
X557913Y276271D01*
X555446D01*
G02X553516Y277433I85J2325D01*
G03X550786I-1365J-787D01*
G02X548856Y276271I-2015J1163D01*
G01X548727D01*
G03X547406Y275483I44J-1575D01*
G02X545476Y274321I-2015J1163D01*
G01X545320D01*
G03X544026Y273534I71J-1574D01*
G02X542081Y272371I-2015J1162D01*
G01X541952D01*
G03X540646Y271584I59J-1575D01*
G02X538887Y270434I-2015J1162D01*
G01X538631Y270178D01*
Y268847D01*
G01X535251Y270796D02*
X534097Y271462D01*
X534014Y271772D01*
G02X535192Y272371I1238J-976D01*
G01X535321D01*
G03X537266Y273534I-70J2325D01*
G02X538560Y274321I1365J-787D01*
G01X538716D01*
G03X540646Y275483I-85J2325D01*
G02X541967Y276271I1365J-787D01*
G01X542096D01*
G03X544026Y277433I-85J2325D01*
G02X545347Y278221I1365J-787D01*
G01X545442D01*
G03X547406Y279384I-51J2326D01*
G02X548712Y280171I1365J-788D01*
G01X548841D01*
G03X550786Y281334I-70J2325D01*
G02X552107Y282122I1365J-787D01*
G01X552195D01*
G02X553516Y281334I-44J-1575D01*
G03X555461Y280171I2015J1162D01*
G01X556329D01*
G03X557703Y281345I-798J2325D01*
G02X558556Y282122I1508J-798D01*
G01X560640D01*
X560840Y281922D01*
X560927D01*
G01X1216681Y253317D02*
X1216594D01*
X1216394Y253117D01*
X1214081D01*
X1213577Y253621D01*
X1211405D01*
G03X1210028Y252447I793J-2325D01*
G01X1210027Y252448D01*
G02X1209176Y251672I-1508J799D01*
G01X1208763D01*
X1208519Y251916D01*
Y253247D01*
G01X535251Y274696D02*
G02X535578Y275952I2574J0D01*
G01X536635Y277843D01*
G03X536616Y279384I-1384J754D01*
G02X538561Y282872I2015J1163D01*
G01X538690D01*
G03X540015Y285200I-59J1575D01*
G01X539996Y285234D01*
X539971Y285276D01*
G02X539996Y287559I2040J1119D01*
G03X540015Y289100I-1365J787D01*
G01X539996Y289134D01*
X539971Y289176D01*
G02X541926Y292621I2040J1120D01*
G01X542055D01*
G03X543376Y293409I-44J1575D01*
G02X545321Y294572I2015J-1162D01*
G01X545450D01*
G03X546756Y295359I-59J1575D01*
G02X548686Y296521I2015J-1163D01*
G01X548815D01*
G03X550136Y297309I-44J1575D01*
G02X552081Y298472I2015J-1162D01*
G01X552808D01*
G03X553659Y299248I-657J1575D01*
G02X555031Y300421I2172J-1152D01*
G01X557930D01*
X562480Y304971D01*
X566214D01*
X566414Y305171D01*
X566501D01*
G01X1219163Y235491D02*
X1219076D01*
X1218876Y235691D01*
X1214669D01*
X1213089Y237271D01*
X1209427D01*
G02X1208519Y237647I0J1284D01*
G01X538631Y245447D02*
Y244116D01*
X538888Y243859D01*
G02X540646Y242709I-257J-2312D01*
G03X541967Y241921I1365J787D01*
G01X542096D01*
G02X544026Y240759I-85J-2325D01*
G03X545332Y239972I1365J788D01*
G01X545461D01*
G02X547406Y238809I-70J-2325D01*
G03X548727Y238021I1365J787D01*
G01X548856D01*
G02X550786Y236859I-85J-2325D01*
G03X552092Y236072I1365J788D01*
G01X561003D01*
X562970Y238039D01*
X565311D01*
X566163Y237187D01*
X572938D01*
X575951Y240200D01*
X578768D01*
X578968Y240400D01*
X579055D01*
G01X538631Y253247D02*
X539785Y252581D01*
X540137Y252676D01*
G02X541926Y253621I1873J-1380D01*
G01X542055D01*
G03X543376Y254409I-44J1575D01*
G02X545389Y255572I2013J-1161D01*
G01X545393D01*
G02X547406Y254409I0J-2324D01*
G03X548727Y253621I1365J787D01*
G01X548856D01*
G02X550786Y252459I-85J-2325D01*
G03X552092Y251672I1365J788D01*
G01X552221D01*
G02X554166Y250509I-70J-2325D01*
G03X555487Y249721I1365J787D01*
G01X555615D01*
G02X557547Y248559I-83J-2325D01*
G01X557672Y248341D01*
X558306Y247707D01*
X561509D01*
X566857Y253055D01*
X572914D01*
X573114Y253255D01*
X573201D01*
G01X1217887Y277943D02*
X1217826Y277882D01*
X1217544Y277883D01*
X1217095Y277434D01*
Y276235D01*
X1213154Y272294D01*
X1211400Y271454D01*
X1209243Y270422D01*
X1208435D01*
G02X1206504Y271584I84J2325D01*
G03X1205198Y272371I-1365J-788D01*
G01X1205080D01*
G03X1203774Y271584I59J-1575D01*
G02X1202015Y270434I-2015J1162D01*
G01X1201759Y270178D01*
Y268847D01*
G01X535251Y262996D02*
X538293Y263348D01*
G02X538561Y263372I341J-2301D01*
G01X538690D01*
G03X539996Y264159I-59J1575D01*
G02X541926Y265321I2015J-1163D01*
G01X542055D01*
G03X543376Y266109I-44J1575D01*
G02X545321Y267272I2015J-1162D01*
G01X545450D01*
G03X546756Y268059I-59J1575D01*
G02X548686Y269221I2015J-1163D01*
G01X548856D01*
G02X550786Y268059I-85J-2325D01*
G03X552092Y267272I1365J788D01*
G01X552210D01*
G03X553516Y268059I-59J1575D01*
G02X555446Y269221I2015J-1163D01*
G01X555616D01*
G02X557546Y268059I-85J-2325D01*
G03X558842Y267272I1365J788D01*
G01X559611D01*
X564321Y271982D01*
X565518D01*
X565718Y272182D01*
X565805D01*
G01X1224693Y264656D02*
X1224606D01*
X1224406Y264856D01*
X1222764D01*
X1218014Y260106D01*
X1206968D01*
X1206574Y260500D01*
X1206107D01*
X1205808Y260201D01*
Y259765D01*
X1205139Y259096D01*
G01X538631Y280547D02*
G02X539534Y280921I903J-903D01*
G01X542055D01*
G03X543376Y281709I-44J1575D01*
G02X545321Y282872I2015J-1162D01*
G01X545450D01*
G03X546756Y283659I-59J1575D01*
G02X548686Y284821I2015J-1163D01*
G01X548815D01*
G03X550136Y285609I-44J1575D01*
G02X552081Y286772I2015J-1162D01*
G01X553923D01*
X559986Y292835D01*
X562955D01*
X563155Y293035D01*
X563242D01*
G01X1215470Y248644D02*
X1215178Y248843D01*
X1213776Y248833D01*
X1210116Y246950D01*
X1207494D01*
X1205473Y248971D01*
X1205069D01*
G02X1202824Y251062I69J2325D01*
G01X1202562Y251600D01*
X1201759Y253247D01*
G01X531871Y284447D02*
G02X533236Y287559I14816J-4643D01*
G03X533255Y289100I-1365J787D01*
G01X533236Y289134D01*
X533211Y289176D01*
G02X533236Y291459I2040J1119D01*
G03X533255Y293000I-1365J787D01*
G01X533236Y293034D01*
X533211Y293076D01*
G02X535166Y296521I2040J1120D01*
G01X535295D01*
G03X536616Y297309I-44J1575D01*
G02X538561Y298472I2015J-1162D01*
G01X538690D01*
G03X539996Y299259I-59J1575D01*
G02X541926Y300421I2015J-1163D01*
G01X542055D01*
G03X543376Y301209I-44J1575D01*
G02X545321Y302372I2015J-1162D01*
G01X545450D01*
G03X546756Y303159I-59J1575D01*
G02X548686Y304321I2015J-1163D01*
G01X548815D01*
G03X550136Y305109I-44J1575D01*
G02X552081Y306272I2015J-1162D01*
G01X552808D01*
G03X553659Y307048I-657J1575D01*
G02X554875Y308161I2172J-1152D01*
G01X555652Y308221D01*
X557169D01*
X559901Y310953D01*
X562788D01*
X562988Y311153D01*
X563075D01*
G01X531871Y280547D02*
G03X531499Y281937I-2782J0D01*
G01X530506Y283659D01*
G02X530412Y283850I1364J790D01*
G02X530487Y285200I1459J596D01*
G01X530506Y285234D01*
X530531Y285276D01*
G03X530506Y287559I-2040J1119D01*
G02X530487Y289100I1365J787D01*
G01X530506Y289134D01*
X530531Y289176D01*
G03X530506Y291459I-2040J1119D01*
G02X530487Y293000I1365J787D01*
G01X530506Y293034D01*
X530531Y293076D01*
G03X530506Y295359I-2040J1119D01*
G02X531827Y297722I1365J788D01*
G01X531956D01*
G03X533886Y298884I-85J2325D01*
G02X535192Y299671I1365J-788D01*
G01X535321D01*
G03X537266Y300834I-70J2325D01*
G02X538587Y301622I1365J-787D01*
G01X538716D01*
G03X540646Y302784I-85J2325D01*
G02X541952Y303571I1365J-788D01*
G01X542081D01*
G03X544026Y304734I-70J2325D01*
G02X545347Y305522I1365J-787D01*
G01X545476D01*
G03X547406Y306684I-85J2325D01*
G02X548712Y307471I1365J-788D01*
G01X548822D01*
G03X550786Y308634I-51J2326D01*
G02X552107Y309422I1365J-787D01*
G01X552236D01*
G03X554166Y310584I-85J2325D01*
G02X555460Y311371I1365J-787D01*
G02X555462Y311372I704J-1405D01*
G01X557622D01*
X559634Y313384D01*
X562220D01*
X562420Y313184D01*
X562507D01*
G01X1218680Y228996D02*
X1218593D01*
X1218393Y228796D01*
X1216856D01*
X1214381Y226321D01*
X1209422D01*
G03X1208519Y225947I0J-1277D01*
G01X535251Y282496D02*
Y281165D01*
X535023Y280937D01*
G02X533869Y281737I227J1559D01*
G02X535192Y284071I1381J759D01*
G01X535321D01*
G03X537266Y287559I-70J2325D01*
G02X537247Y289100I1365J787D01*
G01X537266Y289134D01*
X537291Y289176D01*
G03X537266Y291459I-2040J1119D01*
G02X538587Y293822I1365J788D01*
G01X538716D01*
G03X540646Y294984I-85J2325D01*
G02X541952Y295771I1365J-788D01*
G01X542081D01*
G03X544026Y296934I-70J2325D01*
G02X545347Y297722I1365J-787D01*
G01X545476D01*
G03X547406Y298884I-85J2325D01*
G02X548712Y299671I1365J-788D01*
G01X548841D01*
G03X550786Y300834I-70J2325D01*
G02X552107Y301622I1365J-787D01*
G01X552951D01*
G03X554323Y302795I-800J2325D01*
G02X555174Y303571I1508J-799D01*
G01X557921D01*
X558289Y303939D01*
X558797D01*
X559292Y304434D01*
Y304942D01*
X559787Y305437D01*
X560295D01*
X560790Y305932D01*
Y306440D01*
X561591Y307241D01*
X562242D01*
X562592Y306891D01*
X563292D01*
X563642Y307241D01*
X564342D01*
X564692Y306891D01*
X565392D01*
X565742Y307241D01*
X566442D01*
X566792Y306891D01*
X567492D01*
X567842Y307241D01*
X568542D01*
X568892Y306891D01*
X569592D01*
X569942Y307241D01*
X570792D01*
X570992Y307041D01*
X571079D01*
G01X1219811Y234081D02*
X1219724D01*
X1219524Y233881D01*
X1213980D01*
X1213740Y234121D01*
X1211542D01*
X1211540Y234122D01*
G02X1210691Y234897I659J1574D01*
G03X1209315Y236072I-2172J-1151D01*
G01X1208460D01*
G02X1207154Y236859I59J1575D01*
G03X1205395Y238009I-2015J-1162D01*
G01X1205139Y238265D01*
Y239596D01*
G01X535251Y286396D02*
G02X533676Y286400I-787J4D01*
G02X533886Y287184I1576J-2D01*
G03X533911Y289467I-2015J1164D01*
G01X533886Y289509D01*
X533867Y289543D01*
G02X533886Y291084I1384J754D01*
G03X533911Y293367I-2015J1164D01*
G01X533886Y293409D01*
X533867Y293443D01*
G02X535192Y295771I1384J753D01*
G01X535321D01*
G03X537266Y296934I-70J2325D01*
G02X538587Y297722I1365J-787D01*
G01X538716D01*
G03X540646Y298884I-85J2325D01*
G02X541952Y299671I1365J-788D01*
G01X542081D01*
G03X544026Y300834I-70J2325D01*
G02X545347Y301622I1365J-787D01*
G01X545476D01*
G03X547406Y302784I-85J2325D01*
G02X548712Y303571I1365J-788D01*
G01X548841D01*
G03X550786Y304734I-70J2325D01*
G02X552107Y305522I1365J-787D01*
G01X552951D01*
G03X554323Y306695I-800J2325D01*
G02X555069Y307423I1508J-799D01*
G01X555682Y307471D01*
X557986D01*
X558480Y307965D01*
Y308471D01*
X558974Y308965D01*
X559480D01*
X559974Y309459D01*
Y309965D01*
X560212Y310203D01*
X560850D01*
X561216Y309837D01*
X561916D01*
X562282Y310203D01*
X562788D01*
X562988Y310003D01*
X563075D01*
G01X528491Y282496D02*
G03X529671Y283690I295J889D01*
G02X529831Y285567I2197J758D01*
G01X529856Y285609D01*
X529875Y285643D01*
G03X529856Y287184I-1384J754D01*
G02X529831Y289467I2015J1164D01*
G01X529856Y289509D01*
X529875Y289543D01*
G03X529856Y291084I-1384J754D01*
G02X529831Y293367I2015J1164D01*
G01X529856Y293409D01*
X529875Y293443D01*
G03X529856Y294984I-1384J754D01*
G02X531801Y298472I2015J1163D01*
G01X531930D01*
G03X533236Y299259I-59J1575D01*
G02X535166Y300421I2015J-1163D01*
G01X535295D01*
G03X536616Y301209I-44J1575D01*
G02X538561Y302372I2015J-1162D01*
G01X538690D01*
G03X539996Y303159I-59J1575D01*
G02X541926Y304321I2015J-1163D01*
G01X542055D01*
G03X543376Y305109I-44J1575D01*
G02X545321Y306272I2015J-1162D01*
G01X545450D01*
G03X546756Y307059I-59J1575D01*
G02X548720Y308222I2015J-1163D01*
G01X548815D01*
G03X550136Y309010I-44J1575D01*
G02X552066Y310172I2015J-1163D01*
G01X552195D01*
G03X553516Y310960I-44J1575D01*
G02X555446Y312122I2015J-1163D01*
G01X557311D01*
X557910Y312721D01*
Y313235D01*
X558404Y313729D01*
X558918D01*
X559323Y314134D01*
X562220D01*
X562420Y314334D01*
X562507D01*
G01X1218680Y227846D02*
X1218593D01*
X1218393Y228046D01*
X1217167D01*
X1214692Y225571D01*
X1211587D01*
G03Y223996I0J-787D01*
G01X1212199D01*
G01X1151060Y243496D02*
X1149095Y243393D01*
G03X1147750Y243872I-1415J-1846D01*
G01X1147610D01*
G03X1145665Y242709I70J-2325D01*
G02X1144344Y241921I-1365J787D01*
G01X1143079D01*
X1137231Y236073D01*
X1136420D01*
G03X1134405Y234909I0J-2326D01*
G02X1133111Y234122I-1365J787D01*
G01X1132970D01*
G03X1131025Y232959I70J-2325D01*
G02X1129731Y232172I-1365J787D01*
G01X1129575D01*
G03X1127645Y228684I85J-2325D01*
G02X1127664Y227143I-1365J-787D01*
G01X1127645Y227109D01*
X1127620Y227067D01*
G03X1127645Y224784I2040J-1119D01*
G02X1127664Y223243I-1365J-787D01*
G01X1127645Y223209D01*
X1127620Y223167D01*
G03X1127645Y220884I2040J-1119D01*
G02X1127664Y219343I-1365J-787D01*
G01X1127645Y219309D01*
X1127620Y219267D01*
G03X1127645Y216984I2040J-1119D01*
G02X1127664Y215443I-1365J-787D01*
G01X1127645Y215409D01*
X1127620Y215367D01*
G03X1127645Y213084I2040J-1119D01*
G02X1127664Y211543I-1365J-787D01*
G01X1127433Y211143D01*
X1126222Y209932D01*
X1123746D01*
X1123546Y210132D01*
X1123459D01*
G01X566464Y221243D02*
X566384Y221276D01*
X566123Y221167D01*
X563122Y222417D01*
X561917Y222427D01*
G02X561096Y223197I699J1568D01*
G03X559743Y224372I-2185J-1150D01*
G01X558852D01*
G02X557546Y225159I59J1575D01*
G03X555787Y226309I-2015J-1162D01*
G01X555531Y226565D01*
Y227896D01*
G01X1144300Y239596D02*
X1145064D01*
G02X1145538Y238621I0J-603D01*
G01X1145537D01*
G02X1145006Y238188I-1238J976D01*
G02X1144344Y238021I-707J1408D01*
G01X1143095D01*
X1137250Y232176D01*
X1136427D01*
G03X1134405Y231009I-2J-2333D01*
G02X1133081Y230221I-1365J788D01*
G01X1133036D01*
X1133035Y230222D01*
X1132989D01*
G03X1131000Y226776I51J-2326D01*
G01X1131025Y226734D01*
X1131044Y226700D01*
G02X1131025Y225159I-1384J-754D01*
G03X1131000Y222876I2015J-1164D01*
G01X1131025Y222834D01*
X1131044Y222800D01*
G02X1131025Y221259I-1384J-754D01*
G03X1131000Y218976I2015J-1164D01*
G01X1131025Y218934D01*
X1131044Y218900D01*
G02X1131025Y217359I-1384J-754D01*
G03X1131000Y215076I2015J-1164D01*
G01X1131025Y215034D01*
X1131044Y215000D01*
G02X1131025Y213459I-1384J-754D01*
G03X1131002Y211175I2015J-1162D01*
G01X1131306Y210649D01*
Y209437D01*
X1130637Y208768D01*
X1127869D01*
X1125527Y206426D01*
X1123993D01*
X1123793Y206626D01*
X1123706D01*
G01X566806Y215990D02*
X566544Y215879D01*
X563745Y217017D01*
X563540Y217502D01*
X562932Y217749D01*
X562447Y217545D01*
X561892Y217771D01*
X561083Y219298D01*
G03X559709Y220472I-2172J-1151D01*
G01X558857D01*
G03X556896Y219309I54J-2325D01*
G02X554166I-1365J787D01*
G01X554147Y219343D01*
G02X553977Y219831I1384J756D01*
G02X554687Y220942I967J164D01*
G01X554689D01*
X555416Y220525D01*
X555531Y220096D01*
G01X1151060Y235696D02*
X1151200Y236800D01*
X1150774Y237245D01*
G03X1149695Y236484I285J-1550D01*
G02X1147731Y235321I-2015J1163D01*
G01X1147636D01*
G03X1146315Y234533I44J-1575D01*
G02X1144385Y233371I-2015J1163D01*
G01X1144371Y233372D01*
X1143354D01*
X1137508Y227526D01*
X1136421D01*
G03X1135055Y225159I1J-1578D01*
G02X1135080Y222876I-2015J-1164D01*
G01X1135055Y222834D01*
X1135036Y222800D01*
G03X1135055Y221259I1384J-754D01*
G02X1135080Y218976I-2015J-1164D01*
G01X1135055Y218934D01*
X1135036Y218900D01*
G03X1135055Y217359I1384J-754D01*
G02X1135080Y215076I-2015J-1164D01*
G01X1135055Y215034D01*
X1135036Y215000D01*
G03X1135055Y213459I1384J-754D01*
G02X1135078Y211175I-2015J-1162D01*
G01X1134819Y210726D01*
X1134708Y210534D01*
Y207253D01*
X1131577Y204122D01*
X1127749D01*
X1125377Y201750D01*
X1123750D01*
X1123463Y201550D01*
G01X567700Y206900D02*
Y207087D01*
X567646Y207141D01*
X567547Y207202D01*
Y207204D01*
X559993Y211894D01*
X555088Y213294D01*
X553746Y214636D01*
X553516Y215034D01*
G03X552208Y215822I-1365J-787D01*
G01X552066D01*
G02X550111Y219267I85J2325D01*
G01X550136Y219309D01*
X550155Y219343D01*
G03X550062Y220999I-1384J753D01*
G01X549861Y221286D01*
G03X548771Y220943I-491J-343D01*
G01Y220096D01*
G01X1144300Y227896D02*
Y229500D01*
X1144000Y229800D01*
X1143364D01*
X1141705Y228141D01*
Y227193D01*
X1138780Y224268D01*
Y209309D01*
X1136726Y207255D01*
Y206212D01*
X1136926Y206012D01*
Y205925D01*
G01X558687Y203650D02*
X558600D01*
X558400Y203850D01*
X556389D01*
X554464Y205775D01*
X552641Y210176D01*
X550685Y212131D01*
X550136Y213084D01*
G03X548840Y213871I-1365J-788D01*
G01X548701D01*
G02X546444Y216200I69J2325D01*
G03X545812Y217726I-2158J0D01*
G01X545391Y218147D01*
G01X1154440Y233746D02*
X1152507Y234121D01*
X1150973D01*
G03X1149045Y232959I87J-2324D01*
G02X1147751Y232172I-1365J787D01*
G01X1147595D01*
G03X1145665Y228684I85J-2325D01*
G02X1144357Y226321I-1365J-788D01*
G01X1142730D01*
X1139918Y223509D01*
Y208752D01*
X1139039Y207873D01*
Y203423D01*
X1138839Y203223D01*
G01X559091Y201093D02*
X558695D01*
X558188Y201600D01*
X556200D01*
X552500Y205300D01*
X552218Y205981D01*
Y206542D01*
X547619Y211141D01*
X547406Y211510D01*
G03X545441Y212672I-2015J-1164D01*
G01X545332D01*
G02X544154Y213271I60J1575D01*
G01X544237Y213581D01*
X545391Y214247D01*
G01X1147680Y229847D02*
X1148786Y227400D01*
G03X1149020Y226776I2273J497D01*
G01X1149045Y226734D01*
X1149064Y226700D01*
G02X1147739Y224372I-1384J-753D01*
G01X1147610D01*
G03X1145665Y223209I70J-2325D01*
G02X1144344Y222421I-1365J787D01*
G01X1143238D01*
X1141852Y221035D01*
Y207482D01*
X1141652Y207282D01*
G01X552139Y201000D02*
X551854D01*
X548101Y204753D01*
Y205306D01*
X547606Y205801D01*
X547053D01*
X546559Y206295D01*
Y206848D01*
X546064Y207343D01*
X545511D01*
X545017Y207837D01*
X544027Y209559D01*
G03X542098Y210721I-2015J-1162D01*
G01X541962D01*
X541940Y210722D01*
G02X540646Y213084I71J1574D01*
G03X540671Y215367I-2015J1164D01*
G01X540646Y215409D01*
X540627Y215443D01*
G02X540647Y216983I1385J752D01*
G02X541783Y217755I1365J-787D01*
G01X542080D01*
X542430Y217405D01*
Y216615D01*
X542011Y216196D01*
G01X1147680Y241547D02*
X1148834Y242212D01*
X1148917Y242522D01*
G03X1148847Y242603I-1226J-989D01*
G03X1148845Y242606I-1296J-862D01*
G03X1148637Y242797I-1165J-1060D01*
G03X1147724Y243122I-959J-1250D01*
G01X1147636D01*
G03X1146315Y242334I44J-1575D01*
G02X1144354Y241171I-2015J1162D01*
G01X1143390D01*
X1141570Y239351D01*
Y238784D01*
X1141216Y238430D01*
X1140649D01*
X1137542Y235323D01*
X1136419D01*
G03X1135055Y234534I1J-1576D01*
G02X1133127Y233372I-2015J1162D01*
G01X1133040D01*
X1133039Y233371D01*
X1132969D01*
G03X1131675Y232584I71J-1574D01*
G02X1129730Y231421I-2015J1162D01*
G01X1129589D01*
G03X1128295Y229059I71J-1574D01*
G02X1128320Y226776I-2015J-1164D01*
G01X1128295Y226734D01*
X1128276Y226700D01*
G03X1128295Y225159I1384J-754D01*
G02X1128320Y222876I-2015J-1164D01*
G01X1128295Y222834D01*
X1128276Y222800D01*
G03X1128295Y221259I1384J-754D01*
G02X1128320Y218976I-2015J-1164D01*
G01X1128295Y218934D01*
X1128276Y218900D01*
G03X1128295Y217359I1384J-754D01*
G02X1128320Y215076I-2015J-1164D01*
G01X1128295Y215034D01*
X1128276Y215000D01*
G03X1128295Y213459I1384J-754D01*
G02X1128318Y211175I-2015J-1162D01*
G01X1128029Y210675D01*
X1127966Y210612D01*
X1127963D01*
X1126533Y209182D01*
X1123746D01*
X1123546Y208982D01*
X1123459D01*
G01X566022Y220181D02*
X565942Y220214D01*
X565836Y220474D01*
X562969Y221667D01*
X561769Y221677D01*
G02X560431Y222846I847J2319D01*
G03X559595Y223622I-1520J-799D01*
G01X558826D01*
G02X556896Y224784I85J2325D01*
G03X555759Y225555I-1365J-789D01*
G01X555531Y225327D01*
Y223996D01*
G01X1147680Y237647D02*
X1145891D01*
G03X1145342Y237517I0J-1226D01*
G02X1144354Y237271I-1042J2079D01*
G01X1143406D01*
X1137561Y231426D01*
X1136426D01*
G03X1135055Y230634I0J-1582D01*
G02X1133091Y229471I-2015J1163D01*
G01X1132981D01*
G03X1131656Y227143I59J-1575D01*
G01X1131675Y227109D01*
X1131700Y227067D01*
G02X1131675Y224784I-2040J-1119D01*
G03X1131656Y223243I1365J-787D01*
G01X1131675Y223209D01*
X1131700Y223167D01*
G02X1131675Y220884I-2040J-1119D01*
G03X1131656Y219343I1365J-787D01*
G01X1131675Y219309D01*
X1131700Y219267D01*
G02X1131675Y216984I-2040J-1119D01*
G03X1131656Y215443I1365J-787D01*
G01X1131675Y215409D01*
X1131700Y215367D01*
G02X1131675Y213084I-2040J-1119D01*
G03X1131656Y211543I1365J-787D01*
G01X1132051Y210859D01*
X1132056Y210854D01*
Y209126D01*
X1130948Y208018D01*
X1128180D01*
X1125838Y205676D01*
X1123993D01*
X1123793Y205476D01*
X1123706D01*
G01X566373Y214924D02*
X566224Y215199D01*
X561356Y217178D01*
X560420Y218947D01*
G03X559572Y219722I-1509J-800D01*
G01X558867D01*
G03X557546Y218934I44J-1575D01*
G02X553515I-2015J1161D01*
G02X553237Y219706I2015J1162D01*
G01X552151Y222047D01*
G01X1151060Y239596D02*
Y238265D01*
X1150804Y238008D01*
Y238009D01*
G03X1150638Y237983I141J-1446D01*
G03X1149045Y236860I421J-2288D01*
G02X1147721Y236071I-1366J787D01*
G01X1147627D01*
X1147629Y236072D01*
G03X1145665Y234909I51J-2326D01*
G02X1144371Y234122I-1365J787D01*
G01X1143043D01*
X1137197Y228276D01*
X1136420D01*
G03X1134405Y224784I2J-2328D01*
G02X1134424Y223243I-1365J-787D01*
G01X1134405Y223209D01*
X1134380Y223167D01*
G03X1134405Y220884I2040J-1119D01*
G02X1134424Y219343I-1365J-787D01*
G01X1134405Y219309D01*
X1134380Y219267D01*
G03X1134405Y216984I2040J-1119D01*
G02X1134424Y215443I-1365J-787D01*
G01X1134405Y215409D01*
X1134380Y215367D01*
G03X1134405Y213084I2040J-1119D01*
G02X1134424Y211543I-1365J-787D01*
G01X1133958Y210736D01*
Y207564D01*
X1133553Y207159D01*
X1133037D01*
X1132542Y206664D01*
Y206148D01*
X1131266Y204872D01*
X1127438D01*
X1125066Y202500D01*
X1123750D01*
X1123463Y202700D01*
G01X568362Y207841D02*
X567943D01*
X560300Y212587D01*
X555481Y213962D01*
X554347Y215096D01*
X554167Y215409D01*
G03X552221Y216572I-2015J-1162D01*
G01X552092D01*
G02X550767Y218900I59J1575D01*
G01X550786Y218934D01*
X550811Y218976D01*
G03X550678Y221430I-2040J1120D01*
G01X549446Y223191D01*
G03X548771Y223996I-4925J-3444D01*
G01X1144300Y231797D02*
X1140955Y228452D01*
Y227504D01*
X1138030Y224579D01*
Y209620D01*
X1135976Y207566D01*
Y206212D01*
X1135776Y206012D01*
Y205925D01*
G01X558687Y204800D02*
X558600D01*
X558400Y204600D01*
X556700D01*
X555100Y206200D01*
X553277Y210601D01*
X551286Y212592D01*
X550786Y213459D01*
G03X548855Y214621I-2015J-1163D01*
G01X548727D01*
G02X547307Y216778I45J1576D01*
G01X547437Y217105D01*
G02X548770Y216850I642J-255D01*
G01X548771Y216196D01*
G01X1151060Y231797D02*
X1151600D01*
G03X1152458Y232655I0J858D01*
G01Y232809D01*
G03X1152133Y233318I-561J0D01*
G03X1151896Y233371I-238J-509D01*
G01X1150989D01*
G03X1149695Y232584I71J-1574D01*
G02X1147750Y231421I-2015J1162D01*
G01X1147609D01*
G03X1146315Y229059I71J-1574D01*
G02X1144370Y225571I-2015J-1163D01*
G01X1143041D01*
X1142152Y224682D01*
Y224174D01*
X1141657Y223679D01*
X1141149D01*
X1140668Y223198D01*
Y208441D01*
X1139789Y207562D01*
Y206921D01*
X1140143Y206567D01*
Y205867D01*
X1139789Y205513D01*
Y203423D01*
X1139989Y203223D01*
G01X558277Y200279D02*
X558327Y200329D01*
Y200400D01*
X557877Y200850D01*
X555889D01*
X551864Y204875D01*
X551186Y206513D01*
X547019Y210680D01*
X546756Y211134D01*
G03X545432Y211922I-1365J-788D01*
G01X545333D01*
X545332Y211921D01*
G02X543517Y212867I58J2326D01*
G01X543200D01*
X542011Y212296D01*
G01Y266896D02*
X540857Y266231D01*
X540547Y266315D01*
G02X540546Y267476I1464J582D01*
G02X541952Y268471I1465J-579D01*
G01X542081D01*
G03X544026Y269634I-70J2325D01*
G02X545347Y270422I1365J-787D01*
G01X545476D01*
G03X547406Y271584I-85J2325D01*
G02X548712Y272371I1365J-788D01*
G01X548841D01*
G03X550786Y273534I-70J2325D01*
G02X552080Y274321I1365J-787D01*
G01X552222D01*
G02X553516Y273534I-71J-1574D01*
G03X555461Y272371I2015J1162D01*
G01X555590D01*
G02X556896Y271584I-59J-1575D01*
G03X558827Y270422I2015J1163D01*
G01X559882D01*
X560186Y270726D01*
X560686D01*
X561182Y271222D01*
Y271722D01*
X561678Y272218D01*
X562178D01*
X562674Y272714D01*
Y273214D01*
X562953Y273493D01*
X565198D01*
X567304Y275599D01*
X567649Y275660D01*
G01X542011Y243496D02*
G03X544394Y243649I999J3074D01*
G02X545321Y243872I996J-2102D01*
G01X545461D01*
G02X547406Y242709I-70J-2325D01*
G03X548727Y241921I1365J787D01*
G01X548856D01*
G02X550786Y240759I-85J-2325D01*
G03X552092Y239972I1365J788D01*
G01X553555D01*
X555453Y238074D01*
X560359D01*
X562125Y239840D01*
X566500D01*
X567203Y239137D01*
X571668D01*
X575906Y243375D01*
X580091D01*
X580291Y243575D01*
X580378D01*
G01X1215195Y296500D02*
Y296413D01*
X1214995Y296213D01*
Y291811D01*
X1211562Y283593D01*
X1210091Y282122D01*
X1208187D01*
G02X1207488Y282290I0J1538D01*
G03X1206631Y282496I-857J-1680D01*
G01X1205139D01*
G01X545391Y245447D02*
X546545Y246112D01*
X546897Y246017D01*
G03X548701Y245071I1873J1379D01*
G01X548830D01*
G02X550136Y244284I-59J-1575D01*
G03X552066Y243122I2015J1163D01*
G01X552208D01*
G02X553516Y242334I-57J-1575D01*
G01X554038Y241429D01*
X554822Y240645D01*
X558299Y239205D01*
X559958D01*
X561793Y241040D01*
X571399D01*
X572879Y242525D01*
X573115D01*
X575650Y245060D01*
X582854D01*
X584939Y247145D01*
X585223D01*
X585282Y247204D01*
Y247205D01*
G01X1215782Y289040D02*
X1215841Y288697D01*
X1213607Y283935D01*
X1209978Y279033D01*
X1208988Y278604D01*
X1208192Y278625D01*
X1207673Y279067D01*
X1207311Y279748D01*
G03X1205939Y280921I-2172J-1152D01*
G01X1205054D01*
G03X1203265Y279976I84J-2325D01*
G01X1202913Y279881D01*
X1201759Y280547D01*
G01X545391Y253247D02*
Y251916D01*
X545648Y251659D01*
G02X547406Y250509I-257J-2312D01*
G03X548727Y249721I1365J787D01*
G01X548856D01*
G02X550786Y248559I-85J-2325D01*
G03X552092Y247772I1365J788D01*
G01X552221D01*
G02X554166Y246609I-70J-2325D01*
G03X555487Y245821I1365J787D01*
G01X562921D01*
X566475Y249375D01*
X569373D01*
X569573Y249575D01*
X569660D01*
G01X1217356Y282003D02*
X1217295Y281942D01*
X1217011D01*
X1210659Y275590D01*
X1207011D01*
X1206761Y275767D01*
G03X1205139Y276271I-1622J-2358D01*
G01X1205095D01*
G03X1203774Y275483I44J-1575D01*
G02X1201844Y274321I-2015J1163D01*
G01X1199284D01*
G02X1198379Y274696I0J1280D01*
G01X542011Y251296D02*
X540857Y251962D01*
X540774Y252272D01*
G02X541952Y252871I1238J-976D01*
G01X542065D01*
G03X544026Y254034I-54J2325D01*
G02X545390Y254822I1364J-786D01*
G01X545392D01*
G02X546756Y254034I0J-1574D01*
G03X548717Y252871I2015J1162D01*
G01X548830D01*
G02X550136Y252084I-59J-1575D01*
G03X552066Y250922I2015J1163D01*
G01X552195D01*
G02X553516Y250134I-44J-1575D01*
G03X555461Y248971I2015J1162D01*
G01X555600D01*
G02X556896Y248184I-69J-1575D01*
G01X557071Y247881D01*
X557995Y246957D01*
X561820D01*
X567168Y252305D01*
X568428D01*
X568812Y251921D01*
X569512D01*
X569896Y252305D01*
X570596D01*
X570980Y251921D01*
X571680D01*
X572064Y252305D01*
X572914D01*
X573114Y252105D01*
X573201D01*
G01X1217074Y278758D02*
Y278474D01*
X1216345Y277745D01*
Y276546D01*
X1215259Y275460D01*
X1214707D01*
X1214140Y274893D01*
Y274341D01*
X1212714Y272915D01*
X1211682Y272421D01*
X1211400Y272521D01*
X1211206Y272590D01*
X1210573Y272287D01*
X1210405Y271810D01*
X1209072Y271172D01*
X1208450D01*
G02X1207154Y271959I69J1575D01*
G03X1205224Y273121I-2015J-1163D01*
G01X1205054D01*
G03X1203124Y271959I85J-2325D01*
G02X1201987Y271188I-1365J789D01*
G01X1201759Y271416D01*
Y272747D01*
G01X542011Y255196D02*
G02X542430Y256720I2980J0D01*
G01X542500Y256838D01*
X543376Y258309D01*
G02X545322Y259472I2015J-1162D01*
G02X545460I69J-2325D01*
G02X547406Y258309I-69J-2325D01*
G03X548727Y257521I1365J787D01*
G01X548856D01*
G02X550786Y256359I-85J-2325D01*
G03X552092Y255572I1365J788D01*
G01X552221D01*
G02X554166Y254409I-70J-2325D01*
G03X555487Y253621I1365J787D01*
G01X555575D01*
G03X556896Y254409I-44J1575D01*
G02X558857Y255572I2015J-1162D01*
G01X559572D01*
G03X560285Y256210I-597J1385D01*
G01X560286Y256213D01*
X560288Y256216D01*
X560989Y257421D01*
X561665Y258096D01*
X571205D01*
X572812Y256489D01*
X573734D01*
X573934Y256689D01*
X574021D01*
G01X1222761Y278077D02*
X1222700Y278016D01*
X1222418D01*
X1213801Y269400D01*
X1210923Y266522D01*
X1208434D01*
G02X1206192Y268832I85J2325D01*
G03X1205548Y270387I-2199J0D01*
G01X1205139Y270796D01*
G01X548771Y259096D02*
X547617Y259762D01*
X547534Y260072D01*
G02X548712Y260671I1238J-976D01*
G01X548830D01*
G02X550136Y259884I-59J-1575D01*
G03X552066Y258722I2015J1163D01*
G01X552195D01*
G02X553516Y257934I-44J-1575D01*
G03X555461Y256771I2015J1162D01*
G01X555601D01*
G03X557546Y257934I-70J2325D01*
G02X557797Y258261I1365J-788D01*
G01X559168Y259632D01*
X560809Y260100D01*
X568361D01*
X568714Y260453D01*
X569080D01*
X569634Y261007D01*
Y261373D01*
X569987Y261726D01*
X570354D01*
X570907Y262279D01*
Y262646D01*
X573061Y264800D01*
X574202D01*
X574402Y264600D01*
X574489D01*
G01X1220741Y273149D02*
X1220680Y273088D01*
Y272804D01*
X1219860Y271984D01*
Y271541D01*
X1219681Y271362D01*
X1219680D01*
X1219501Y271183D01*
Y270483D01*
X1219680Y270304D01*
X1219681D01*
X1219860Y270125D01*
Y269571D01*
X1219434Y269145D01*
X1218931D01*
X1218435Y268649D01*
Y268399D01*
X1218437Y268148D01*
X1217537Y267248D01*
X1217041D01*
X1216234Y268055D01*
G01X542011Y262996D02*
Y261665D01*
X542239Y261437D01*
G03X543376Y262209I-228J1559D01*
G02X545321Y263372I2015J-1162D01*
G01X545450D01*
G03X546756Y264159I-59J1575D01*
G02X548686Y265321I2015J-1163D01*
G01X548856D01*
G02X550786Y264159I-85J-2325D01*
G03X552092Y263372I1365J788D01*
G01X552210D01*
G03X553516Y264159I-59J1575D01*
G02X555446Y265321I2015J-1163D01*
G01X555616D01*
G02X557546Y264159I-85J-2325D01*
G01X557693Y263907D01*
X558400Y263200D01*
X567140D01*
X572169Y268229D01*
X573330D01*
X573530Y268429D01*
X573617D01*
G01X1223556Y268735D02*
X1223495Y268674D01*
X1223211D01*
X1216987Y262450D01*
X1207698D01*
X1206695Y263452D01*
X1206504Y263784D01*
G03X1205208Y264571I-1365J-788D01*
G01X1202667D01*
G02X1201759Y264947I0J1284D01*
G01X542011Y278596D02*
X540857Y279262D01*
X540774Y279572D01*
G02X541952Y280171I1238J-976D01*
G01X542081D01*
G03X544026Y281334I-70J2325D01*
G02X545347Y282122I1365J-787D01*
G01X545476D01*
G03X547406Y283284I-85J2325D01*
G02X548712Y284071I1365J-788D01*
G01X548841D01*
G03X550786Y285234I-70J2325D01*
G02X552107Y286022I1365J-787D01*
G01X554234D01*
X555270Y287058D01*
X555778D01*
X556273Y287553D01*
Y288061D01*
X560297Y292085D01*
X562955D01*
X563155Y291885D01*
X563242D01*
G01X1215460Y249794D02*
X1215173Y249593D01*
X1213592Y249582D01*
X1209934Y247700D01*
X1207805D01*
X1205784Y249721D01*
X1205095D01*
G02X1203675Y251878I45J1576D01*
G01X1203804Y252204D01*
G02X1205139Y251949I643J-255D01*
G01Y251296D01*
G01X545391Y241547D02*
X544237Y242212D01*
X544154Y242522D01*
G02X545347Y243122I1238J-975D01*
G01X545435D01*
G02X546756Y242334I-44J-1575D01*
G03X548717Y241171I2015J1162D01*
G01X548830D01*
G02X550136Y240384I-59J-1575D01*
G03X552066Y239222I2015J1163D01*
G01X553244D01*
X555142Y237324D01*
X560670D01*
X562436Y239090D01*
X566189D01*
X566892Y238387D01*
X571979D01*
X576217Y242625D01*
X576857D01*
X577045Y242437D01*
Y242436D01*
X577233Y242248D01*
X577933D01*
X578121Y242436D01*
Y242437D01*
X578309Y242625D01*
X580091D01*
X580291Y242425D01*
X580378D01*
G01X1214045Y296500D02*
Y296413D01*
X1214245Y296213D01*
Y294129D01*
X1213855Y293739D01*
Y293039D01*
X1214245Y292649D01*
Y291962D01*
X1214027Y291441D01*
X1213530Y291237D01*
X1213259Y290590D01*
X1213464Y290094D01*
X1213193Y289447D01*
X1212696Y289243D01*
X1212425Y288596D01*
X1212630Y288100D01*
X1212359Y287453D01*
X1211862Y287249D01*
X1211591Y286602D01*
X1211796Y286106D01*
X1210927Y284019D01*
X1209780Y282872D01*
X1208187D01*
G02X1207829Y282958I0J788D01*
G02X1208187Y284447I358J701D01*
G01X1208819D01*
G01X548771Y247396D02*
X547617Y246731D01*
X547534Y246421D01*
G03X548727Y245821I1238J975D01*
G01X548856D01*
G02X550786Y244659I-85J-2325D01*
G03X552092Y243872I1365J788D01*
G01X552221D01*
G02X554166Y242709I-70J-2325D01*
G01X554639Y241890D01*
X555247Y241281D01*
X558449Y239955D01*
X559647D01*
X561482Y241790D01*
X571087D01*
X572465Y243173D01*
Y243438D01*
X572961Y243934D01*
X573463D01*
X573959Y244430D01*
Y244932D01*
X574455Y245428D01*
X574957D01*
X575339Y245810D01*
X576011D01*
X576399Y246198D01*
X577099D01*
X577487Y245810D01*
X578187D01*
X578575Y246198D01*
X579275D01*
X579663Y245810D01*
X580363D01*
X580751Y246198D01*
X581451D01*
X581839Y245810D01*
X582543D01*
X584409Y247676D01*
X584408Y247958D01*
X584469Y248019D01*
G01X1216823Y288551D02*
X1216519Y288376D01*
X1214255Y283548D01*
X1210462Y278424D01*
X1209134Y277849D01*
X1207907Y277882D01*
X1207077Y278588D01*
X1206648Y279396D01*
Y279397D01*
G03X1205801Y280171I-1509J-801D01*
G01X1205080D01*
G03X1203902Y279572I60J-1575D01*
G01X1203985Y279262D01*
X1205139Y278596D01*
G01X545391Y249347D02*
Y250678D01*
X545619Y250906D01*
G02X546756Y250134I-228J-1559D01*
G03X548701Y248971I2015J1162D01*
G01X548830D01*
G02X550136Y248184I-59J-1575D01*
G03X552066Y247022I2015J1163D01*
G01X552195D01*
G02X553516Y246234I-44J-1575D01*
G03X555461Y245071I2015J1162D01*
G01X563232D01*
X566786Y248625D01*
X569373D01*
X569573Y248425D01*
X569660D01*
G01X1216541Y282817D02*
X1216480Y282756D01*
Y282472D01*
X1215306Y281298D01*
X1214794D01*
X1214299Y280803D01*
Y280291D01*
X1210348Y276340D01*
X1207251D01*
X1207189Y276383D01*
X1207186Y276385D01*
G03X1205139Y277021I-2047J-2976D01*
G01X1205054D01*
G03X1203124Y275859I85J-2325D01*
G02X1201830Y275072I-1365J787D01*
G01X1201080D01*
G02X1200394Y275758I0J686D01*
G02X1201282Y276646I888J0D01*
G01X1201759D01*
G01X545391Y257147D02*
X544237Y256481D01*
X543927Y256565D01*
G02X544026Y257934I1464J582D01*
G02X545344Y258722I1365J-787D01*
G02X545438I47J-1575D01*
G02X546756Y257934I-47J-1575D01*
G03X548701Y256771I2015J1162D01*
G01X548830D01*
G02X550136Y255984I-59J-1575D01*
G03X552066Y254822I2015J1163D01*
G01X552195D01*
G02X553516Y254034I-44J-1575D01*
G03X555461Y252871I2015J1162D01*
G01X555601D01*
G03X557546Y254034I-70J2325D01*
G02X558867Y254822I1365J-787D01*
G01X559711D01*
G03X560937Y255838I-736J2136D01*
G01X561589Y256959D01*
X561976Y257346D01*
X562610D01*
X562966Y256990D01*
X563666D01*
X564022Y257346D01*
X564722D01*
X565078Y256990D01*
X565778D01*
X566134Y257346D01*
X566834D01*
X567190Y256990D01*
X567890D01*
X568246Y257346D01*
X568946D01*
X569302Y256990D01*
X570002D01*
X570358Y257346D01*
X570894D01*
X572501Y255739D01*
X573734D01*
X573934Y255539D01*
X574021D01*
G01X1221947Y278891D02*
X1221886Y278830D01*
Y278546D01*
X1221286Y277946D01*
X1220782D01*
X1220287Y277451D01*
Y276947D01*
X1219792Y276452D01*
X1219288D01*
X1218793Y275957D01*
Y275453D01*
X1215704Y272364D01*
X1215138D01*
X1214784Y272011D01*
Y271444D01*
X1214431Y271091D01*
X1213865D01*
X1213511Y270738D01*
Y270171D01*
X1213158Y269818D01*
X1212592D01*
X1212238Y269465D01*
Y268898D01*
X1211885Y268545D01*
X1211319D01*
X1210965Y268192D01*
Y267625D01*
X1210612Y267272D01*
X1208460D01*
G02X1206944Y268837I60J1575D01*
G02X1207055Y269428I1576J10D01*
G01X1207365Y269512D01*
X1208519Y268847D01*
G01X545391Y261047D02*
G03X548103Y261325I626J7259D01*
G02X548686Y261421I666J-2229D01*
G01X548856D01*
G02X550786Y260259I-85J-2325D01*
G03X552092Y259472I1365J788D01*
G01X552221D01*
G02X554166Y258309I-70J-2325D01*
G03X555487Y257521I1365J787D01*
G01X555575D01*
G03X556896Y258309I-44J1575D01*
G02X557266Y258792I2016J-1161D01*
G01X558774Y260300D01*
X558775D01*
X560704Y260850D01*
X568050D01*
X572750Y265550D01*
X574202D01*
X574402Y265750D01*
X574489D01*
G01X1221555Y272336D02*
X1221273D01*
X1220610Y271673D01*
Y269260D01*
X1217848Y266498D01*
X1217177D01*
X1216234Y265555D01*
G01X542011Y259096D02*
Y260427D01*
X542268Y260684D01*
G03X544026Y261834I-257J2312D01*
G02X545347Y262622I1365J-787D01*
G01X545476D01*
G03X547406Y263784I-85J2325D01*
G02X548712Y264571I1365J-788D01*
G01X548830D01*
G02X550136Y263784I-59J-1575D01*
G03X552066Y262622I2015J1163D01*
G01X552236D01*
G03X554166Y263784I-85J2325D01*
G02X555472Y264571I1365J-788D01*
G01X555600D01*
G02X556896Y263784I-69J-1575D01*
G01X556897Y263783D01*
Y263782D01*
X556898Y263781D01*
X557094Y263445D01*
X558089Y262450D01*
X567451D01*
X572480Y267479D01*
X573330D01*
X573530Y267279D01*
X573617D01*
G01X1222741Y269549D02*
X1222680Y269488D01*
Y269204D01*
X1216676Y263200D01*
X1212711D01*
X1212530Y263381D01*
Y263382D01*
X1212349Y263563D01*
X1211649D01*
X1211468Y263382D01*
Y263381D01*
X1211287Y263200D01*
X1210587D01*
X1210406Y263381D01*
Y263382D01*
X1210225Y263563D01*
X1209525D01*
X1209344Y263382D01*
Y263381D01*
X1209163Y263200D01*
X1208009D01*
X1207296Y263913D01*
X1207154Y264159D01*
G03X1205224Y265321I-2015J-1163D01*
G01X1204287D01*
G02X1203808Y265800I0J479D01*
G02X1204904Y266896I1096J0D01*
G01X1205139D01*
G01X542011Y282496D02*
X542391Y282876D01*
G03X543065Y284503I-1627J1627D01*
G02X545321Y286772I2326J-56D01*
G01X545450D01*
G03X546756Y287559I-59J1575D01*
G02X548686Y288721I2015J-1163D01*
G01X548815D01*
G03X550136Y289509I-44J1575D01*
G02X552053Y290671I2015J-1162D01*
G01X554654D01*
X559020Y295037D01*
X561625D01*
X566027Y299439D01*
X571522D01*
X571722Y299639D01*
X571809D01*
G01X542011Y286396D02*
Y287727D01*
X542268Y287984D01*
G03X544026Y289134I-257J2312D01*
G02X545320Y289921I1365J-787D01*
G01X545489D01*
G03X547406Y291083I-98J2324D01*
G02X548727Y291871I1365J-787D01*
G01X548856D01*
G03X550786Y293033I-85J2325D01*
G02X552132Y293821I1365J-788D01*
G01X552948D01*
G03X554323Y294995I-797J2326D01*
G02X555174Y295771I1508J-799D01*
G01X556916D01*
X558510Y297365D01*
X559988D01*
X560188Y297165D01*
X560275D01*
G01X1220374Y239178D02*
X1220286D01*
X1220330Y239134D01*
X1220174Y238978D01*
X1216323D01*
X1213379Y241922D01*
X1211320D01*
X1210535Y242707D01*
X1210534Y242709D01*
G03X1208498Y243874I-2016J-1161D01*
G01X1206052D01*
G03X1205139Y243496I0J-1291D01*
G01X545391Y284447D02*
X544237Y283781D01*
X543927Y283865D01*
G02X543816Y284485I1464J582D01*
G02X545347Y286022I1575J-38D01*
G01X545476D01*
G03X547406Y287184I-85J2325D01*
G02X548712Y287971I1365J-788D01*
G01X548841D01*
G03X550786Y289134I-70J2325D01*
G02X552080Y289921I1365J-787D01*
G01X554965D01*
X559331Y294287D01*
X561936D01*
X562772Y295123D01*
X563284D01*
X563779Y295618D01*
Y296130D01*
X564274Y296625D01*
X564786D01*
X565281Y297120D01*
Y297632D01*
X566338Y298689D01*
X567076D01*
X567450Y298315D01*
X568150D01*
X568524Y298689D01*
X569224D01*
X569598Y298315D01*
X570298D01*
X570672Y298689D01*
X571522D01*
X571722Y298489D01*
X571809D01*
G01X542011Y290296D02*
Y288965D01*
X542239Y288737D01*
G03X543376Y289509I-228J1559D01*
G02X545293Y290671I2015J-1162D01*
G01X545462D01*
G03X546756Y291458I-71J1574D01*
G02X548701Y292621I2015J-1162D01*
G01X548830D01*
G03X550136Y293408I-59J1575D01*
G02X552100Y294571I2015J-1163D01*
G01X552805D01*
G03X553659Y295348I-654J1576D01*
G02X555031Y296521I2172J-1152D01*
G01X556605D01*
X558199Y298115D01*
X559988D01*
X560188Y298315D01*
X560275D01*
G01X1220374Y238028D02*
X1220287D01*
X1220087Y238228D01*
X1216012D01*
X1213068Y241172D01*
X1211009D01*
X1210004Y242177D01*
Y242176D01*
X1209932Y242248D01*
X1209933D01*
X1209884Y242334D01*
G03X1208502Y243123I-1365J-786D01*
G01X1208498Y243124D01*
X1208087D01*
G03Y241547I0J-788D01*
G01X1208519D01*
G01X1134160Y272747D02*
Y274078D01*
X1133932Y274306D01*
G03X1132795Y273534I228J-1559D01*
G01X1128276Y265700D01*
G03X1128295Y264159I1384J-754D01*
G02X1128320Y261876I-2015J-1164D01*
G01X1128295Y261834D01*
X1128276Y261800D01*
G03X1128295Y260259I1384J-754D01*
G02X1126350Y256771I-2015J-1163D01*
G01X1126221D01*
G03X1124915Y255984I59J-1575D01*
G02X1122985Y254822I-2015J1163D01*
G01X1122900D01*
G03X1121549Y254057I0J-1575D01*
G01X1121536Y254034D01*
G02X1119591Y252871I-2015J1162D01*
G01X1119462D01*
G03X1118156Y252084I59J-1575D01*
G02X1116226Y250922I-2015J1163D01*
G01X1116097D01*
G03X1114776Y250134I44J-1575D01*
G02X1112831Y248971I-2015J1162D01*
G01X1112702D01*
G03X1111396Y248184I59J-1575D01*
G02X1109466Y247022I-2015J1163D01*
G01X1109337D01*
G03X1108016Y246234I44J-1575D01*
G02X1106071Y245071I-2015J1162D01*
G01X1105942D01*
G03X1104636Y244284I59J-1575D01*
G02X1102706Y243122I-2015J1163D01*
G01X1102577D01*
G03X1101256Y242334I44J-1575D01*
G02X1099311Y241171I-2015J1162D01*
G01X1099182D01*
G03X1097876Y240384I59J-1575D01*
G02X1095946Y239222I-2015J1163D01*
G01X1095817D01*
G03X1094496Y238434I44J-1575D01*
G02X1092551Y237271I-2015J1162D01*
G01X1092422D01*
G03X1091116Y236484I59J-1575D01*
G02X1089152Y235321I-2015J1163D01*
G01X1089057D01*
G03X1087736Y234533I44J-1575D01*
G02X1085806Y233371I-2015J1163D01*
G01X1085650D01*
G03X1084356Y232584I71J-1574D01*
G02X1082411Y231421I-2015J1162D01*
G01X1082293D01*
G03X1080977Y230634I48J-1574D01*
G02X1079013Y229471I-2015J1163D01*
G01X1078903D01*
G03X1077597Y228684I59J-1575D01*
G02X1075667Y227522I-2015J1163D01*
G01X1075538D01*
G03X1074217Y226734I44J-1575D01*
G02X1072272Y225571I-2015J1162D01*
G01X1072143D01*
G03X1070837Y224784I59J-1575D01*
G02X1068907Y223622I-2015J1163D01*
G01X1068291D01*
G03X1067362Y222842I531J-1575D01*
G02X1065891Y221671I-2120J1154D01*
G01X1063800D01*
X1061490Y218926D01*
X1060956Y218022D01*
X1061079Y217543D01*
X1060545Y216639D01*
X1060066Y216515D01*
X1059062Y214816D01*
X1058047Y214547D01*
X1057799Y214119D01*
X1056784Y213849D01*
X1056356Y214098D01*
X1055341Y213829D01*
X1055093Y213401D01*
X1054078Y213131D01*
X1053650Y213380D01*
X1050819Y212629D01*
X1049273D01*
G03X1047919Y211847I0J-1562D01*
G02X1045974Y210684I-2015J1162D01*
G01X1045845D01*
G03X1044539Y209897I59J-1575D01*
G02X1042609Y208735I-2015J1163D01*
G01X1042524D01*
G03X1041173Y207970I0J-1575D01*
G01X1041160Y207947D01*
G02X1039215Y206784I-2015J1162D01*
G01X1039086D01*
G03X1037780Y205997I59J-1575D01*
G02X1035850Y204835I-2015J1163D01*
G01X1035721D01*
G03X1034400Y204047I44J-1575D01*
G02X1032455Y202884I-2015J1162D01*
G01X1032326D01*
G03X1031020Y202097I59J-1575D01*
G02X1029090Y200935I-2015J1163D01*
G01X1028961D01*
G03X1027708Y200187I42J-1494D01*
G01X1026344Y197823D01*
X1026418Y197551D01*
X1026374Y197475D01*
G01X1134160Y276646D02*
Y275315D01*
X1133904Y275059D01*
G03X1132145Y273909I256J-2312D01*
G01X1127620Y266067D01*
G03X1127645Y263784I2040J-1119D01*
G02X1127664Y262243I-1365J-787D01*
G01X1127645Y262209D01*
X1127620Y262167D01*
G03X1127645Y259884I2040J-1119D01*
G02X1126324Y257521I-1365J-788D01*
G01X1126195D01*
G03X1124265Y256359I85J-2325D01*
G02X1122959Y255572I-1365J788D01*
G01X1122830D01*
G03X1120885Y254409I70J-2325D01*
G01X1120872Y254386D01*
G02X1119521Y253621I-1351J810D01*
G01X1119436D01*
G03X1117506Y252459I85J-2325D01*
G02X1116200Y251672I-1365J788D01*
G01X1116071D01*
G03X1114126Y250509I70J-2325D01*
G02X1112805Y249721I-1365J787D01*
G01X1112676D01*
G03X1110746Y248559I85J-2325D01*
G02X1109440Y247772I-1365J788D01*
G01X1109311D01*
G03X1107366Y246609I70J-2325D01*
G02X1106045Y245821I-1365J787D01*
G01X1105916D01*
G03X1103986Y244659I85J-2325D01*
G02X1102680Y243872I-1365J788D01*
G01X1102551D01*
G03X1100606Y242709I70J-2325D01*
G02X1099285Y241921I-1365J787D01*
G01X1099156D01*
G03X1097226Y240759I85J-2325D01*
G02X1095920Y239972I-1365J788D01*
G01X1095791D01*
G03X1093846Y238809I70J-2325D01*
G02X1092525Y238021I-1365J787D01*
G01X1092396D01*
G03X1090466Y236859I85J-2325D01*
G02X1089160Y236072I-1365J788D01*
G01X1089050D01*
G03X1087086Y234909I51J-2326D01*
G02X1085792Y234122I-1365J787D01*
G01X1085651D01*
G03X1083706Y232959I70J-2325D01*
G02X1082412Y232172I-1365J787D01*
G01X1082256D01*
G03X1080326Y231010I85J-2325D01*
G01X1080313Y230987D01*
G02X1078962Y230222I-1351J810D01*
G01X1078911D01*
G03X1076947Y229059I51J-2326D01*
G02X1075641Y228272I-1365J788D01*
G01X1075512D01*
G03X1073567Y227109I70J-2325D01*
G02X1072246Y226321I-1365J787D01*
G01X1072117D01*
G03X1070187Y225159I85J-2325D01*
G02X1068881Y224372I-1365J788D01*
G01X1068173D01*
G03X1066702Y223201I649J-2325D01*
G02X1065773Y222421I-1460J795D01*
G01X1063450D01*
X1060875Y219362D01*
X1058572Y215463D01*
X1050721Y213379D01*
X1049274D01*
G03X1047269Y212222I-2J-2313D01*
G02X1045961Y211434I-1365J787D01*
G01X1045819D01*
G03X1043889Y210272I85J-2325D01*
G02X1042583Y209485I-1365J788D01*
G01X1042454D01*
G03X1040509Y208322I70J-2325D01*
G01X1040496Y208299D01*
G02X1039145Y207534I-1351J810D01*
G01X1039060D01*
G03X1037130Y206372I85J-2325D01*
G02X1035824Y205585I-1365J788D01*
G01X1035695D01*
G03X1033750Y204422I70J-2325D01*
G02X1032429Y203634I-1365J787D01*
G01X1032300D01*
G03X1030370Y202472I85J-2325D01*
G02X1029064Y201685I-1365J788D01*
G01X1028951D01*
G03X1027058Y200562I52J-2244D01*
G01X1025694Y198198D01*
X1025422Y198126D01*
X1025378Y198050D01*
G01X1130780Y282496D02*
Y283827D01*
X1130552Y284055D01*
G03X1129396Y281743I228J-1559D01*
G01X1129415Y281709D01*
X1129440Y281667D01*
G02X1129415Y279384I-2040J-1119D01*
G03X1129396Y277843I1365J-787D01*
G01X1129415Y277809D01*
G02Y275483I-2015J-1163D01*
G01X1124915Y267684D01*
G03X1124896Y266143I1365J-787D01*
G01X1124915Y266109D01*
X1124940Y266067D01*
G02X1124915Y263784I-2040J-1119D01*
G03X1124896Y262243I1365J-787D01*
G01X1124915Y262209D01*
X1124940Y262167D01*
G02X1122985Y258722I-2040J-1120D01*
G01X1122900D01*
G03X1121549Y257957I0J-1575D01*
G01X1121536Y257934D01*
G02X1119591Y256771I-2015J1162D01*
G01X1119462D01*
G03X1118156Y255984I59J-1575D01*
G02X1116226Y254822I-2015J1163D01*
G01X1116097D01*
G03X1114776Y254034I44J-1575D01*
G02X1112831Y252871I-2015J1162D01*
G01X1112702D01*
G03X1111396Y252084I59J-1575D01*
G02X1109466Y250922I-2015J1163D01*
G01X1109337D01*
G03X1108016Y250134I44J-1575D01*
G02X1106071Y248971I-2015J1162D01*
G01X1105942D01*
G03X1104636Y248184I59J-1575D01*
G02X1102706Y247022I-2015J1163D01*
G01X1102577D01*
G03X1101256Y246234I44J-1575D01*
G02X1099311Y245071I-2015J1162D01*
G01X1099182D01*
G03X1097876Y244284I59J-1575D01*
G02X1095946Y243122I-2015J1163D01*
G01X1095817D01*
G03X1094496Y242334I44J-1575D01*
G02X1092551Y241171I-2015J1162D01*
G01X1092422D01*
G03X1091116Y240384I59J-1575D01*
G02X1089186Y239222I-2015J1163D01*
G01X1089057D01*
G03X1087736Y238434I44J-1575D01*
G02X1085791Y237271I-2015J1162D01*
G01X1085662D01*
G03X1084356Y236484I59J-1575D01*
G02X1082392Y235321I-2015J1163D01*
G01X1082341D01*
G03X1080990Y234556I0J-1575D01*
G01X1080977Y234533D01*
G02X1079047Y233371I-2015J1163D01*
G01X1078891D01*
G03X1077597Y232584I71J-1574D01*
G02X1075652Y231421I-2015J1162D01*
G01X1075511D01*
G03X1074217Y230634I71J-1574D01*
G02X1072253Y229471I-2015J1163D01*
G01X1072143D01*
G03X1070837Y228684I59J-1575D01*
G02X1068907Y227522I-2015J1163D01*
G01X1068291D01*
G03X1067362Y226742I531J-1575D01*
G02X1065891Y225571I-2120J1154D01*
G01X1064616D01*
X1057996Y222384D01*
X1056441D01*
X1055699Y221642D01*
Y221147D01*
X1054956Y220404D01*
X1054461D01*
X1053719Y219662D01*
Y219167D01*
X1052976Y218424D01*
X1052481D01*
X1050592Y216535D01*
X1049227D01*
G03X1047919Y215747I57J-1575D01*
G02X1045974Y214584I-2015J1162D01*
G01X1045845D01*
G03X1044539Y213797I59J-1575D01*
G02X1042609Y212635I-2015J1163D01*
G01X1042524D01*
G03X1041173Y211870I0J-1575D01*
G01X1041160Y211847D01*
G02X1039215Y210684I-2015J1162D01*
G01X1039086D01*
G03X1037780Y209897I59J-1575D01*
G02X1035850Y208735I-2015J1163D01*
G01X1035721D01*
G03X1034400Y207947I44J-1575D01*
G02X1032455Y206784I-2015J1162D01*
G01X1032316D01*
G03X1031020Y205997I69J-1575D01*
G01X1030687Y205420D01*
X1028464Y203750D01*
X1028426Y203472D01*
X1028357Y203420D01*
G01X1130780Y286396D02*
Y285065D01*
X1130524Y284809D01*
G03X1128740Y281376I256J-2313D01*
G01X1128765Y281334D01*
X1128784Y281300D01*
G02X1128765Y279759I-1384J-754D01*
G03Y277433I2015J-1163D01*
G02Y275859I-1365J-787D01*
G01Y275858D01*
X1124265Y268059D01*
G03X1124240Y265776I2015J-1164D01*
G01X1124265Y265734D01*
X1124284Y265700D01*
G02X1124265Y264159I-1384J-754D01*
G03X1124240Y261876I2015J-1164D01*
G01X1124265Y261834D01*
X1124284Y261800D01*
G02X1122959Y259472I-1384J-753D01*
G01X1122830D01*
G03X1120885Y258309I70J-2325D01*
G01X1120872Y258286D01*
G02X1119521Y257521I-1351J810D01*
G01X1119436D01*
G03X1117506Y256359I85J-2325D01*
G02X1116200Y255572I-1365J788D01*
G01X1116071D01*
G03X1114126Y254409I70J-2325D01*
G02X1112805Y253621I-1365J787D01*
G01X1112676D01*
G03X1110746Y252459I85J-2325D01*
G02X1109440Y251672I-1365J788D01*
G01X1109311D01*
G03X1107366Y250509I70J-2325D01*
G02X1106045Y249721I-1365J787D01*
G01X1105916D01*
G03X1103986Y248559I85J-2325D01*
G02X1102680Y247772I-1365J788D01*
G01X1102551D01*
G03X1100606Y246609I70J-2325D01*
G02X1099285Y245821I-1365J787D01*
G01X1099156D01*
G03X1097226Y244659I85J-2325D01*
G02X1095920Y243872I-1365J788D01*
G01X1095791D01*
G03X1093846Y242709I70J-2325D01*
G02X1092525Y241921I-1365J787D01*
G01X1092396D01*
G03X1090466Y240759I85J-2325D01*
G02X1089160Y239972I-1365J788D01*
G01X1089031D01*
G03X1087086Y238809I70J-2325D01*
G02X1085765Y238021I-1365J787D01*
G01X1085636D01*
G03X1083706Y236859I85J-2325D01*
G02X1082400Y236072I-1365J788D01*
G01X1082290D01*
G03X1080326Y234909I51J-2326D01*
G02X1079010Y234122I-1364J787D01*
G01X1078892D01*
G03X1076947Y232959I70J-2325D01*
G02X1075653Y232172I-1365J787D01*
G01X1075497D01*
G03X1073567Y231010I85J-2325D01*
G02X1072246Y230222I-1365J787D01*
G01X1072151D01*
G03X1070187Y229059I51J-2326D01*
G02X1068881Y228272I-1365J788D01*
G01X1068173D01*
G03X1066702Y227101I649J-2325D01*
G01X1066703D01*
G02X1065778Y226321I-1461J795D01*
G01X1064444D01*
X1057824Y223134D01*
X1056130D01*
X1050281Y217285D01*
X1049214D01*
G03X1047269Y216122I70J-2325D01*
G02X1045948Y215334I-1365J787D01*
G01X1045819D01*
G03X1043889Y214172I85J-2325D01*
G02X1042583Y213385I-1365J788D01*
G01X1042454D01*
G03X1040509Y212222I70J-2325D01*
G01X1040496Y212199D01*
G02X1039145Y211434I-1351J810D01*
G01X1039060D01*
G03X1037130Y210272I85J-2325D01*
G02X1035824Y209485I-1365J788D01*
G01X1035695D01*
G03X1033750Y208322I70J-2325D01*
G02X1032429Y207534I-1365J787D01*
G01X1032300D01*
G03X1030370Y206372I85J-2325D01*
G01X1030114Y205928D01*
X1028015Y204351D01*
X1027734Y204391D01*
X1027666Y204340D01*
G01X1119521Y266896D02*
G03X1120855Y264902I3234J720D01*
G02X1119591Y260671I-1334J-1906D01*
G01X1119462D01*
G03X1118156Y259884I59J-1575D01*
G02X1116226Y258722I-2015J1163D01*
G01X1116097D01*
G03X1114776Y257934I44J-1575D01*
G02X1112831Y256771I-2015J1162D01*
G01X1112702D01*
G03X1111396Y255984I59J-1575D01*
G02X1109466Y254822I-2015J1163D01*
G01X1109337D01*
G03X1108016Y254034I44J-1575D01*
G02X1106071Y252871I-2015J1162D01*
G01X1105942D01*
G03X1104636Y252084I59J-1575D01*
G02X1102706Y250922I-2015J1163D01*
G01X1102577D01*
G03X1101256Y250134I44J-1575D01*
G02X1099311Y248971I-2015J1162D01*
G01X1099182D01*
G03X1097876Y248184I59J-1575D01*
G02X1095946Y247022I-2015J1163D01*
G01X1095817D01*
G03X1094496Y246234I44J-1575D01*
G02X1092551Y245071I-2015J1162D01*
G01X1092422D01*
G03X1091116Y244284I59J-1575D01*
G02X1089186Y243122I-2015J1163D01*
G01X1089057D01*
G03X1087736Y242334I44J-1575D01*
G02X1085791Y241171I-2015J1162D01*
G01X1085662D01*
G03X1084356Y240384I59J-1575D01*
G02X1082426Y239222I-2015J1163D01*
G01X1082341D01*
G03X1080990Y238457I0J-1575D01*
G01X1080977Y238434D01*
G02X1079032Y237271I-2015J1162D01*
G01X1078903D01*
G03X1077597Y236484I59J-1575D01*
G02X1075633Y235321I-2015J1163D01*
G01X1075538D01*
G03X1074217Y234533I44J-1575D01*
G02X1072287Y233371I-2015J1163D01*
G01X1072131D01*
G03X1070837Y232584I71J-1574D01*
G02X1068892Y231421I-2015J1162D01*
G01X1068288D01*
G03X1067362Y230642I534J-1574D01*
G02X1066013Y229509I-2120J1155D01*
G02X1065889Y229471I-769J2288D01*
G01X1064709D01*
G03X1063782Y228692I533J-1575D01*
G01X1061373Y226283D01*
X1055783D01*
X1053835Y224335D01*
X1049073D01*
G03X1047931Y223568I210J-1546D01*
G01X1047927Y223561D01*
X1047920Y223548D01*
X1047919Y223547D01*
G02X1045958Y222384I-2015J1162D01*
G01X1045845D01*
G03X1044539Y221597I59J-1575D01*
G02X1042609Y220435I-2015J1163D01*
G01X1042524D01*
G03X1041173Y219670I0J-1575D01*
G01X1041160Y219647D01*
G02X1039215Y218484I-2015J1162D01*
G01X1039086D01*
G03X1037780Y217697I59J-1575D01*
G02X1035850Y216535I-2015J1163D01*
G01X1035721D01*
G03X1034400Y215747I44J-1575D01*
G02X1032455Y214584I-2015J1162D01*
G01X1032326D01*
G03X1031020Y213797I59J-1575D01*
G02X1029090Y212635I-2015J1163D01*
G01X1028961D01*
G03X1027640Y211847I44J-1575D01*
G02X1025695Y210684I-2015J1162D01*
G01X1025566D01*
G03X1024260Y209897I59J-1575D01*
G02X1022296Y208734I-2015J1163D01*
G01X1022201D01*
G03X1020880Y207946I44J-1575D01*
G02X1018950Y206784I-2015J1163D01*
G01X1018806D01*
G03X1017500Y205997I59J-1575D01*
G02X1015570Y204835I-2015J1163D01*
G01X1015441D01*
G03X1014120Y204047I44J-1575D01*
G01X1013675Y203278D01*
X1012412Y202016D01*
X1005070D01*
X1004870Y201816D01*
X1004783D01*
G01X1119521Y262996D02*
G02X1118843Y264117I-33J746D01*
G02X1119748Y264554I776J-451D01*
G02X1120424Y264286I-227J-1558D01*
G02X1119521Y261421I-902J-1290D01*
G01X1119436D01*
G03X1117506Y260259I85J-2325D01*
G02X1116200Y259472I-1365J788D01*
G01X1116071D01*
G03X1114126Y258309I70J-2325D01*
G02X1112805Y257521I-1365J787D01*
G01X1112676D01*
G03X1110746Y256359I85J-2325D01*
G02X1109440Y255572I-1365J788D01*
G01X1109311D01*
G03X1107366Y254409I70J-2325D01*
G02X1106045Y253621I-1365J787D01*
G01X1105916D01*
G03X1103986Y252459I85J-2325D01*
G02X1102680Y251672I-1365J788D01*
G01X1102551D01*
G03X1100606Y250509I70J-2325D01*
G02X1099285Y249721I-1365J787D01*
G01X1099156D01*
G03X1097226Y248559I85J-2325D01*
G02X1095920Y247772I-1365J788D01*
G01X1095791D01*
G03X1093846Y246609I70J-2325D01*
G02X1092525Y245821I-1365J787D01*
G01X1092396D01*
G03X1090466Y244659I85J-2325D01*
G02X1089160Y243872I-1365J788D01*
G01X1089031D01*
G03X1087086Y242709I70J-2325D01*
G02X1085765Y241921I-1365J787D01*
G01X1085636D01*
G03X1083706Y240759I85J-2325D01*
G02X1082400Y239972I-1365J788D01*
G01X1082271D01*
G03X1080326Y238809I70J-2325D01*
G01X1080313Y238786D01*
G02X1078962Y238021I-1351J810D01*
G01X1078877D01*
G03X1076947Y236859I85J-2325D01*
G02X1075641Y236072I-1365J788D01*
G01X1075531D01*
G03X1073567Y234909I51J-2326D01*
G02X1072273Y234122I-1365J787D01*
G01X1072132D01*
G03X1070187Y232959I70J-2325D01*
G02X1068893Y232172I-1365J787D01*
G01X1068171D01*
G03X1066702Y231002I651J-2325D01*
G02X1065773Y230222I-1460J795D01*
G01X1065770Y230221D01*
X1064597D01*
G03X1063182Y229153I645J-2325D01*
G01X1061062Y227033D01*
X1060012D01*
X1059662Y227383D01*
X1058612D01*
X1058262Y227033D01*
X1055472D01*
X1053524Y225085D01*
X1051827D01*
X1051477Y225435D01*
X1050427D01*
X1050077Y225085D01*
X1049027D01*
G03X1047281Y223943I255J-2296D01*
G01X1047275Y223932D01*
X1047269Y223922D01*
G02X1045948Y223134I-1365J787D01*
G01X1045819D01*
G03X1043889Y221972I85J-2325D01*
G02X1042583Y221185I-1365J788D01*
G01X1042454D01*
G03X1040509Y220022I70J-2325D01*
G01X1040496Y219999D01*
G02X1039145Y219234I-1351J810D01*
G01X1039060D01*
G03X1037130Y218072I85J-2325D01*
G02X1035824Y217285I-1365J788D01*
G01X1035695D01*
G03X1033750Y216122I70J-2325D01*
G02X1032429Y215334I-1365J787D01*
G01X1032300D01*
G03X1030370Y214172I85J-2325D01*
G02X1029064Y213385I-1365J788D01*
G01X1028935D01*
G03X1026990Y212222I70J-2325D01*
G02X1025669Y211434I-1365J787D01*
G01X1025540D01*
G03X1023610Y210272I85J-2325D01*
G02X1022304Y209485I-1365J788D01*
G01X1022194D01*
G03X1020230Y208322I51J-2326D01*
G02X1018909Y207534I-1365J787D01*
G01X1018780D01*
G03X1016850Y206372I85J-2325D01*
G02X1015544Y205585I-1365J788D01*
G01X1015431D01*
G03X1013470Y204423I53J-2325D01*
G01X1013075Y203740D01*
X1012101Y202766D01*
X1010073D01*
X1009723Y203116D01*
X1008673D01*
X1008323Y202766D01*
X1005070D01*
X1004870Y202966D01*
X1004783D01*
G01X1127400Y346847D02*
X1126247Y346182D01*
X1125937Y346266D01*
G02X1126036Y347634I1463J582D01*
G01X1126071Y347694D01*
G03X1126036Y349960I-2050J1102D01*
G02Y351534I1364J787D01*
G01X1126071Y351594D01*
G03X1126036Y353860I-2050J1102D01*
G02Y355434I1364J787D01*
G01X1126071Y355494D01*
G03X1126036Y357760I-2050J1102D01*
G02Y359334I1364J787D01*
G01X1126071Y359394D01*
G03X1126036Y361660I-2050J1102D01*
G02Y363234I1364J787D01*
G01X1126071Y363294D01*
G03X1126036Y365560I-2050J1102D01*
G02Y367134I1364J787D01*
G01X1126071Y367194D01*
G03X1126036Y369460I-2050J1102D01*
G02Y371034I1364J787D01*
G03X1126061Y373317I-2015J1164D01*
G01X1126036Y373359D01*
G02Y374933I1364J787D01*
G01X1126061Y374975D01*
G03X1126036Y377260I-2040J1120D01*
G02Y378834I1364J787D01*
G01X1126071Y378894D01*
G03X1126036Y381160I-2050J1102D01*
G02Y382734I1364J787D01*
G01X1126071Y382794D01*
G03X1124119Y386221I-2050J1102D01*
G01X1123977D01*
G02X1122656Y387009I44J1575D01*
G03X1120711Y388172I-2015J-1162D01*
G01X1120582D01*
G02X1119276Y388959I59J1575D01*
G03X1117346Y390121I-2015J-1163D01*
G01X1117217D01*
G02X1115896Y390909I44J1575D01*
G03X1113951Y392072I-2015J-1162D01*
G01X1113822D01*
G02X1112516Y392859I59J1575D01*
G03X1110552Y394022I-2015J-1163D01*
G01X1106978D01*
X1105028Y395972D01*
X1098989D01*
X1095089Y399872D01*
X1090089D01*
X1088876Y401085D01*
Y401368D01*
X1088815Y401429D01*
G01X1124021Y344896D02*
X1125174Y345561D01*
X1125268Y345913D01*
G02X1125350Y347949I2131J934D01*
G01X1125385Y348009D01*
G03Y349583I-1364J787D01*
G02X1125350Y351849I2015J1164D01*
G01X1125385Y351909D01*
G03Y353483I-1364J787D01*
G02X1125350Y355749I2015J1164D01*
G01X1125385Y355809D01*
G03Y357383I-1364J787D01*
G02X1125350Y359649I2015J1164D01*
G01X1125385Y359709D01*
G03Y361283I-1364J787D01*
G02X1125350Y363549I2015J1164D01*
G01X1125385Y363609D01*
G03Y365183I-1364J787D01*
G02X1125350Y367449I2015J1164D01*
G01X1125385Y367509D01*
G03Y369083I-1364J787D01*
G02X1125360Y371368I2015J1165D01*
G01X1125385Y371410D01*
G03Y372984I-1364J787D01*
G01X1125360Y373026D01*
G02X1125385Y375309I2040J1119D01*
G03Y376883I-1364J787D01*
G02X1125350Y379149I2015J1164D01*
G01X1125385Y379209D01*
G03Y380783I-1364J787D01*
G02X1125350Y383049I2015J1164D01*
G01X1125385Y383109D01*
G03X1124021Y385471I-1364J787D01*
G01X1123951D01*
G02X1122006Y386634I70J2325D01*
G03X1120685Y387422I-1365J-787D01*
G01X1120556D01*
G02X1118626Y388584I85J2325D01*
G03X1117320Y389371I-1365J-788D01*
G01X1117191D01*
G02X1115246Y390534I70J2325D01*
G03X1113925Y391322I-1365J-787D01*
G01X1113796D01*
G02X1111866Y392484I85J2325D01*
G03X1110560Y393271I-1365J-788D01*
G01X1110502D01*
X1110501Y393272D01*
X1106667D01*
X1104717Y395222D01*
X1098678D01*
X1094778Y399122D01*
X1089778D01*
X1088347Y400553D01*
X1088063D01*
X1088002Y400614D01*
G01X1130780Y348796D02*
X1129626Y349462D01*
X1129532Y349814D01*
G03X1129440Y351867I-2131J933D01*
G01X1129415Y351909D01*
X1129396Y351943D01*
G02X1129415Y353484I1384J754D01*
G03X1129440Y355767I-2015J1164D01*
G01X1129415Y355809D01*
X1129396Y355843D01*
G02X1129415Y357384I1384J754D01*
G03X1129440Y359667I-2015J1164D01*
G01X1129415Y359709D01*
X1129396Y359743D01*
G02X1129415Y361284I1384J754D01*
G03X1129440Y363567I-2015J1164D01*
G01X1129415Y363609D01*
X1129396Y363643D01*
G02X1129415Y365184I1384J754D01*
G03X1129440Y367467I-2015J1164D01*
G01X1129415Y367509D01*
X1129396Y367543D01*
G02X1129415Y369084I1384J754D01*
G03Y371410I-2015J1163D01*
G02Y372984I1365J787D01*
G01X1129440Y373026D01*
G03X1129415Y375309I-2040J1119D01*
G01X1129396Y375343D01*
G02X1129415Y376884I1384J754D01*
G03X1129440Y379167I-2015J1164D01*
G01X1129415Y379209D01*
X1129396Y379243D01*
G02X1129415Y380784I1384J754D01*
G03X1129440Y383067I-2015J1164D01*
G01X1129415Y383109D01*
X1129396Y383143D01*
G02X1129415Y384684I1384J754D01*
G03X1127470Y388172I-2015J1163D01*
G01X1127400D01*
G02X1126049Y388937I0J1575D01*
G01X1126036Y388960D01*
G03X1124119Y390121I-2015J-1164D01*
G01X1123977D01*
G02X1122656Y390909I44J1575D01*
G03X1120711Y392072I-2015J-1162D01*
G01X1120582D01*
G02X1119276Y392859I59J1575D01*
G03X1117346Y394021I-2015J-1163D01*
G01X1117217D01*
G02X1115896Y394809I44J1575D01*
G03X1113951Y395972I-2015J-1162D01*
G01X1113810D01*
G02X1112516Y396759I71J1574D01*
G01X1112023Y397615D01*
X1104464Y405174D01*
Y405458D01*
X1104403Y405519D01*
G01X1127400Y350747D02*
X1128554Y350081D01*
X1128864Y350165D01*
G03X1128784Y351500I-1465J582D01*
G01X1128765Y351534D01*
X1128740Y351576D01*
G02X1128765Y353859I2040J1119D01*
G03X1128784Y355400I-1365J787D01*
G01X1128765Y355434D01*
X1128740Y355476D01*
G02X1128765Y357759I2040J1119D01*
G03X1128784Y359300I-1365J787D01*
G01X1128765Y359334D01*
X1128740Y359376D01*
G02X1128765Y361659I2040J1119D01*
G03X1128784Y363200I-1365J787D01*
G01X1128765Y363234D01*
X1128740Y363276D01*
G02X1128765Y365559I2040J1119D01*
G03X1128784Y367100I-1365J787D01*
G01X1128765Y367134D01*
X1128740Y367176D01*
G02X1128765Y369459I2040J1119D01*
G03X1128784Y371000I-1365J787D01*
G01X1128765Y371034D01*
G02X1128740Y373317I2015J1164D01*
G01X1128765Y373359D01*
G03Y374933I-1365J787D01*
G02Y377259I2015J1163D01*
G03X1128784Y378800I-1365J787D01*
G01X1128765Y378834D01*
X1128740Y378876D01*
G02X1128765Y381159I2040J1119D01*
G03X1128784Y382700I-1365J787D01*
G01X1128765Y382734D01*
X1128740Y382776D01*
G02X1128765Y385059I2040J1119D01*
G03X1127444Y387422I-1365J788D01*
G01X1127302D01*
G02X1125385Y388583I98J2325D01*
G01X1125372Y388606D01*
G03X1124021Y389371I-1351J-810D01*
G01X1123951D01*
G02X1122006Y390534I70J2325D01*
G03X1120685Y391322I-1365J-787D01*
G01X1120556D01*
G02X1118626Y392484I85J2325D01*
G03X1117320Y393271I-1365J-788D01*
G01X1117191D01*
G02X1115246Y394434I70J2325D01*
G03X1113952Y395221I-1365J-787D01*
G01X1113811D01*
G02X1111866Y396384I70J2325D01*
G01X1111422Y397154D01*
X1110680Y397896D01*
X1110185D01*
X1109442Y398639D01*
Y399134D01*
X1108700Y399876D01*
X1108205D01*
X1107462Y400619D01*
Y401114D01*
X1106720Y401856D01*
X1106225D01*
X1105482Y402599D01*
Y403094D01*
X1103932Y404644D01*
X1103650D01*
X1103589Y404705D01*
G01X1134160Y311747D02*
Y313078D01*
X1134416Y313334D01*
G03X1136200Y316767I-256J2313D01*
G01X1136175Y316809D01*
X1136156Y316843D01*
G02X1136175Y318384I1384J754D01*
G03X1136200Y320667I-2015J1164D01*
G01X1136175Y320709D01*
G02Y322283I1365J787D01*
G03Y324609I-2015J1163D01*
G01X1136156Y324643D01*
G02X1136175Y326184I1384J754D01*
G03X1136200Y328467I-2015J1164D01*
G01X1136175Y328509D01*
X1136156Y328543D01*
G02X1136175Y330084I1384J754D01*
G03X1136200Y332367I-2015J1164D01*
G01X1136175Y332409D01*
X1136156Y332443D01*
G02X1136175Y333984I1384J754D01*
G03X1136200Y336267I-2015J1164D01*
G01X1136175Y336309D01*
X1136156Y336343D01*
G02X1136175Y337884I1384J754D01*
G03X1136200Y340167I-2015J1164D01*
G01X1136175Y340209D01*
X1136156Y340243D01*
G02X1136175Y341784I1384J754D01*
G03X1136200Y344067I-2015J1164D01*
G01X1136175Y344109D01*
X1136156Y344143D01*
G02X1136175Y345684I1384J754D01*
G03X1136200Y347967I-2015J1164D01*
G01X1136175Y348009D01*
X1136156Y348043D01*
G02X1136175Y349584I1384J754D01*
G03X1136200Y351867I-2015J1164D01*
G01X1136175Y351909D01*
X1136156Y351943D01*
G02X1136175Y353484I1384J754D01*
G03X1136200Y355767I-2015J1164D01*
G01X1136175Y355809D01*
X1136156Y355843D01*
G02X1136175Y357384I1384J754D01*
G03X1136200Y359667I-2015J1164D01*
G01X1136175Y359709D01*
X1136156Y359743D01*
G02X1136175Y361284I1384J754D01*
G03X1136200Y363567I-2015J1164D01*
G01X1136175Y363609D01*
X1136156Y363643D01*
G02X1136175Y365184I1384J754D01*
G03X1136200Y367467I-2015J1164D01*
G01X1136175Y367509D01*
X1136156Y367543D01*
G02X1136175Y369084I1384J754D01*
G03Y371410I-2015J1163D01*
G02Y372984I1365J787D01*
G01X1136200Y373026D01*
G03X1136175Y375309I-2040J1119D01*
G01X1136156Y375343D01*
G02X1136175Y376884I1384J754D01*
G03X1136200Y379167I-2015J1164D01*
G01X1136175Y379209D01*
X1136156Y379243D01*
G02X1136175Y380784I1384J754D01*
G03X1136200Y383067I-2015J1164D01*
G01X1136175Y383109D01*
X1136156Y383143D01*
G02X1136175Y384684I1384J754D01*
G03X1134230Y388172I-2015J1163D01*
G01X1134101D01*
G02X1132795Y388959I59J1575D01*
G03X1130865Y390121I-2015J-1163D01*
G01X1130736D01*
G02X1129415Y390909I44J1575D01*
G01X1129055Y391533D01*
X1125978Y394610D01*
Y402547D01*
X1117981Y410544D01*
Y410545D01*
X1117980D01*
Y410827D01*
X1117919Y410888D01*
G01X1134160Y315647D02*
Y314316D01*
X1134388Y314088D01*
G03X1135544Y316400I-228J1559D01*
G01X1135525Y316434D01*
X1135500Y316476D01*
G02X1135525Y318759I2040J1119D01*
G03X1135544Y320300I-1365J787D01*
G01X1135525Y320334D01*
X1135500Y320376D01*
G02X1135525Y322659I2040J1119D01*
G03Y324233I-1365J787D01*
G02Y326559I2015J1163D01*
G03X1135544Y328100I-1365J787D01*
G01X1135525Y328134D01*
X1135500Y328176D01*
G02X1135525Y330459I2040J1119D01*
G03X1135544Y332000I-1365J787D01*
G01X1135525Y332034D01*
X1135500Y332076D01*
G02X1135525Y334359I2040J1119D01*
G03X1135544Y335900I-1365J787D01*
G01X1135525Y335934D01*
X1135500Y335976D01*
G02X1135525Y338259I2040J1119D01*
G03X1135544Y339800I-1365J787D01*
G01X1135525Y339834D01*
X1135500Y339876D01*
G02X1135525Y342159I2040J1119D01*
G03X1135544Y343700I-1365J787D01*
G01X1135525Y343734D01*
X1135500Y343776D01*
G02X1135525Y346059I2040J1119D01*
G03X1135544Y347600I-1365J787D01*
G01X1135525Y347634D01*
X1135500Y347676D01*
G02X1135525Y349959I2040J1119D01*
G03X1135544Y351500I-1365J787D01*
G01X1135525Y351534D01*
X1135500Y351576D01*
G02X1135525Y353859I2040J1119D01*
G03X1135544Y355400I-1365J787D01*
G01X1135525Y355434D01*
X1135500Y355476D01*
G02X1135525Y357759I2040J1119D01*
G03X1135544Y359300I-1365J787D01*
G01X1135525Y359334D01*
X1135500Y359376D01*
G02X1135525Y361659I2040J1119D01*
G03X1135544Y363200I-1365J787D01*
G01X1135525Y363234D01*
X1135500Y363276D01*
G02X1135525Y365559I2040J1119D01*
G03X1135544Y367100I-1365J787D01*
G01X1135525Y367134D01*
X1135500Y367176D01*
G02X1135525Y369459I2040J1119D01*
G03X1135544Y371000I-1365J787D01*
G01X1135525Y371034D01*
G02X1135500Y373317I2015J1164D01*
G01X1135525Y373359D01*
G03Y374933I-1365J787D01*
G02Y377259I2015J1163D01*
G03X1135544Y378800I-1365J787D01*
G01X1135525Y378834D01*
X1135500Y378876D01*
G02X1135525Y381159I2040J1119D01*
G03X1135544Y382700I-1365J787D01*
G01X1135525Y382734D01*
X1135500Y382776D01*
G02X1135525Y385059I2040J1119D01*
G03X1134204Y387422I-1365J788D01*
G01X1134075D01*
G02X1132145Y388584I85J2325D01*
G03X1130839Y389371I-1365J-788D01*
G01X1130710D01*
G02X1128765Y390534I70J2325D01*
G01X1128455Y391071D01*
X1127089Y392438D01*
X1126594D01*
X1125851Y393180D01*
Y393676D01*
X1125228Y394299D01*
Y395549D01*
X1124878Y395899D01*
Y396949D01*
X1125228Y397299D01*
Y398349D01*
X1124878Y398699D01*
Y399749D01*
X1125228Y400099D01*
Y402236D01*
X1124486Y402978D01*
X1123991D01*
X1123248Y403721D01*
Y404216D01*
X1122506Y404958D01*
X1122011D01*
X1121268Y405701D01*
Y406196D01*
X1120526Y406938D01*
X1120031D01*
X1119288Y407681D01*
Y408176D01*
X1117451Y410013D01*
X1117167D01*
X1117105Y410075D01*
G01X1480150Y442942D02*
Y442855D01*
X1479950Y442655D01*
Y442089D01*
X1481332Y440707D01*
X1484127D01*
X1485776Y439058D01*
X1490179Y430991D01*
X1491800Y429370D01*
Y428564D01*
X1492150Y428214D01*
X1493375D01*
G01X1479000Y442942D02*
Y442855D01*
X1479200Y442655D01*
Y441778D01*
X1481021Y439957D01*
X1483816D01*
X1485169Y438604D01*
X1489572Y430537D01*
X1491050Y429059D01*
Y428564D01*
X1490700Y428214D01*
X1489475D01*
G01X1208519Y229847D02*
X1205894Y230222D01*
X1205095D01*
G02X1203774Y231010I44J1575D01*
G01X1203499Y231470D01*
Y234044D01*
G02X1203124Y234533I1668J1668D01*
G03X1201803Y235321I-1365J-787D01*
G01X1201214D01*
X1198835Y237700D01*
G01X1209439Y222400D02*
X1207778Y224172D01*
X1207154Y225159D01*
G02X1207135Y226700I1365J787D01*
G01X1207154Y226734D01*
X1207776Y227779D01*
X1208670D01*
X1210088Y229197D01*
Y230497D01*
X1209120Y231465D01*
X1207819D01*
X1205197Y234087D01*
G02X1203774Y234909I0J1642D01*
G03X1203413Y235382I-2015J-1163D01*
G01X1203358Y235437D01*
Y238683D01*
G01X1201858Y231900D02*
X1202814Y231081D01*
X1203124Y230634D01*
G03X1205088Y229471I2015J1163D01*
G01X1205198D01*
G02X1206523Y227143I-59J-1575D01*
G01X1206504Y227109D01*
X1206479Y227067D01*
G03X1206504Y224784I2040J-1119D01*
G01X1207051Y223836D01*
X1207741Y223034D01*
G01X1473962Y387900D02*
X1480252Y394190D01*
Y396231D01*
X1481487Y397466D01*
X1484978D01*
X1486875Y399363D01*
X1492075D01*
X1492329Y399109D01*
X1493405D01*
G02X1494162Y399809I1919J-1316D01*
G03X1494950Y401130I-787J1365D01*
G01Y401259D01*
G02X1495409Y402563I2325J-86D01*
G01Y403740D01*
G01X1511926Y405774D02*
X1514742D01*
X1517181Y408213D01*
X1519138D01*
X1522956Y412031D01*
X1527362D01*
X1527450Y412119D01*
X1528750D01*
X1528764Y412105D01*
X1531035D01*
X1531330Y411810D01*
G01X1556155Y458945D02*
X1556166Y458956D01*
X1556037Y459085D01*
Y459794D01*
X1556166Y460674D01*
G02X1556938Y461811I1559J-228D01*
G02X1558512I787J-1365D01*
G02X1559300Y460490I-787J-1365D01*
G01Y460361D01*
G03X1560462Y458431I2325J85D01*
G03X1562788I1163J2015D01*
G02X1564362I787J-1365D01*
G03X1566688I1163J2015D01*
G02X1568262I787J-1365D01*
G03X1570588I1163J2015D01*
G02X1571492Y458637I787J-1365D01*
G01X1571867D01*
X1572440Y459210D01*
Y459911D01*
X1574510Y461981D01*
G01X1487953Y388060D02*
G02X1488688Y389019I1522J-406D01*
G03X1489850Y390949I-1163J2015D01*
G01Y391078D01*
G02X1490638Y392399I1575J-44D01*
G03X1491800Y394329I-1163J2015D01*
G01Y394458D01*
G02X1492588Y395779I1575J-44D01*
G03X1493750Y397709I-1163J2015D01*
G01Y397838D01*
G02X1494538Y399159I1575J-44D01*
G03X1495700Y401089I-1163J2015D01*
G01Y401218D01*
G02X1496488Y402539I1575J-44D01*
G01X1501175Y380894D02*
X1502506D01*
X1502734Y380666D01*
G02X1501962Y379529I-1559J228D01*
G03X1500800Y377599I1163J-2015D01*
G01Y374794D01*
G01X1502112Y360152D02*
Y360588D01*
X1501800Y360900D01*
Y369465D01*
G01Y376184D02*
X1501550Y376434D01*
Y377558D01*
G02X1502338Y378879I1575J-44D01*
G03X1503500Y380809I-1163J2015D01*
G01Y380938D01*
G02X1504288Y382259I1575J-44D01*
G03X1505450Y384189I-1163J2015D01*
G01Y384318D01*
G02X1506238Y385639I1575J-44D01*
G03X1507400Y387569I-1163J2015D01*
G01Y387698D01*
G02X1508188Y389019I1575J-44D01*
G03X1509350Y390949I-1163J2015D01*
G01Y391078D01*
G02X1510138Y392399I1575J-44D01*
G03X1511190Y393703I-1163J2015D01*
G01X1516775Y394414D02*
X1515444D01*
X1515188Y394158D01*
G02X1514038Y392399I-2312J256D01*
G03X1513250Y391078I787J-1365D01*
G01Y390949D01*
G02X1512088Y389019I-2325J85D01*
G03X1511300Y387698I787J-1365D01*
G01Y387569D01*
G02X1510138Y385639I-2325J85D01*
G03X1509350Y384318I787J-1365D01*
G01Y384189D01*
G02X1508188Y382259I-2325J85D01*
G03X1507400Y380938I787J-1365D01*
G01Y380809D01*
G02X1506238Y378879I-2325J85D01*
G03X1505450Y377558I787J-1365D01*
G01Y375500D01*
G01X1509355Y373393D02*
X1509350Y373398D01*
Y377558D01*
G02X1510138Y378879I1575J-44D01*
G03X1511300Y380809I-1163J2015D01*
G01Y380938D01*
G02X1512088Y382259I1575J-44D01*
G03X1513250Y384189I-1163J2015D01*
G01Y384318D01*
G02X1514038Y385639I1575J-44D01*
G03X1515188Y387398I-1162J2015D01*
G01X1515444Y387654D01*
X1516775D01*
G01X1513076Y346322D02*
X1509425Y349973D01*
Y351280D01*
X1509620Y351475D01*
Y360911D01*
X1510404Y361695D01*
Y370596D01*
X1508600Y372400D01*
Y377599D01*
G02X1509762Y379529I2325J-85D01*
G03X1510550Y380850I-787J1365D01*
G01Y380979D01*
G02X1510925Y384274I14664J0D01*
G01X1512558Y402870D02*
X1514447Y404759D01*
X1519705D01*
X1521069Y406123D01*
X1523275D01*
X1523364Y406034D01*
X1525786D01*
X1525891Y406139D01*
X1529281D01*
X1530304Y407162D01*
Y408546D01*
X1532060Y410302D01*
X1536583D01*
X1538200Y408685D01*
Y407943D01*
X1538606Y407537D01*
Y407284D01*
X1539525Y406365D01*
X1539778D01*
X1539843Y406300D01*
G01X1584200Y462610D02*
X1588210D01*
X1589770Y461050D01*
Y458720D01*
X1589240Y458190D01*
X1581719D01*
X1577255Y453726D01*
Y451315D01*
X1574520Y448580D01*
X1560298D01*
X1559294Y447576D01*
Y445732D01*
X1558106Y444544D01*
Y442004D01*
X1559294Y440816D01*
Y439516D01*
X1557344Y437566D01*
Y435470D01*
G01X1541963Y402780D02*
X1537780D01*
X1536656Y403904D01*
Y405205D01*
X1535738Y406123D01*
X1530726D01*
X1527383Y402780D01*
X1515601D01*
X1514444Y401623D01*
Y400272D01*
X1513992Y399180D01*
X1513100Y398288D01*
Y396909D01*
X1514611Y395398D01*
X1514434Y394186D01*
G02X1513662Y393049I-1559J228D01*
G03X1512500Y391119I1163J-2015D01*
G01Y390990D01*
G02X1511712Y389669I-1575J44D01*
G03X1510550Y387739I1163J-2015D01*
G01Y387610D01*
G02X1509762Y386289I-1575J44D01*
G03X1508600Y384359I1163J-2015D01*
G01Y384230D01*
G02X1507812Y382909I-1575J44D01*
G03X1506650Y380979I1163J-2015D01*
G01Y380850D01*
G02X1505862Y379529I-1575J44D01*
G03X1504700Y377599I1163J-2015D01*
G01Y374200D01*
G01X1519105Y380243D02*
X1519100Y380248D01*
Y380938D01*
G02X1519888Y382259I1575J-44D01*
G03X1520319Y382580I-1165J2014D01*
G01X1520931D01*
X1522625Y384274D01*
G01X1530425Y397794D02*
X1531006Y398802D01*
Y399258D01*
G03X1529638Y399159I-582J-1464D01*
G01X1529044Y398816D01*
G02X1527400Y399000I-568J2358D01*
G01X1526986Y399204D01*
G03X1525803Y399010I-328J-1704D01*
G02X1524176Y398718I-1228J2164D01*
G01X1523412Y399159D01*
G03X1521838I-787J-1365D01*
G02X1519512I-1163J2015D01*
G03X1517938Y396429I-787J-1365D01*
G02X1519100Y394499I-1163J-2015D01*
G01Y394329D01*
G02X1517938Y392399I-2325J85D01*
G03Y389669I787J-1365D01*
G02X1519100Y387739I-1163J-2015D01*
G01Y387569D01*
G02X1517938Y385639I-2325J85D01*
G03X1517150Y384318I787J-1365D01*
G01Y384189D01*
G02X1515988Y382259I-2325J85D01*
G03X1515200Y380938I787J-1365D01*
G01Y379360D01*
X1516395Y378165D01*
G01X1532375Y401174D02*
X1531710Y400020D01*
X1531358Y399926D01*
G03X1529262Y399809I-932J-2132D01*
G01X1528775Y399529D01*
G02X1527734Y399674I-301J1645D01*
G01X1527235Y399921D01*
G03X1525431Y399664I-575J-2421D01*
G02X1524418Y399446I-855J1510D01*
G01X1523788Y399809D01*
G03X1521462I-1163J-2015D01*
G02X1519888I-787J1365D01*
G03X1517562I-1163J-2015D01*
G03X1516400Y397879I1163J-2015D01*
G01Y397709D01*
G03X1517562Y395779I2325J85D01*
G02X1518350Y394458I-787J-1365D01*
G01Y394370D01*
G02X1517562Y393049I-1575J44D01*
G03X1516400Y391119I1163J-2015D01*
G01Y390949D01*
G03X1517562Y389019I2325J85D01*
G02X1518350Y387698I-787J-1365D01*
G01Y387610D01*
G02X1517562Y386289I-1575J44D01*
G03X1516400Y384359I1163J-2015D01*
G01Y384230D01*
G02X1515612Y382909I-1575J44D01*
G03X1514450Y380979I1163J-2015D01*
G01Y379394D01*
X1513255Y378199D01*
G01X1626450Y85517D02*
X1627842Y84125D01*
Y80935D01*
X1629297Y79480D01*
G01X1520675Y484106D02*
X1521678D01*
G03X1522238Y484338I0J792D01*
G01X1522262Y484362D01*
G02X1523412Y486121I2312J-256D01*
G03Y488851I-787J1365D01*
G02X1522861Y489805I551J954D01*
G01Y491330D01*
X1522661Y491530D01*
Y491617D01*
G01X1524575Y477346D02*
G03X1522497Y478402I-2237J-1829D01*
G02X1520300Y480641I128J2323D01*
G01Y480770D01*
G03X1519512Y482091I-1575J-44D01*
G02X1518350Y484021I1163J2015D01*
G01Y484150D01*
G03X1517562Y485471I-1575J-44D01*
G02X1516400Y487401I1163J2015D01*
G02Y487432I2325J15D01*
G01Y488374D01*
G02X1516723Y489153I1101J0D01*
G01X1519393Y491823D01*
G03X1519496Y492071I-247J248D01*
G01Y499065D01*
X1519296Y499265D01*
Y499352D01*
G01X1516166Y498920D02*
Y498833D01*
X1516366Y498633D01*
Y495773D01*
G02X1516263Y495525I-350J0D01*
G01X1512986Y492248D01*
G03X1512500Y491073I1175J-1174D01*
G01Y487432D01*
G03X1513663Y485471I2325J54D01*
G01X1513662D01*
G02X1514450Y484150I-787J-1365D01*
G01Y484021D01*
G03X1515612Y482091I2325J85D01*
G02X1516400Y480770I-787J-1365D01*
G01Y480641D01*
G03X1517562Y478711I2325J85D01*
G02X1518350Y477390I-787J-1365D01*
G01Y477261D01*
G03X1521838Y475331I2325J85D01*
G02X1523412I787J-1365D01*
G03X1525738I1163J2015D01*
G02X1527312I787J-1365D01*
G03X1529638I1163J2015D01*
G02X1531212I787J-1365D01*
G03X1532558Y475027I1162J2015D01*
G02X1534325Y473966I140J-1768D01*
G01X1512875Y477346D02*
X1513918D01*
G03X1514410Y477550I0J695D01*
G01X1514434Y477574D01*
G03X1513662Y478711I-1559J-228D01*
G02X1512500Y480641I1163J2015D01*
G01Y480770D01*
G03X1511712Y482091I-1575J-44D01*
G02X1510550Y484021I1163J2015D01*
G01Y484150D01*
G03X1509762Y485471I-1575J-44D01*
G02X1508600Y487401I1163J2015D01*
G01Y489200D01*
X1508400Y489400D01*
Y489487D01*
G01X1526525Y480726D02*
G02X1529186Y481888I7003J-12409D01*
G03X1529637Y486121I-709J2216D01*
G02X1528850Y487417I788J1365D01*
G01Y497150D01*
X1529400Y497700D01*
Y499056D01*
X1529600Y499256D01*
Y499300D01*
G01X1524575Y484106D02*
X1523532D01*
G02X1523040Y484310I0J695D01*
G01X1523016Y484334D01*
G02X1523788Y485471I1559J-228D01*
G01X1523787D01*
G03Y489501I-1162J2015D01*
G02X1523611Y489806I176J305D01*
G01Y491373D01*
X1523811Y491573D01*
Y491617D01*
G01X1522625Y480726D02*
X1522735Y480768D01*
G02X1523756Y480307I280J-741D01*
G01Y480306D01*
G02X1523295Y479285I-741J-280D01*
G02X1522914Y479178I-801J2119D01*
G02X1522538Y479154I-288J1549D01*
G02X1521050Y480682I87J1573D01*
G01Y480811D01*
G03X1519888Y482741I-2325J-85D01*
G02X1519100Y484062I787J1365D01*
G01Y484191D01*
G03X1517938Y486121I-2325J-85D01*
G02X1517150Y487442I787J1365D01*
G01Y488374D01*
G02X1517253Y488622I350J0D01*
G01X1519923Y491292D01*
G03X1520246Y492071I-778J779D01*
G01Y499065D01*
X1520446Y499265D01*
Y499352D01*
G01X1517316Y498920D02*
Y498833D01*
X1517116Y498633D01*
Y495774D01*
G02X1516793Y494994I-1100J-1D01*
G01X1513517Y491717D01*
G03X1513250Y491073I643J-644D01*
G01Y487442D01*
G03X1514038Y486121I1575J44D01*
G02X1515200Y484191I-1163J-2015D01*
G01Y484062D01*
G03X1515988Y482741I1575J44D01*
G02X1517150Y480811I-1163J-2015D01*
G01Y480682D01*
G03X1517938Y479361I1575J44D01*
G02X1519100Y477431I-1163J-2015D01*
G01Y477302D01*
G03X1521462Y475981I1575J44D01*
G02X1523788I1163J-2015D01*
G03X1525362I787J1365D01*
G02X1527688I1163J-2015D01*
G03X1529262I787J1365D01*
G02X1531588I1163J-2015D01*
G03X1532499Y475776I785J1364D01*
G03X1532757Y475818I-123J1569D01*
G01X1533119Y475911D01*
G03X1533178Y475930I-96J400D01*
G03X1532583Y477407I-297J739D01*
G01X1532532Y477388D01*
X1532375Y477346D01*
G01X1509550Y489487D02*
Y489400D01*
X1509350Y489200D01*
Y487442D01*
G03X1510138Y486121I1575J44D01*
G02X1511300Y484191I-1163J-2015D01*
G01Y484062D01*
G03X1512088Y482741I1575J44D01*
G02X1513250Y480811I-1163J-2015D01*
G01Y480682D01*
G03X1514038Y479361I1575J44D01*
G02X1515188Y477602I-1162J-2015D01*
G01X1515212Y477578D01*
G03X1515772Y477346I560J560D01*
G01X1516775D01*
G01X1590224Y182908D02*
X1591642Y181490D01*
G01X1579921Y196887D02*
Y190415D01*
X1590138Y180198D01*
Y180104D01*
G01X1590224Y181176D02*
X1590890Y180510D01*
G01X1584070Y448328D02*
X1612367D01*
X1613760Y446935D01*
Y443539D01*
X1619126Y438173D01*
X1630446D01*
X1637750Y445477D01*
X1639750D01*
G01X1553825Y460446D02*
X1555156D01*
X1555412Y460702D01*
G02X1556562Y462461I2312J-256D01*
G02X1558888I1163J-2015D01*
G02X1560050Y460531I-1163J-2015D01*
G01Y460402D01*
G03X1560838Y459081I1575J44D01*
G03X1562412I787J1365D01*
G02X1564738I1163J-2015D01*
G03X1566312I787J1365D01*
G02X1568638I1163J-2015D01*
G03X1570212I787J1365D01*
G02X1571201Y459386I1163J-2015D01*
G01X1571600Y459785D01*
G01X1611636Y465800D02*
X1614901D01*
X1620551Y460150D01*
X1624700D01*
G01X1567475Y443546D02*
G03X1570588Y444911I-4636J14805D01*
G02X1572162I787J-1365D01*
G03X1573325Y444600I1162J2016D01*
G01X1578128D01*
X1579537Y443191D01*
G01X1581414Y473547D02*
X1581340Y473501D01*
X1581277Y473227D01*
X1581267Y473221D01*
X1579749Y472240D01*
X1576519Y469010D01*
X1571375D01*
G02X1570588Y469221I1J1576D01*
G03X1568262I-1163J-2015D01*
G02X1566688I-787J1365D01*
G03X1563200Y467291I-1163J-2015D01*
G01Y467162D01*
G02X1562412Y465841I-1575J44D01*
G03X1561250Y463911I1163J-2015D01*
G01Y463741D01*
G03X1562412Y461811I2325J85D01*
G03X1565525Y460446I7723J13381D01*
G01X1582024Y472572D02*
X1581950Y472526D01*
X1581675Y472590D01*
X1581674D01*
X1581667Y472583D01*
X1581662D01*
X1581657Y472580D01*
X1580223Y471653D01*
X1578811Y470241D01*
Y469745D01*
X1578068Y469002D01*
X1577573D01*
X1576831Y468260D01*
X1574174D01*
X1573824Y467910D01*
X1572774D01*
X1572424Y468260D01*
X1571374D01*
G02X1570213Y468571I1J2326D01*
G01Y468570D01*
X1570212Y468571D01*
G03X1568638I-787J-1365D01*
G02X1566312I-1163J2015D01*
G03X1563950Y467250I-787J-1365D01*
G01Y467121D01*
G02X1562788Y465191I-2325J85D01*
G03X1562000Y463870I787J-1365D01*
G01Y463782D01*
G03X1562788Y462461I1575J44D01*
G03X1564010Y462070I1513J2625D01*
G01X1564011D01*
G03X1564942Y462837I82J849D01*
G03X1564174Y463768I-849J82D01*
G01X1563575Y463826D01*
G01X1570212Y455051D02*
G03X1568638I-787J-1365D01*
G02X1566312I-1163J2015D01*
G03X1564944Y455150I-786J-1365D01*
G02X1563800Y454700I-62753J157852D01*
G02X1562412Y455051I-76J2619D01*
G01X1562207Y455169D01*
G02X1561288Y456575I929J1611D01*
G01X1561006Y457066D01*
X1559675D01*
G01X1557600Y495975D02*
X1557539Y495914D01*
X1557257D01*
X1551428Y490085D01*
G02X1550650Y489763I-778J778D01*
G01X1545975D01*
G03X1545727Y489660I0J-350D01*
G01X1544553Y488486D01*
G03X1544450Y488238I247J-248D01*
G01Y487401D01*
G02X1543288Y485471I-2325J85D01*
G03X1542500Y484150I787J-1365D01*
G01Y484021D01*
G02X1541338Y482091I-2325J85D01*
G03X1540550Y480770I787J-1365D01*
G01Y480641D01*
G02X1539388Y478711I-2325J85D01*
G01Y478712D01*
G02X1538148Y478400I-1166J2013D01*
G01X1538143D01*
G03X1536275Y477346I-65J-2068D01*
G01X1538000Y503600D02*
Y503513D01*
X1538200Y503313D01*
Y502411D01*
G02X1538025Y502061I-547J55D01*
G03X1537850Y501711I372J-405D01*
G01Y500661D01*
G03X1538025Y500311I547J55D01*
G02X1538200Y499961I-372J-405D01*
G01Y498911D01*
G02X1538025Y498561I-547J55D01*
G03X1537850Y498211I372J-405D01*
G01Y497161D01*
G03X1538025Y496811I547J55D01*
G02X1538200Y496461I-372J-405D01*
G01Y495411D01*
G02X1538097Y495163I-350J0D01*
G01X1537272Y494338D01*
G02X1536901Y494214I-348J426D01*
G03X1536529Y494090I-24J-549D01*
G01X1535787Y493348D01*
G03X1535663Y492977I426J-348D01*
G02X1535539Y492605I-549J-24D01*
G01X1534797Y491863D01*
G02X1534426Y491739I-348J426D01*
G03X1534054Y491615I-24J-549D01*
G01X1533312Y490873D01*
G03X1533188Y490502I426J-348D01*
G02X1533064Y490130I-549J-24D01*
G01X1532322Y489388D01*
G03X1532000Y488610I778J-778D01*
G01Y487442D01*
G02X1531400Y486249I-1575J45D01*
G01X1531090Y486332D01*
X1530425Y487486D01*
G01X1528475Y484106D02*
G03X1527894Y482642I-291J-732D01*
G03X1528956Y482606I581J1464D01*
G03X1529262Y485471I-481J1500D01*
G02X1528100Y487401I1163J2015D01*
G01Y488451D01*
G03X1527925Y488801I-547J-55D01*
G02X1527750Y489151I372J405D01*
G01Y490201D01*
G02X1527925Y490551I547J-55D01*
G03X1528100Y490901I-372J405D01*
G01Y491951D01*
G03X1527925Y492301I-547J-55D01*
G02X1527750Y492651I372J405D01*
G01Y493701D01*
G02X1527925Y494051I547J-55D01*
G03X1528100Y494401I-372J405D01*
G01Y497461D01*
X1528650Y498011D01*
Y499013D01*
X1528450Y499213D01*
Y499300D01*
G01X1551502Y501192D02*
Y501105D01*
X1551302Y500905D01*
Y498726D01*
G02X1550980Y497948I-1100J0D01*
G01X1549756Y496724D01*
G02X1548978Y496402I-778J778D01*
G01X1545009D01*
G03X1544763Y496299I2J-350D01*
G01X1541703Y493239D01*
G03X1541579Y492868I426J-348D01*
G02X1541455Y492496I-549J-24D01*
G01X1540713Y491754D01*
G02X1540342Y491630I-348J426D01*
G03X1539970Y491506I-24J-549D01*
G01X1536753Y488289D01*
G03X1536651Y488042I247J-247D01*
G01X1536650Y488043D01*
Y487432D01*
G02X1535488Y485471I-2325J53D01*
G03X1534700Y484150I787J-1365D01*
G01Y484021D01*
G02X1533538Y482091I-2325J85D01*
G03X1532766Y480954I787J-1365D01*
G01X1532994Y480726D01*
X1534325D01*
G01X1556786Y496789D02*
X1556725Y496728D01*
Y496444D01*
X1555847Y495566D01*
G02X1555476Y495442I-348J426D01*
G03X1555104Y495318I-24J-549D01*
G01X1554362Y494576D01*
G03X1554238Y494205I426J-348D01*
G02X1554114Y493833I-549J-24D01*
G01X1553372Y493091D01*
G02X1553001Y492967I-348J425D01*
G03X1552630Y492843I-23J-549D01*
G01X1551887Y492101D01*
G03X1551763Y491730I426J-349D01*
G02X1551640Y491358I-550J-25D01*
G01X1550897Y490616D01*
G02X1550651Y490513I-248J247D01*
G01X1549476D01*
G02X1549126Y490688I55J547D01*
G03X1548776Y490863I-405J-372D01*
G01X1547726D01*
G03X1547376Y490688I55J-547D01*
G02X1547026Y490513I-405J372D01*
G01X1545976D01*
G03X1545196Y490190I-1J-1100D01*
G01X1544023Y489017D01*
G03X1543700Y488238I777J-779D01*
G01Y487442D01*
G02X1542912Y486121I-1575J44D01*
G03X1541750Y484191I1163J-2015D01*
G01Y484062D01*
G02X1540962Y482741I-1575J44D01*
G03X1539800Y480811I1163J-2015D01*
G01Y480682D01*
G02X1539012Y479361I-1575J44D01*
G02X1538172Y479150I-789J1364D01*
G01X1538011Y479155D01*
G02X1537684Y479413I11J350D01*
G01X1537615Y479668D01*
X1538225Y480726D01*
G01X1539150Y503600D02*
Y503513D01*
X1538950Y503313D01*
Y495411D01*
G02X1538627Y494632I-1101J0D01*
G01X1538262Y494267D01*
X1538263D01*
X1532853Y488857D01*
G03X1532751Y488610I247J-247D01*
G01X1532750Y488611D01*
Y487401D01*
G02X1531805Y485612I-2325J84D01*
G01X1531710Y485260D01*
X1532375Y484106D01*
G01X1550352Y501192D02*
Y501105D01*
X1550552Y500905D01*
Y498725D01*
X1550551Y498726D01*
G02X1550449Y498479I-349J0D01*
G01X1549225Y497255D01*
G02X1548979Y497152I-248J247D01*
G01X1545007D01*
G03X1544232Y496830I3J-1100D01*
G01X1536222Y488820D01*
G03X1535900Y488042I778J-778D01*
G01Y487442D01*
G02X1535112Y486121I-1575J44D01*
G03X1533950Y484191I1163J-2015D01*
G01Y484062D01*
G02X1533162Y482741I-1575J44D01*
G03X1532012Y480982I1162J-2015D01*
G01X1531756Y480726D01*
X1530425D01*
G01X1824748Y139172D02*
X1833372D01*
X1842116Y147916D01*
Y172766D01*
X1847475Y178125D01*
Y184251D01*
X1841663Y190063D01*
Y204607D01*
X1848648Y211592D01*
Y211997D01*
X1847699Y212946D01*
G01X1850876D02*
Y212771D01*
X1849700Y211595D01*
Y211300D01*
X1842613Y204213D01*
Y190457D01*
X1848425Y184645D01*
Y177731D01*
X1842891Y172197D01*
Y147347D01*
X1833766Y138222D01*
X1824578D01*
X1822198Y140602D01*
G01X1855000Y167100D02*
X1854549Y166649D01*
Y161988D01*
X1853088Y160527D01*
Y153187D01*
X1853089Y153186D01*
Y152564D01*
X1851117Y150592D01*
Y140312D01*
X1850507Y139702D01*
Y125030D01*
X1859297Y116240D01*
Y109780D01*
X1857714Y108197D01*
X1853317D01*
G01X1959300Y518000D02*
X1958351Y518949D01*
X1957251D01*
X1949800Y526400D01*
X1930185D01*
X1925692Y530893D01*
X1917207D01*
X1907500Y540600D01*
Y545600D01*
G54D24*
G01X61356Y181000D02*
X54860D01*
X48644Y187216D01*
X-12785D01*
X-20079Y194510D01*
Y237290D01*
X-5883Y251486D01*
Y275682D01*
X-2906Y278659D01*
X1696D01*
X4297Y276058D01*
X5120D01*
G01X2269Y273532D02*
Y273652D01*
X551Y275370D01*
X-1132D01*
X-2717Y273785D01*
Y250262D01*
X-16914Y236065D01*
Y195943D01*
X-11381Y190410D01*
X49932D01*
X55971Y184371D01*
X58659D01*
X60288Y186000D01*
X61256D01*
G01X10365Y461602D02*
X8917Y463050D01*
X5131D01*
X341Y467840D01*
X-5690D01*
G01X66016Y468350D02*
Y465707D01*
X48407Y448098D01*
X21575D01*
X10365Y459308D01*
Y461602D01*
G01X-3100Y533991D02*
X-3048Y533939D01*
X9325D01*
X10628Y532636D01*
X14926D01*
X17710Y529852D01*
X33295D01*
X34351Y530908D01*
Y536235D01*
X40367Y542251D01*
X47163D01*
X53914Y535500D01*
X62500D01*
G01X105898Y55194D02*
X106774D01*
X110200Y58620D01*
Y77110D01*
X114910Y81820D01*
X138090D01*
X139090Y82820D01*
Y94141D01*
X143501Y98552D01*
X184984Y115734D01*
X262130Y192880D01*
Y208930D01*
X267000Y213800D01*
G01X94360Y335210D02*
X91980D01*
X90240Y336950D01*
Y337990D01*
X87515Y340715D01*
X83185D01*
X82500Y341400D01*
G01X104600Y316602D02*
X104343D01*
X100500Y312759D01*
Y306800D01*
X102600Y304700D01*
X103500D01*
G01X103200Y335190D02*
Y334130D01*
X101680Y332610D01*
X96960D01*
X94360Y335210D01*
G01X109500Y370000D02*
Y357700D01*
X108300Y356500D01*
Y351040D01*
X112880Y346460D01*
Y340380D01*
X110900Y338400D01*
Y331100D01*
X113000Y329000D01*
Y309140D01*
X110800Y306940D01*
Y292740D01*
X114500Y289040D01*
X117039D01*
X117063Y289016D01*
G01X90518Y388828D02*
Y392477D01*
X94844Y396803D01*
Y418715D01*
X101756Y425627D01*
X116003D01*
X119571Y422059D01*
Y416924D01*
X122574Y413921D01*
X125927D01*
X129988Y409860D01*
X150650D01*
G01X118008Y348991D02*
X119090Y350073D01*
Y354464D01*
X117554Y356000D01*
X116216D01*
X114500Y357716D01*
Y362020D01*
X115400Y362920D01*
Y370300D01*
X111805Y373895D01*
Y378695D01*
X107400Y383100D01*
X74814D01*
X74800Y383114D01*
G01X273500Y218900D02*
X269500D01*
X256830Y206230D01*
Y192931D01*
X182268Y118369D01*
X138668Y100309D01*
X133541Y95182D01*
X111071D01*
X109057Y93168D01*
Y92774D01*
G01X267850Y212050D02*
X265900Y210100D01*
Y192310D01*
X185413Y111823D01*
X184919Y111618D01*
X146319Y95629D01*
X144430Y93740D01*
Y82600D01*
X140640Y78810D01*
X117520D01*
X113800Y75090D01*
Y72087D01*
X115500Y70387D01*
X116200D01*
G01X386970Y623539D02*
X395880D01*
X398419Y621000D01*
X657500D01*
X662910Y615590D01*
Y600590D01*
X665000Y598500D01*
G01X667700Y275600D02*
Y268460D01*
X669309Y266851D01*
X679211D01*
X688220Y257842D01*
Y245220D01*
X696800Y236640D01*
X701920D01*
X704280Y234280D01*
X712130D01*
X715885Y230525D01*
Y226485D01*
X718550Y223820D01*
Y216794D01*
X715100Y213344D01*
G01X718546Y500283D02*
Y501417D01*
X720745Y503616D01*
X732076D01*
X735297Y506837D01*
X752387D01*
X760808Y498416D01*
X867094D01*
X872196Y503518D01*
X963120D01*
X971886Y494752D01*
X1042753D01*
X1045850Y491655D01*
X1122124D01*
X1136244Y505775D01*
X1271602D01*
X1274728Y502649D01*
X1283410D01*
X1290159Y495900D01*
X1295387D01*
X1297878Y493409D01*
Y493150D01*
G01X721894Y501346D02*
X722297Y501749D01*
X732871D01*
X736159Y505037D01*
X751641D01*
X760062Y496616D01*
X867872D01*
X872911Y501655D01*
X962172D01*
X971007Y492820D01*
X1041952D01*
X1044939Y489833D01*
X1122972D01*
X1137114Y503975D01*
X1270730D01*
X1273856Y500849D01*
X1282664D01*
X1290154Y493359D01*
X1295240D01*
G01X1401300Y149600D02*
X1393777D01*
X1391403Y151974D01*
X1312032D01*
X1310098Y150040D01*
G01X1399100Y166900D02*
X1396200Y164000D01*
Y156731D01*
X1399676Y153255D01*
X1402626D01*
X1404273Y151608D01*
Y147729D01*
X1403273Y146729D01*
X1391830D01*
X1391038Y147521D01*
X1314188D01*
X1312492Y145825D01*
Y141652D01*
X1304766Y133926D01*
Y121342D01*
X1302526Y119102D01*
G01X1331824Y209051D02*
Y211736D01*
X1332824Y212736D01*
X1337099D01*
X1338959Y214596D01*
Y224841D01*
X1334100Y229700D01*
Y239400D01*
X1318553Y254947D01*
Y260091D01*
X1311987Y266657D01*
Y286875D01*
X1314320Y289208D01*
X1316427D01*
X1320138Y285497D01*
X1328703D01*
X1332804Y281396D01*
X1346947D01*
X1350500Y284949D01*
Y285788D01*
X1351612Y286900D01*
X1352451D01*
X1352632Y287081D01*
X1364096D01*
X1365246Y285931D01*
G01X1318054Y460507D02*
Y458607D01*
X1318050Y458603D01*
Y439050D01*
X1312500Y433500D01*
Y426600D01*
X1310362Y424462D01*
Y416924D01*
X1312500Y414782D01*
Y365736D01*
X1311164Y364400D01*
Y352164D01*
X1307858Y348858D01*
Y308949D01*
X1309622Y307185D01*
Y292726D01*
X1304726Y287830D01*
Y271372D01*
X1316753Y259345D01*
Y252447D01*
X1323030Y246170D01*
Y216531D01*
G01X1309462Y240229D02*
X1313800Y244567D01*
Y258099D01*
X1303980Y267919D01*
X1300444D01*
G01X1331720Y334810D02*
Y335090D01*
X1332720Y336090D01*
X1337635D01*
X1342325Y331400D01*
X1346700D01*
X1353900Y324200D01*
X1358600D01*
X1359200Y323600D01*
Y322200D01*
G01X1308500Y540784D02*
X1310689D01*
X1315798Y535675D01*
X1321628D01*
X1326513Y530790D01*
X1393420D01*
X1399721Y537091D01*
Y537509D01*
G01X1396158Y537595D02*
Y536102D01*
X1392802Y532746D01*
X1327987D01*
X1322733Y538000D01*
X1316059D01*
X1311026Y543033D01*
X1306033D01*
X1305500Y542500D01*
G01X1388450Y331250D02*
X1388690Y331490D01*
X1389929D01*
X1402840Y344401D01*
Y352749D01*
X1397529Y358060D01*
X1391940D01*
X1389500Y360500D01*
G01X1364260Y331619D02*
Y335460D01*
X1369810Y341010D01*
X1378090D01*
X1381850Y337250D01*
X1389050D01*
X1398000Y346200D01*
Y351500D01*
X1395100Y354400D01*
X1386810D01*
X1382150Y359060D01*
Y363030D01*
X1385270Y366150D01*
Y378794D01*
X1380900Y383164D01*
G01X1524557Y88336D02*
X1523259D01*
X1521503Y90092D01*
Y113777D01*
X1520505Y114775D01*
Y125005D01*
X1522800Y127300D01*
Y131718D01*
X1518025Y136493D01*
Y179569D01*
X1522410Y183954D01*
Y207409D01*
X1523433Y208432D01*
Y211993D01*
X1525300Y213860D01*
Y219003D01*
X1523370Y220933D01*
Y229238D01*
X1518513Y234095D01*
Y243295D01*
X1517350Y244458D01*
Y271632D01*
X1512986Y275996D01*
X1511834D01*
X1509248Y278582D01*
Y283552D01*
X1506369Y286431D01*
Y298110D01*
X1506370Y298111D01*
Y299001D01*
X1501213Y304158D01*
Y316040D01*
X1500436Y316817D01*
Y316844D01*
X1495510Y321770D01*
Y321779D01*
X1495304Y321985D01*
Y329016D01*
X1490030Y334290D01*
Y340929D01*
X1483059Y347900D01*
X1480412D01*
X1479000Y349312D01*
Y354020D01*
X1478080Y354940D01*
X1478163D01*
G01X1472758Y216495D02*
X1471323D01*
X1467643Y212815D01*
Y191162D01*
X1470398Y188407D01*
Y188372D01*
X1470382D01*
G01X1487716Y218650D02*
X1487096Y218030D01*
X1485930D01*
X1480397Y212497D01*
X1476401D01*
X1475401Y211497D01*
Y210017D01*
G01X1556810Y71760D02*
X1552560Y76010D01*
X1544897D01*
X1541520Y79387D01*
G01X1577269Y95344D02*
X1578405D01*
X1583600Y100539D01*
Y101788D01*
X1585056Y103244D01*
X1597805D01*
X1600977Y100072D01*
X1603935D01*
X1606363Y102500D01*
X1606423D01*
X1606587Y102664D01*
X1615219D01*
X1617097Y104542D01*
Y112134D01*
X1616890Y112341D01*
G01X1613741Y106042D02*
X1610658D01*
X1608688Y108012D01*
X1604612D01*
X1603388Y106788D01*
X1588500D01*
G01X1616890Y118641D02*
X1622076Y113455D01*
Y105533D01*
X1621840Y105297D01*
Y105296D01*
X1620786Y104242D01*
X1619007D01*
X1616029Y101264D01*
X1607167D01*
X1604396Y98493D01*
X1600207D01*
X1596856Y101844D01*
X1589344D01*
X1588000Y100500D01*
G01X1600000Y104243D02*
X1600001Y104242D01*
X1614487D01*
X1615541Y105296D01*
Y107391D01*
X1613741Y109191D01*
G01X1674019Y175990D02*
X1672483D01*
X1670861Y174368D01*
Y166649D01*
X1667348Y163136D01*
Y156500D01*
G01X1651754Y488025D02*
Y490357D01*
X1652847Y491450D01*
Y495010D01*
X1672626Y514789D01*
X1684092D01*
X1694299Y524996D01*
X1722353D01*
X1732309Y534952D01*
Y536174D01*
X1732308Y536175D01*
Y542331D01*
X1738216Y548239D01*
G01X1705767Y482434D02*
X1722222D01*
X1731613Y491825D01*
X1759347D01*
X1762900Y495378D01*
Y513800D01*
X1766100Y517000D01*
Y521124D01*
G01X1719250Y179150D02*
X1717000Y176900D01*
Y175100D01*
X1721509Y170591D01*
X1779910D01*
X1784501Y166000D01*
X1787148D01*
X1792488Y160660D01*
X1792862D01*
X1796108Y157414D01*
Y142066D01*
X1799441Y138733D01*
X1802976D01*
X1810808Y130901D01*
Y126053D01*
X1809718Y124963D01*
Y115082D01*
X1810100Y114700D01*
G01X1814852Y519901D02*
X1818276D01*
X1823943Y525568D01*
Y573457D01*
X1813900Y583500D01*
X1813456D01*
G01X1791500Y606500D02*
X1792000D01*
X1797346Y601154D01*
Y597290D01*
X1793452Y593396D01*
Y586701D01*
G01X1893238Y208042D02*
X1890502D01*
X1888000Y205540D01*
Y197250D01*
X1881500Y190750D01*
Y175576D01*
X1883076Y174000D01*
Y160659D01*
X1884635Y159100D01*
X1886550D01*
X1890600Y155050D01*
Y136079D01*
X1894274Y132405D01*
Y114576D01*
X1896477Y112373D01*
X1899622D01*
X1902101Y109894D01*
Y105168D01*
X1882505Y85572D01*
X1881200D01*
X1877400Y81772D01*
Y74550D01*
X1878000Y73950D01*
G01X1848208Y49427D02*
X1861104D01*
X1862431Y48100D01*
X1879300D01*
X1882886Y51686D01*
Y64086D01*
X1889300Y70500D01*
X1897900D01*
X1900226Y72826D01*
X1909326D01*
X1916190Y79690D01*
Y91653D01*
X1918113Y93576D01*
G01X1892401Y516040D02*
X1894689Y518328D01*
G01D02*
X1896977Y520616D01*
G01X1892401D02*
X1894689Y518328D01*
G01D02*
X1896977Y516040D01*
G54D15*
X18228Y178386D03*
X-1969D03*
X44291D03*
G54D34*
G01X1664257Y-43317D02*
X1470600D01*
G03Y-45768I0J-1226D01*
G01X1663763D01*
G02Y-51521I0J-2876D01*
G01X1462786D01*
X1459348Y-48083D01*
X1416432D01*
X1412258Y-52257D01*
G01X1664257Y-41666D02*
X1470600D01*
G03Y-47419I0J-2876D01*
G01X1663763D01*
G02Y-49870I0J-1226D01*
G01X1463470D01*
X1460032Y-46432D01*
X1416433D01*
X1412258Y-42257D01*
G01X1553825Y418074D02*
X1555156D01*
X1555412Y417818D01*
G03X1556562Y416059I2312J256D01*
G02X1557350Y414738I-787J-1365D01*
G01Y414609D01*
G03X1558512Y412679I2325J85D01*
G02X1559300Y411358I-787J-1365D01*
G01Y411229D01*
G03X1560462Y409299I2325J85D01*
G02X1561250Y407978I-787J-1365D01*
G01Y407849D01*
G03X1562412Y405919I2325J85D01*
G02X1563200Y404598I-787J-1365D01*
G01Y404469D01*
G03X1566688Y402539I2325J85D01*
G02X1568262I787J-1365D01*
G01X1568414Y402451D01*
G03X1570582Y402528I1011J2103D01*
G02X1571366Y402737I786J-1374D01*
G01X1572292D01*
X1572998Y402031D01*
Y400480D01*
X1573958Y399520D01*
Y398882D01*
X1574020Y398820D01*
Y398821D01*
G01X1557725Y418074D02*
X1556394D01*
X1556166Y417846D01*
G03X1556937Y416710I1559J228D01*
G02X1558101Y414748I-1162J-2016D01*
G01Y414625D01*
G03X1558887Y413330I1574J69D01*
G02X1560051Y411368I-1162J-2016D01*
G01Y411245D01*
G03X1560837Y409950I1574J69D01*
G02X1562001Y407988I-1162J-2016D01*
G01Y407865D01*
G03X1562787Y406570I1574J69D01*
G02X1563951Y404608I-1162J-2016D01*
G01Y404485D01*
G03X1566313Y403190I1574J69D01*
G02X1568638I1163J-2016D01*
G01X1568763Y403117D01*
G03X1570209Y403180I662J1437D01*
G02X1571365Y403488I1159J-2026D01*
G01X1572604D01*
X1573749Y402343D01*
Y400792D01*
X1574491Y400050D01*
X1575126D01*
X1575188Y399988D01*
G01X1567475Y407934D02*
X1568806D01*
X1569073Y407599D01*
G03X1571386Y405598I2314J337D01*
G01X1574432D01*
X1575067Y404963D01*
Y404327D01*
X1575129Y404265D01*
G01X1576296Y405433D02*
X1576297D01*
X1576235Y405495D01*
X1575599D01*
X1575280Y405814D01*
X1575279D01*
X1574744Y406349D01*
X1571387D01*
G02X1569817Y407707I0J1587D01*
G01X1570044Y407934D01*
X1571375D01*
G01X1563575Y414694D02*
X1564906D01*
X1565161Y414949D01*
G02X1566312Y416710I2313J-255D01*
G02X1568638I1163J-2016D01*
G03X1570212I787J1364D01*
G02X1572538I1163J-2016D01*
G03X1573325Y416498I787J1355D01*
G01X1575016D01*
X1575466Y416948D01*
X1575836D01*
G01X1567475Y414694D02*
X1566144D01*
X1565917Y414921D01*
G02X1566688Y416058I1558J-227D01*
G02X1568262I787J-1364D01*
G03X1570588I1163J2016D01*
G02X1572162I787J-1364D01*
G03X1573325Y415747I1162J2017D01*
G01X1575016D01*
X1575466Y415297D01*
X1575553D01*
G01X1575133Y423678D02*
X1574713Y423258D01*
X1573325D01*
G02X1572538Y423470I0J1567D01*
G03X1570212I-1163J-2016D01*
G02X1568638I-787J1364D01*
G03X1566312I-1163J-2016D01*
G02X1564738I-787J1364D01*
G03X1562412I-1163J-2016D01*
G03X1561249Y421535I1163J-2016D01*
G01Y421406D01*
G02X1560462Y420090I-1574J48D01*
G02X1558888I-787J1364D01*
G02X1558117Y421227I787J1364D01*
G01X1558344Y421454D01*
X1559675D01*
G01X1575133Y422027D02*
X1574653Y422507D01*
X1573327D01*
X1573326Y422506D01*
Y422507D01*
X1573325D01*
G02X1572162Y422819I-1J2318D01*
G01Y422818D01*
G03X1570588I-787J-1364D01*
G02X1568262I-1163J2016D01*
G03X1566688I-787J-1364D01*
G02X1564362I-1163J2016D01*
G03X1562788I-787J-1364D01*
G03X1562001Y421502I787J-1364D01*
G01Y421373D01*
G02X1560838Y419438I-2326J81D01*
G02X1558512I-1163J2016D01*
G02X1557361Y421199I1162J2016D01*
G01X1557106Y421454D01*
X1555775D01*
G54D25*
G01X913758Y366958D02*
X875496D01*
X845639Y396815D01*
X828285D01*
X824000Y401100D01*
Y402863D01*
G01X919200Y371100D02*
X876004D01*
X846389Y400715D01*
X829948D01*
X827800Y402863D01*
G01X922700Y374758D02*
X878298D01*
Y374764D01*
X848747Y404315D01*
X833752D01*
X832300Y402863D01*
G54D16*
X3937Y204370D03*
X-3937D03*
X-11811D03*
X35433D03*
X27559D03*
X19685D03*
X3937Y227992D03*
X-3937D03*
X-11811D03*
X35433D03*
X27559D03*
X19685D03*
X3937Y313504D03*
X-3937D03*
X-11811D03*
X3937Y337126D03*
X-3937D03*
X-11811D03*
X35433D03*
X27559D03*
X19685D03*
X35433Y313504D03*
X27559D03*
X19685D03*
G54D35*
G01X267000Y213800D02*
X268100Y214900D01*
X275300D01*
X277300Y216900D01*
X278700D01*
X280700Y214900D01*
X282000D01*
X284000Y216900D01*
X285500D01*
X287400Y215000D01*
X288800D01*
X290753Y213047D01*
Y212909D01*
X292108D01*
X294199Y215000D01*
X295600D01*
X297691Y212909D01*
X298944D01*
X300893Y214858D01*
X302223D01*
X304376Y217011D01*
X305805D01*
X307552Y218758D01*
X309081D01*
X311234Y220911D01*
X312564D01*
X313647Y221994D01*
Y223526D01*
X313329Y223844D01*
Y225475D01*
X314615Y226761D01*
X315944D01*
X317692Y228509D01*
X319222D01*
X321373Y230660D01*
X322704D01*
X324655Y232611D01*
X326084D01*
X327167Y233694D01*
Y235324D01*
X326849Y235643D01*
Y237175D01*
X327932Y238258D01*
X329361D01*
X331514Y240411D01*
X332844D01*
X333927Y241494D01*
Y243125D01*
X333609Y243443D01*
Y244975D01*
X334894Y246260D01*
X336224D01*
X338175Y248211D01*
X339604D01*
X342217Y250824D01*
Y252008D01*
X342218Y252009D01*
G01X338838Y250060D02*
X334794D01*
X332743Y248009D01*
X331312D01*
X330229Y246926D01*
Y245394D01*
X330547Y245075D01*
Y243443D01*
X329464Y242360D01*
X328033D01*
X326084Y240411D01*
X324754D01*
X323469Y239126D01*
Y237493D01*
X323787Y237175D01*
Y235643D01*
X322704Y234560D01*
X321273D01*
X319121Y232408D01*
X317792D01*
X316044Y230660D01*
X314514D01*
X312564Y228710D01*
X311233D01*
X309949Y227426D01*
Y225894D01*
X310267Y225576D01*
Y223943D01*
X308982Y222658D01*
X307652D01*
X305905Y220911D01*
X304376D01*
X302425Y218960D01*
X301095D01*
X298944Y216809D01*
X297691D01*
X295600Y218900D01*
X294200D01*
X292109Y216809D01*
X290891D01*
X288800Y218900D01*
X287400D01*
X285400Y220900D01*
X284100D01*
X282100Y218900D01*
X280600D01*
X278600Y220900D01*
X277400D01*
X275400Y218900D01*
X273500D01*
G01X342218Y248109D02*
X340687Y246578D01*
Y245394D01*
X339402Y244109D01*
X338072D01*
X336989Y243026D01*
Y241393D01*
X337307Y241075D01*
Y239543D01*
X336022Y238258D01*
X334591D01*
X332844Y236511D01*
X331514D01*
X330229Y235226D01*
Y233694D01*
X330547Y233376D01*
Y231743D01*
X329263Y230459D01*
X327932D01*
X325982Y228509D01*
X324452D01*
X322704Y226761D01*
X321375D01*
X319223Y224609D01*
X317792D01*
X316709Y223526D01*
Y221994D01*
X317027Y221676D01*
Y220043D01*
X315742Y218758D01*
X314311D01*
X312362Y216809D01*
X311032D01*
X309081Y214858D01*
X307552D01*
X305805Y213111D01*
X304403D01*
X302250Y210958D01*
X300893D01*
X298943Y209008D01*
X297692D01*
X295600Y211100D01*
X294201D01*
X292109Y209008D01*
X290753D01*
Y209147D01*
X288900Y211000D01*
X287500D01*
X285500Y213000D01*
X284000D01*
X282100Y211100D01*
X280600D01*
X278700Y213000D01*
X277300D01*
X275400Y211100D01*
X273900D01*
X271800Y213200D01*
X269000D01*
X267850Y212050D01*
G01X998586Y337809D02*
X997055Y339340D01*
Y340526D01*
X995770Y341811D01*
X994440D01*
X992551Y343700D01*
X991021D01*
X989010Y345711D01*
X987680D01*
X985933Y347458D01*
X984403D01*
X982250Y349611D01*
X980920D01*
X978971Y351560D01*
X977540D01*
X976457Y352643D01*
Y354175D01*
X976775Y354493D01*
Y356126D01*
X975692Y357209D01*
X974261D01*
X972110Y359360D01*
X970780D01*
X969697Y360443D01*
Y362075D01*
X970015Y362394D01*
Y363926D01*
X968932Y365009D01*
X967501D01*
X965552Y366958D01*
X963919D01*
X962172Y365211D01*
X960640D01*
X958893Y366958D01*
X957160D01*
X955413Y365211D01*
X953881D01*
X952134Y366958D01*
X950400D01*
X948653Y365211D01*
X947121D01*
X945374Y366958D01*
X943640D01*
X941893Y365211D01*
X940361D01*
X938614Y366958D01*
X936880D01*
X935133Y365211D01*
X933601D01*
X931854Y366958D01*
X930120D01*
X928373Y365211D01*
X926841D01*
X925094Y366958D01*
X913758D01*
G01X998586Y341709D02*
X997055Y343240D01*
Y344426D01*
X995770Y345711D01*
X994339D01*
X992592Y347458D01*
X991163D01*
X989010Y349611D01*
X987680D01*
X985731Y351560D01*
X984300D01*
X982349Y353511D01*
X980920D01*
X979837Y354594D01*
Y356126D01*
X980155Y356444D01*
Y358075D01*
X978870Y359360D01*
X977540D01*
X975589Y361311D01*
X974160D01*
X973077Y362394D01*
Y363926D01*
X973395Y364244D01*
Y365875D01*
X972109Y367161D01*
X970780D01*
X968831Y369110D01*
X967301D01*
X965552Y370859D01*
X964020D01*
X962271Y369110D01*
X960541D01*
X958792Y370859D01*
X957260D01*
X955511Y369110D01*
X953782D01*
X952033Y370859D01*
X950501D01*
X948752Y369110D01*
X947022D01*
X945273Y370859D01*
X943741D01*
X941992Y369110D01*
X940262D01*
X938513Y370859D01*
X936981D01*
X935232Y369110D01*
X933502D01*
X931753Y370859D01*
X930221D01*
X928472Y369110D01*
X926742D01*
X924993Y370859D01*
X919441D01*
X919200Y371100D01*
G01X998586Y345609D02*
X997055Y347140D01*
Y348326D01*
X995972Y349409D01*
X994541D01*
X992390Y351560D01*
X991060D01*
X989109Y353511D01*
X987680D01*
X985933Y355258D01*
X984502D01*
X983217Y356543D01*
Y358075D01*
X983535Y358393D01*
Y360026D01*
X982250Y361311D01*
X980920D01*
X979173Y363058D01*
X977742D01*
X976457Y364343D01*
Y365875D01*
X976775Y366193D01*
Y367826D01*
X975491Y369110D01*
X974160D01*
X972210Y371060D01*
X970780D01*
X968829Y373011D01*
X967400D01*
X965653Y374758D01*
X963919D01*
X962172Y373011D01*
X960640D01*
X958893Y374758D01*
X957160D01*
X955413Y373011D01*
X953881D01*
X952134Y374758D01*
X950400D01*
X948653Y373011D01*
X947121D01*
X945374Y374758D01*
X943640D01*
X941893Y373011D01*
X940361D01*
X938614Y374758D01*
X936880D01*
X935133Y373011D01*
X933601D01*
X931854Y374758D01*
X930120D01*
X928373Y373011D01*
X926841D01*
X925094Y374758D01*
X922700D01*
G54D26*
G01X641541Y243828D02*
X651147D01*
X654381Y247062D01*
Y249308D01*
X652796Y250893D01*
Y255293D01*
X656903Y259400D01*
X676900D01*
X684400Y251900D01*
Y242600D01*
X697900Y229100D01*
X708100D01*
X710500Y226700D01*
Y224500D01*
G54D17*
X42724Y644684D03*
Y644656D03*
Y654684D03*
Y654656D03*
X67724Y644684D03*
Y644656D03*
Y654684D03*
Y654656D03*
X221656Y644656D03*
X196656D03*
X231446Y644756D03*
Y644784D03*
X221656Y644684D03*
X196656D03*
X221656Y654656D03*
X196656D03*
X231446Y654756D03*
Y654784D03*
X221656Y654684D03*
X196656D03*
X256446Y644756D03*
Y644784D03*
Y654756D03*
Y654784D03*
X409240Y644564D03*
X384240D03*
X418914Y644486D03*
Y644514D03*
X409240Y644536D03*
X384240D03*
X409240Y654564D03*
X384240D03*
X418914Y654486D03*
Y654514D03*
X409240Y654536D03*
X384240D03*
X596707Y644293D03*
X596708Y644266D03*
X596707Y654293D03*
X596708Y654266D03*
X606462Y644245D03*
X631462D03*
X606462Y644217D03*
X631462D03*
X606462Y654245D03*
X631462D03*
X606462Y654217D03*
X631462D03*
X912351Y644245D03*
X887351D03*
X912351Y644273D03*
X887351D03*
X912351Y654245D03*
X887351D03*
X912351Y654273D03*
X887351D03*
X922116Y644206D03*
X947116D03*
X922116Y644234D03*
X947116D03*
X922116Y654206D03*
X947116D03*
X922116Y654234D03*
X947116D03*
X1200877Y644262D03*
Y644234D03*
Y654262D03*
Y654234D03*
X1225877Y644262D03*
X1235614Y644236D03*
Y644264D03*
X1225877Y644234D03*
Y654262D03*
X1235614Y654236D03*
Y654264D03*
X1225877Y654234D03*
X1539375Y644292D03*
Y644264D03*
Y654292D03*
Y654264D03*
G54D36*
G01X562230Y394358D02*
Y414819D01*
X522649Y454400D01*
X484248Y462079D01*
X409433Y447115D01*
X388501Y451300D01*
X371457Y447892D01*
X327331Y456717D01*
X276320Y446513D01*
X244189Y425092D01*
X232689Y407844D01*
X222437Y356584D01*
X223890Y349319D01*
X220929Y334510D01*
X215040Y320296D01*
X211768Y303934D01*
X225622Y234662D01*
X224760Y230343D01*
X203474Y198415D01*
X159908Y169374D01*
X141682Y163863D01*
X133619D01*
X123864Y168721D01*
X102906Y172912D01*
X69521Y166236D01*
X46848Y162516D01*
X34141Y156431D01*
X31842Y154371D01*
X28026Y152977D01*
X-5609D01*
X-7950Y150636D01*
Y148951D01*
X-8436Y148465D01*
X-10236D01*
G01X557229Y403499D02*
Y413544D01*
X549419Y421354D01*
X548500D01*
X547545Y422308D01*
Y423228D01*
X519720Y451053D01*
X484098Y458176D01*
X406430Y442643D01*
X390394Y445850D01*
X385149Y444797D01*
X384639Y444032D01*
X383316Y443767D01*
X382550Y444276D01*
X376271Y443016D01*
X326935Y452885D01*
X279612Y443420D01*
X247904Y422280D01*
X238595Y408319D01*
X227253Y351599D01*
X229185Y341938D01*
Y329698D01*
X226475Y326988D01*
Y323160D01*
X228713Y318974D01*
X236655Y307077D01*
X237554Y302580D01*
X236310Y296367D01*
X225530Y276206D01*
Y265028D01*
X227650Y259909D01*
Y254428D01*
X227059Y251471D01*
X230330Y235121D01*
X229280Y229871D01*
X229279D01*
X206799Y196150D01*
X161740Y166112D01*
X134742Y157950D01*
X122112D01*
X116853Y160636D01*
X112207Y165222D01*
X104714Y168581D01*
X101323Y168792D01*
X98998Y168326D01*
X98522Y167612D01*
X97196Y167346D01*
X96482Y167824D01*
X69577Y162446D01*
X49867Y159208D01*
X43678Y155736D01*
X43090Y155053D01*
X41764Y151474D01*
X40865Y150467D01*
X40916Y149549D01*
X40017Y148543D01*
X39099Y148491D01*
X37234Y146403D01*
X33673Y143953D01*
X9462D01*
X8250Y145165D01*
Y146620D01*
X6405Y148465D01*
X6299D01*
G01X544094Y416491D02*
X513949Y446636D01*
X484645Y452468D01*
X461533Y447871D01*
X461022Y447107D01*
X459698Y446844D01*
X458934Y447354D01*
X379813Y431617D01*
X365288Y434523D01*
X327953Y427057D01*
X292619Y434123D01*
X270514Y429701D01*
X250060Y416067D01*
X244124Y407163D01*
X244104Y407066D01*
X243922Y406792D01*
X232868Y351522D01*
X242656Y302583D01*
X240991Y294257D01*
X231630Y276767D01*
Y269587D01*
X235064Y266153D01*
Y264617D01*
X232678Y252681D01*
X236216Y234978D01*
X234721Y227508D01*
X211598Y192820D01*
X164265Y161267D01*
X137051Y152850D01*
X114491D01*
X111708Y154988D01*
X111707D01*
X109545Y156650D01*
X98093D01*
X91382Y160478D01*
X90177Y160691D01*
X68155Y156929D01*
X59968Y153540D01*
X56391Y149963D01*
X49960Y147300D01*
X46409D01*
X43263Y146636D01*
X39851Y143223D01*
X38728Y142473D01*
X38549Y141571D01*
X37427Y140822D01*
X36525Y141001D01*
X35402Y140251D01*
X35223Y139349D01*
X34100Y138600D01*
X33199Y138779D01*
X30906Y137247D01*
X28087Y136079D01*
X4678D01*
X3250Y137507D01*
Y139262D01*
X1921Y140591D01*
X1181D01*
G01X-4725Y148465D02*
X-6277D01*
X-6800Y148988D01*
Y150159D01*
X-5132Y151827D01*
X28230D01*
X32445Y153366D01*
X34787Y155464D01*
X47197Y161407D01*
X69727Y165104D01*
X102906Y171739D01*
X123488Y167623D01*
X133348Y162713D01*
X141853D01*
X160404Y168322D01*
X204304Y197585D01*
X225844Y229894D01*
X226795Y234662D01*
X212941Y303934D01*
X216146Y319960D01*
X222035Y334174D01*
X225063Y349319D01*
X223610Y356584D01*
X233772Y407395D01*
X245019Y424262D01*
X269112Y440323D01*
X269615Y440222D01*
X270741Y440972D01*
X270840Y441476D01*
X272010Y442255D01*
X272655Y442125D01*
X273781Y442875D01*
X273908Y443521D01*
Y443522D01*
X276769Y445430D01*
X327331Y455544D01*
X371457Y446719D01*
X388501Y450127D01*
X409433Y445942D01*
X484248Y460906D01*
X522082Y453340D01*
X548586Y426836D01*
Y426200D01*
X549542Y425244D01*
X550178D01*
X561080Y414342D01*
Y394358D01*
G01X11811Y148465D02*
X11156D01*
X9400Y146709D01*
Y145642D01*
X9939Y145103D01*
X33315D01*
X36468Y147272D01*
X40761Y152078D01*
X42083Y155646D01*
X42938Y156640D01*
X49480Y160311D01*
X69371Y163578D01*
X101244Y169950D01*
X104994Y169716D01*
X112868Y166187D01*
X117535Y161580D01*
X122389Y159100D01*
X134571D01*
X161244Y167164D01*
X205969Y196980D01*
X228196Y230320D01*
X229156Y235121D01*
X229157D01*
X225886Y251471D01*
X226500Y254542D01*
Y259680D01*
X224380Y264799D01*
Y276498D01*
X235215Y296760D01*
X236381Y302580D01*
X235572Y306628D01*
X227725Y318382D01*
X225325Y322871D01*
Y327465D01*
X228035Y330175D01*
Y341824D01*
X226080Y351599D01*
X237512Y408768D01*
X247074Y423110D01*
X279163Y444503D01*
X326935Y454058D01*
X376271Y444189D01*
X390394Y447023D01*
X406430Y443816D01*
X484098Y459349D01*
X520287Y452113D01*
X558379Y414021D01*
Y403499D01*
G01X6693Y140591D02*
X5941D01*
X4400Y139050D01*
Y137984D01*
X5155Y137229D01*
X27858D01*
X30361Y138266D01*
X39117Y144117D01*
X42691Y147691D01*
X46288Y148450D01*
X49731D01*
X55739Y150939D01*
X59316Y154516D01*
X67834Y158041D01*
X90180Y161859D01*
X91779Y161576D01*
X98398Y157800D01*
X101936D01*
X102586Y158450D01*
X103936D01*
X104586Y157800D01*
X109936D01*
X114882Y154000D01*
X136877D01*
X163765Y162317D01*
X210768Y193650D01*
X233638Y227957D01*
X235043Y234978D01*
X231505Y252681D01*
X233914Y264736D01*
Y265676D01*
X230480Y269110D01*
Y277056D01*
X239896Y294650D01*
X241483Y302583D01*
X231695Y351522D01*
X242838Y407240D01*
X243022Y407517D01*
X243043Y407615D01*
X249230Y416897D01*
X270065Y430784D01*
X292619Y435296D01*
X327953Y428230D01*
X365288Y435696D01*
X379814Y432790D01*
X484645Y453641D01*
X514516Y447696D01*
X544908Y417304D01*
G01X-15354Y156339D02*
X-15353D01*
X-13250Y158442D01*
Y160177D01*
X-5977Y167450D01*
X25139D01*
X39216Y170250D01*
X44015D01*
X63711Y174167D01*
X67173D01*
X102129Y181159D01*
X102130D01*
X105298Y180500D01*
X108000Y181401D01*
X109090Y184076D01*
X111191Y186152D01*
X114661Y186844D01*
X117431Y186291D01*
X117846Y186254D01*
X126749Y175812D01*
X135748Y171585D01*
X140880D01*
X155079Y175758D01*
X155091Y175761D01*
X155098Y175763D01*
X197053Y203733D01*
X214442Y229813D01*
X208760Y258227D01*
Y277705D01*
X201942Y311788D01*
X220601Y405492D01*
X236432Y429237D01*
X274100Y454350D01*
X326633Y464856D01*
X358106Y458563D01*
X387402Y464420D01*
X422212Y457451D01*
X484833Y469975D01*
X530570Y460829D01*
X570480Y420919D01*
Y370200D01*
X566881Y366601D01*
G01X564492Y369355D02*
X567680Y372543D01*
Y418428D01*
X527379Y458729D01*
X484439Y467315D01*
X417187Y453867D01*
X387547Y459790D01*
X363304Y454942D01*
X327383Y462127D01*
X274748Y451599D01*
X239437Y428053D01*
X239436D01*
X223247Y403813D01*
X207914Y327106D01*
X208795Y325786D01*
X209798Y325585D01*
X210151Y325056D01*
X209944Y324025D01*
X209415Y323672D01*
X208412Y323873D01*
X207091Y322991D01*
X206697Y321022D01*
X207578Y319702D01*
X208581Y319501D01*
X208934Y318972D01*
X208727Y317941D01*
X208198Y317588D01*
X207195Y317789D01*
X205874Y316907D01*
X204858Y311827D01*
X211710Y277569D01*
Y258004D01*
X217425Y229423D01*
X198966Y201734D01*
X156900Y173692D01*
X141115Y168917D01*
X135542D01*
X126001Y173396D01*
X101029Y178387D01*
X54766Y169135D01*
X42641Y167148D01*
X41361Y167447D01*
X24636Y164707D01*
X7487D01*
X5595Y163680D01*
X3150Y161235D01*
Y158307D01*
X1182Y156339D01*
X1181D01*
G01X563930Y386564D02*
Y415870D01*
X524254Y455546D01*
X484351Y463523D01*
X412782Y449213D01*
X410579Y449653D01*
X409814Y449143D01*
X408491Y449408D01*
X407981Y450173D01*
X406657Y450437D01*
X405892Y449927D01*
X404568Y450192D01*
X404058Y450957D01*
X402734Y451221D01*
X401970Y450711D01*
X400646Y450976D01*
X400136Y451741D01*
X400135D01*
X387449Y454277D01*
X367661Y450318D01*
X327731Y458303D01*
X275873Y447932D01*
X242659Y425790D01*
X230356Y407335D01*
X220210Y356626D01*
X221054Y352479D01*
X218747Y341140D01*
X216402Y337596D01*
X216403D01*
X209980Y305496D01*
X215394Y278286D01*
Y260337D01*
X221712Y228716D01*
X211967Y214100D01*
X211966Y214099D01*
X202222Y199484D01*
X158570Y170381D01*
X141482Y165213D01*
X134001D01*
X124797Y169912D01*
X101260Y174618D01*
X55305Y165428D01*
X42319Y163301D01*
X41042Y163600D01*
X23055Y160653D01*
X22073Y160228D01*
X20800Y158959D01*
Y158124D01*
X22585Y156339D01*
X23228D01*
G01X-9843D02*
X-12100Y158596D01*
Y159700D01*
X-5500Y166300D01*
X25253D01*
X39330Y169100D01*
X44129D01*
X63825Y173017D01*
X67287D01*
X102125Y179985D01*
X102126Y179984D01*
Y179985D01*
X105368Y179310D01*
X108866Y180477D01*
X110067Y183423D01*
X111755Y185091D01*
X114661Y185671D01*
X117267Y185151D01*
X117270Y185150D01*
X117275Y185148D01*
X126035Y174876D01*
X135491Y170435D01*
X141046D01*
X155404Y174653D01*
X155416Y174657D01*
X155421Y174658D01*
X155589Y174707D01*
X155590Y174708D01*
X197883Y202903D01*
X215664Y229571D01*
X209910Y258341D01*
Y277819D01*
X203115Y311789D01*
X221685Y405043D01*
X237262Y428407D01*
X274549Y453267D01*
X326633Y463683D01*
X358106Y457390D01*
X387402Y463247D01*
X410446Y458633D01*
X410956Y457868D01*
X412279Y457603D01*
X413044Y458113D01*
X414368Y457848D01*
X414877Y457083D01*
X416201Y456818D01*
X416966Y457328D01*
X418290Y457063D01*
X418800Y456298D01*
X420123Y456033D01*
X420888Y456543D01*
X422212Y456278D01*
X484833Y468802D01*
X530003Y459769D01*
X569330Y420442D01*
Y370677D01*
X566067Y367414D01*
G01X563679Y370169D02*
X566530Y373020D01*
Y417951D01*
X549245Y435236D01*
X548325D01*
X547371Y436191D01*
Y437110D01*
X546416Y438065D01*
X545497D01*
X544542Y439019D01*
Y439939D01*
X526812Y457669D01*
X484439Y466142D01*
X417187Y452694D01*
X387547Y458617D01*
X363304Y453769D01*
X327383Y460954D01*
X275197Y450516D01*
X240266Y427223D01*
X226743Y406973D01*
X226922Y406072D01*
X226172Y404949D01*
X225271Y404770D01*
X224331Y403363D01*
X209136Y327348D01*
X209488Y326821D01*
X210491Y326620D01*
X211373Y325298D01*
X210978Y323332D01*
X209657Y322450D01*
X208654Y322651D01*
X208126Y322298D01*
X207919Y321264D01*
X208271Y320737D01*
X209274Y320536D01*
X210156Y319214D01*
X209761Y317248D01*
X208440Y316366D01*
X207437Y316567D01*
X206909Y316214D01*
X206031Y311827D01*
X206032Y311825D01*
X212860Y277683D01*
Y258118D01*
X218647Y229181D01*
X199796Y200904D01*
X157397Y172640D01*
X141286Y167767D01*
X135285D01*
X125638Y172295D01*
X101029Y177214D01*
X54972Y168003D01*
X42601Y165976D01*
X41322Y166275D01*
X24730Y163557D01*
X13386D01*
X12924Y163095D01*
X11574D01*
X11112Y163557D01*
X7779D01*
X6291Y162748D01*
X4300Y160758D01*
Y158732D01*
X6693Y156339D01*
G01X565080Y386564D02*
Y416347D01*
X524821Y456606D01*
X484351Y464696D01*
X412782Y450386D01*
X387449Y455450D01*
X367661Y451491D01*
X327731Y459476D01*
X275424Y449015D01*
X241829Y426620D01*
X229273Y407784D01*
X219037Y356625D01*
X219036Y356624D01*
X219880Y352479D01*
X217664Y341589D01*
X215319Y338043D01*
X208807Y305497D01*
X214244Y278172D01*
Y260223D01*
X220490Y228958D01*
X201392Y200313D01*
X158073Y171433D01*
X141311Y166363D01*
X134278D01*
X125178Y171009D01*
X101260Y175791D01*
X55108Y166562D01*
X42358Y164473D01*
X41082Y164772D01*
X22729Y161765D01*
X21416Y161197D01*
X19650Y159437D01*
Y158272D01*
X17717Y156339D01*
X17716D01*
G01X1478119Y466469D02*
Y468576D01*
X1464045Y482650D01*
Y491942D01*
X1460965Y495022D01*
Y500634D01*
X1445250Y516350D01*
X1429750D01*
X1426450Y519650D01*
Y526847D01*
X1422431Y530866D01*
Y532806D01*
X1413837Y541400D01*
X1398500D01*
X1392211Y547689D01*
X1382989D01*
X1381976Y546676D01*
X1370080D01*
X1368411Y545007D01*
X1354750D01*
X1350624Y540881D01*
X1338550D01*
X1336692Y539023D01*
X1326775D01*
X1319298Y546500D01*
X1301326D01*
X1298375Y549451D01*
Y561174D01*
X1300057Y562856D01*
Y580674D01*
X1300969Y581586D01*
Y599814D01*
X1298983Y601800D01*
X740484D01*
X734939Y607345D01*
X731257D01*
X727538Y603626D01*
X723020D01*
X719305Y599911D01*
Y593870D01*
X709085Y583650D01*
X700142D01*
X698642Y585150D01*
X659851D01*
X647336Y597665D01*
X628009D01*
X625321Y600353D01*
X115555D01*
X102150Y586948D01*
Y547277D01*
X97606Y542733D01*
X93216D01*
X75624Y525141D01*
Y514651D01*
X67350Y506377D01*
Y491249D01*
X75819Y482780D01*
Y469718D01*
X36832Y430731D01*
Y429141D01*
X37550Y428423D01*
Y425400D01*
G01X40965Y429434D02*
X38166D01*
X37982Y429618D01*
Y430254D01*
X76969Y469241D01*
Y483257D01*
X68500Y491726D01*
Y505900D01*
X76774Y514174D01*
Y524664D01*
X93693Y541583D01*
X98083D01*
X103300Y546800D01*
Y586471D01*
X116032Y599203D01*
X624844D01*
X627532Y596515D01*
X646859D01*
X659374Y584000D01*
X698165D01*
X699665Y582500D01*
X709562D01*
X720455Y593393D01*
Y599434D01*
X723497Y602476D01*
X728015D01*
X731734Y606195D01*
X734462D01*
X740007Y600650D01*
X1298506D01*
X1299819Y599337D01*
Y582063D01*
X1298907Y581151D01*
Y563333D01*
X1297225Y561651D01*
Y548974D01*
X1300849Y545350D01*
X1318821D01*
X1326298Y537873D01*
X1337169D01*
X1339027Y539731D01*
X1351101D01*
X1355227Y543857D01*
X1368888D01*
X1370557Y545526D01*
X1382453D01*
X1383466Y546539D01*
X1391734D01*
X1398023Y540250D01*
X1413360D01*
X1421281Y532329D01*
Y530389D01*
X1425300Y526370D01*
Y519173D01*
X1429273Y515200D01*
X1430623D01*
X1431273Y514550D01*
X1432623D01*
X1433273Y515200D01*
X1434623D01*
X1435273Y514550D01*
X1436623D01*
X1437273Y515200D01*
X1438623D01*
X1439273Y514550D01*
X1440623D01*
X1441273Y515200D01*
X1444773D01*
X1445728Y514245D01*
Y513326D01*
X1446682Y512372D01*
X1447601D01*
X1448556Y511417D01*
Y510498D01*
X1449511Y509543D01*
X1450430D01*
X1451385Y508588D01*
Y507669D01*
X1452339Y506715D01*
X1453258D01*
X1459815Y500158D01*
Y494545D01*
X1462895Y491465D01*
Y482173D01*
X1465656Y479412D01*
Y478493D01*
X1466610Y477539D01*
X1467529D01*
X1468484Y476584D01*
Y475665D01*
X1469438Y474710D01*
X1470358D01*
X1471312Y473756D01*
Y472837D01*
X1472267Y471882D01*
X1473186D01*
X1474141Y470927D01*
Y470008D01*
X1475095Y469054D01*
X1476014D01*
X1476969Y468099D01*
Y466469D01*
G01X509089Y403972D02*
X507300D01*
X506847Y404425D01*
X461200Y413556D01*
X439620Y409239D01*
X420774Y413008D01*
X384011Y405653D01*
X364470Y409561D01*
X331783Y403023D01*
X299917Y409396D01*
X275452Y404504D01*
X267113Y398947D01*
X265803Y396980D01*
X256598Y350954D01*
X266236Y302755D01*
X256917Y256150D01*
X260862Y236426D01*
X256939Y216808D01*
X227896Y173246D01*
X182456Y143560D01*
X175773Y133536D01*
X129273Y102528D01*
X101639Y97000D01*
X97149D01*
X96499Y97650D01*
X95149D01*
X94499Y97000D01*
X93149D01*
X92499Y97650D01*
X91149D01*
X90499Y97000D01*
X89149D01*
X88499Y97650D01*
X87149D01*
X86499Y97000D01*
X85149D01*
X84499Y97650D01*
X83149D01*
X82499Y97000D01*
X81149D01*
X67462Y94276D01*
X65650Y92464D01*
Y91350D01*
X65200Y90900D01*
X63725D01*
G01X509089Y402822D02*
X506823D01*
X506280Y403365D01*
X461200Y412383D01*
X439620Y408066D01*
X420774Y411835D01*
X384011Y404480D01*
X364470Y408388D01*
X331783Y401850D01*
X299917Y408223D01*
X275901Y403420D01*
X267943Y398118D01*
X266887Y396531D01*
X257771Y350954D01*
X267409Y302755D01*
X258090Y256150D01*
X262035Y236426D01*
X258022Y216359D01*
X228723Y172411D01*
X183283Y142725D01*
X176603Y132706D01*
X129722Y101445D01*
X101753Y95850D01*
X81263D01*
X68029Y93216D01*
X66800Y91987D01*
Y91350D01*
X67250Y90900D01*
X68725D01*
G01X51309Y154356D02*
X50234D01*
X49884Y154706D01*
Y155498D01*
X50631Y156409D01*
X51651Y156794D01*
X68166Y159515D01*
X93022Y164488D01*
X100379Y162848D01*
X115439Y157532D01*
X119593Y155450D01*
X135116D01*
X163531Y164040D01*
X209569Y194731D01*
X232263Y228771D01*
X233381Y234360D01*
X229849Y252021D01*
X231002Y257786D01*
X228580Y265794D01*
Y276603D01*
X238685Y295485D01*
X240105Y302581D01*
X239011Y308053D01*
X231375Y319490D01*
Y321988D01*
X232875Y323488D01*
Y328353D01*
X232280Y328948D01*
Y340758D01*
X232189Y341123D01*
X229994Y352102D01*
X241063Y407457D01*
X249048Y419435D01*
X281665Y441171D01*
X327068Y450253D01*
X327080Y450256D01*
X382326Y439206D01*
X395318Y441804D01*
X405701Y439727D01*
X483678Y455321D01*
X516982Y448649D01*
X548120Y417511D01*
G01X526039Y428050D02*
X513512D01*
X503199Y425987D01*
X452116Y436204D01*
X434717Y432725D01*
X418899Y435887D01*
X381499Y428408D01*
X364754Y431757D01*
X327600Y424326D01*
X294266Y430993D01*
X270359Y426209D01*
X251486Y413630D01*
X246277Y405816D01*
X235524Y352053D01*
X245393Y302703D01*
X243465Y293060D01*
X237880Y282625D01*
Y265133D01*
X235553Y253496D01*
X239204Y235247D01*
X237340Y225939D01*
X237339Y225935D01*
X214073Y191033D01*
X166403Y159250D01*
X157416Y156205D01*
X136366Y150000D01*
X113817D01*
X107472Y152350D01*
X100500Y153500D01*
X92103D01*
X82749Y156868D01*
X67466Y153812D01*
X66173Y152519D01*
Y151823D01*
X66523Y151473D01*
X68098D01*
G01X47309Y154356D02*
X48284D01*
X48734Y154806D01*
Y155910D01*
X49936Y157377D01*
X51349Y157910D01*
X67960Y160647D01*
X93035Y165664D01*
X100697Y163956D01*
X101970Y163507D01*
X102799Y163903D01*
X104072Y163454D01*
X104469Y162625D01*
X109717Y160772D01*
X110546Y161169D01*
X111819Y160720D01*
X112215Y159890D01*
X115890Y158593D01*
X119866Y156600D01*
X134945D01*
X163035Y165092D01*
X208739Y195561D01*
X231180Y229220D01*
X232208Y234360D01*
X228676Y252021D01*
X229817Y257730D01*
X227430Y265623D01*
Y276892D01*
X237590Y295878D01*
X238932Y302581D01*
X237928Y307604D01*
X230225Y319141D01*
Y322465D01*
X231725Y323965D01*
Y327876D01*
X231130Y328471D01*
Y340616D01*
X231066Y340871D01*
X228820Y352100D01*
X239980Y407906D01*
X248218Y420265D01*
X281216Y442254D01*
X327080Y451429D01*
X382326Y440379D01*
X395318Y442977D01*
X405701Y440900D01*
X483678Y456494D01*
X517207Y449777D01*
Y449778D01*
X517550Y449709D01*
X548934Y418325D01*
G01X63098Y151473D02*
X64673D01*
X65023Y151823D01*
Y152996D01*
X66899Y154872D01*
X82837Y158059D01*
X92305Y154650D01*
X100595D01*
X107768Y153467D01*
X114038Y151150D01*
X136200D01*
X157069Y157302D01*
X165891Y160291D01*
X213243Y191863D01*
X236257Y226388D01*
X238031Y235247D01*
X234380Y253496D01*
X236730Y265247D01*
Y275806D01*
X236080Y276456D01*
Y277806D01*
X236730Y278456D01*
Y282914D01*
X242370Y293453D01*
X244220Y302703D01*
X234351Y352053D01*
X245194Y406265D01*
X250656Y414460D01*
X269910Y427292D01*
X294266Y432166D01*
X327600Y425499D01*
X364754Y432930D01*
X381499Y429581D01*
X418899Y437060D01*
X421455Y436549D01*
X422219Y437059D01*
X423543Y436795D01*
X424053Y436030D01*
X425377Y435765D01*
X426142Y436275D01*
X427466Y436010D01*
X427976Y435246D01*
X434717Y433898D01*
X452113Y437378D01*
X452116Y437377D01*
X453440Y437112D01*
X454205Y437622D01*
X455528Y437357D01*
X456038Y436593D01*
X503199Y427160D01*
X513398Y429200D01*
X526039D01*
G01X60801Y102750D02*
X60831Y101275D01*
X61371Y100735D01*
X107510D01*
X108834Y101000D01*
X109344Y101765D01*
X110667Y102030D01*
X111432Y101520D01*
X112756Y101785D01*
X113266Y102550D01*
X114590Y102815D01*
X115354Y102305D01*
X116678Y102570D01*
X117188Y103335D01*
X118512Y103600D01*
X119277Y103090D01*
X120600Y103355D01*
X121110Y104120D01*
X122434Y104385D01*
X123199Y103875D01*
X127467Y104729D01*
X174037Y135808D01*
X180286Y145181D01*
X226671Y176107D01*
X254166Y217345D01*
X257864Y235833D01*
X254029Y255006D01*
X263597Y302852D01*
X263596D01*
X253867Y351503D01*
X263074Y397533D01*
X265447Y401095D01*
X275281Y407649D01*
X299812Y412555D01*
X329719Y406574D01*
X363609Y413352D01*
X386509Y408772D01*
X421239Y415720D01*
X438355Y412297D01*
X459470Y416520D01*
X504059Y407601D01*
X511314Y409057D01*
X513092D01*
G01X65384Y104750D02*
Y106225D01*
X65834Y106675D01*
X67432D01*
X69078Y107356D01*
X70679Y108960D01*
X74929D01*
X76064Y107825D01*
X110405D01*
X126615Y114540D01*
X127464Y114188D01*
X128711Y114704D01*
X129063Y115554D01*
X130310Y116070D01*
X131159Y115719D01*
X132407Y116235D01*
X132758Y117085D01*
X134006Y117601D01*
X134855Y117249D01*
X136102Y117766D01*
X136454Y118615D01*
X151795Y124970D01*
X155495Y128004D01*
X156410Y127913D01*
X157454Y128769D01*
X157544Y129684D01*
X158588Y130540D01*
X159503Y130450D01*
X160547Y131306D01*
X160637Y132220D01*
X161681Y133076D01*
X162596Y132986D01*
X163640Y133842D01*
X163731Y134757D01*
X175710Y144579D01*
X226201Y178252D01*
X252859Y218236D01*
X256433Y236100D01*
X252647Y255032D01*
X253500Y259297D01*
X262200Y302802D01*
X252431Y351652D01*
X261689Y397951D01*
Y397953D01*
X264780Y402591D01*
X274724Y409217D01*
X299067Y414085D01*
X329729Y407953D01*
X363609Y414729D01*
X385510Y410349D01*
X420245Y417298D01*
X436780Y413990D01*
X458188Y418272D01*
X504202Y409069D01*
X511269Y410506D01*
X512230D01*
G01X519871Y413375D02*
X512689D01*
X504546Y411749D01*
X456768Y421305D01*
X435252Y417000D01*
X420246Y420001D01*
X386000Y413150D01*
X364098Y417530D01*
X329365Y410583D01*
X296272Y417202D01*
X275466Y413040D01*
X263098Y404801D01*
X259128Y398842D01*
X249781Y352099D01*
X259639Y302805D01*
X250015Y254676D01*
X253692Y236290D01*
X250333Y219511D01*
X224046Y180081D01*
X164428Y140328D01*
X155320Y131220D01*
X150112Y129063D01*
X149760Y128214D01*
X148513Y127697D01*
X147663Y128049D01*
X146416Y127532D01*
X146064Y126683D01*
X144817Y126166D01*
X143968Y126518D01*
X142720Y126002D01*
X142369Y125152D01*
X141121Y124636D01*
X140272Y124988D01*
X139025Y124471D01*
X138673Y123622D01*
X137426Y123105D01*
X136577Y123457D01*
X128288Y120024D01*
X127936Y119175D01*
X126689Y118658D01*
X125840Y119010D01*
X124593Y118493D01*
X124241Y117644D01*
X122993Y117128D01*
X122144Y117479D01*
X115489Y114723D01*
X73528D01*
X70880Y113626D01*
X61150D01*
X60700Y113176D01*
Y111750D01*
G01X520860Y417359D02*
X512742D01*
X504328Y415677D01*
X455842Y425374D01*
X434162Y421037D01*
X420246Y423821D01*
X386000Y416970D01*
X364098Y421350D01*
X329131Y414356D01*
X296226Y420937D01*
X273671Y416429D01*
X259935Y407276D01*
X255825Y401111D01*
X246018Y352050D01*
X255847Y302901D01*
X246199Y254655D01*
X249795Y236672D01*
X249796D01*
X246597Y220698D01*
X246598D01*
X222075Y183919D01*
X160571Y142898D01*
X152146Y134474D01*
X150851Y133938D01*
X150001Y134290D01*
X148754Y133773D01*
X148402Y132924D01*
X147155Y132408D01*
X146306Y132759D01*
X145058Y132243D01*
X144706Y131394D01*
X143459Y130877D01*
X142610Y131229D01*
X141363Y130713D01*
X141011Y129864D01*
X139763Y129347D01*
X138914Y129699D01*
X137667Y129183D01*
X137315Y128333D01*
X125962Y123633D01*
X124638Y123368D01*
X123873Y123878D01*
X122550Y123613D01*
X122040Y122848D01*
X120716Y122584D01*
X119951Y123093D01*
X118627Y122829D01*
X118117Y122064D01*
X109600Y120360D01*
X106674Y118409D01*
X91718Y118445D01*
X91719D01*
X76763Y118481D01*
X68692Y121825D01*
X65835D01*
X65405Y122255D01*
Y123730D01*
G01X521664Y418942D02*
X511647D01*
X503308Y417277D01*
X454775Y426983D01*
X434093Y422845D01*
X420246Y425615D01*
X385999Y418764D01*
X364907Y422982D01*
X328896Y415780D01*
X295936Y422373D01*
X272906Y417769D01*
X258698Y408301D01*
X254380Y401820D01*
X244501Y352399D01*
X254430Y302752D01*
X244609Y253638D01*
X248145Y235955D01*
X245340Y221948D01*
X220735Y185045D01*
X156460Y142161D01*
X154174Y139875D01*
X121889Y126500D01*
X118659D01*
X112506Y123950D01*
X76225D01*
X67232Y127675D01*
X61281D01*
X60831Y127225D01*
Y125750D01*
G01X65687Y137750D02*
Y136275D01*
X66137Y135825D01*
X71274D01*
X72397Y134702D01*
Y132478D01*
X72847Y132028D01*
X74897D01*
X75347Y132478D01*
Y134702D01*
X76795Y136150D01*
X79493D01*
X96013Y129308D01*
X99496D01*
X119087Y137424D01*
X128982Y135412D01*
X140596Y140224D01*
X140948Y141073D01*
X142195Y141590D01*
X143045Y141238D01*
X144292Y141755D01*
X144643Y142604D01*
X145891Y143121D01*
X146740Y142769D01*
X147987Y143286D01*
X148339Y144135D01*
X149586Y144652D01*
X150435Y144300D01*
X151683Y144817D01*
X152034Y145666D01*
X153282Y146183D01*
X154131Y145831D01*
X155378Y146348D01*
X218581Y188508D01*
X241806Y223339D01*
X244212Y235341D01*
X240595Y253430D01*
X250537Y303150D01*
X240659Y352547D01*
X251043Y404514D01*
X254922Y410335D01*
X271159Y421155D01*
X295934Y426106D01*
X328125Y419668D01*
X364990Y427041D01*
X386203Y422799D01*
X420698Y429700D01*
X433354Y427168D01*
X452935Y431085D01*
X503052Y421062D01*
X514725Y423396D01*
X523118D01*
G01X60831Y139750D02*
Y141225D01*
X61304Y141698D01*
X64332D01*
X68988Y139770D01*
X74391D01*
X96309Y130927D01*
X99192D01*
X116440Y138229D01*
X128007Y141286D01*
X129322Y141731D01*
Y141732D01*
X163242Y153227D01*
X216352Y188659D01*
X240309Y224590D01*
X242424Y235142D01*
X238775Y253381D01*
X248900Y304000D01*
X239006Y353473D01*
X249171Y404356D01*
X253760Y411242D01*
X270697Y422530D01*
X270698D01*
X295721Y427528D01*
X328133Y421047D01*
X365216Y428464D01*
X385753Y424357D01*
X420050Y431217D01*
X432022Y428821D01*
X451664Y432750D01*
X502657Y422550D01*
X514492Y424917D01*
X524063D01*
G01X513092Y407907D02*
X511429D01*
X504059Y406428D01*
X459470Y415347D01*
X438355Y411124D01*
X421239Y414547D01*
X386509Y407599D01*
X363609Y412179D01*
X329719Y405401D01*
X299812Y411382D01*
X275730Y406566D01*
X266277Y400265D01*
X264158Y397086D01*
Y397084D01*
X255040Y351503D01*
X264770Y302852D01*
X255202Y255006D01*
X259037Y235833D01*
X255249Y216896D01*
X227501Y175277D01*
X181116Y144351D01*
X174867Y134978D01*
X127916Y103646D01*
X107624Y99585D01*
X61284D01*
X60829Y99139D01*
X60801Y97750D01*
G01X512230Y411656D02*
X511155D01*
X504200Y410243D01*
X458188Y419445D01*
X436780Y415163D01*
X420245Y418471D01*
X385510Y411522D01*
X363609Y415902D01*
X329729Y409126D01*
X299067Y415258D01*
X274275Y410301D01*
X263950Y403421D01*
X260605Y398400D01*
X251258Y351652D01*
X261027Y302802D01*
X251474Y255032D01*
X255260Y236100D01*
X251776Y218685D01*
X225371Y179082D01*
X200197Y162293D01*
Y162292D01*
X175024Y145505D01*
X151197Y125968D01*
X110176Y108975D01*
X76541D01*
X75406Y110110D01*
X70202D01*
X68426Y108331D01*
X67203Y107825D01*
X65834D01*
X65384Y108275D01*
Y109750D01*
G01X519871Y414525D02*
X512486D01*
X512464Y414503D01*
X504546Y412922D01*
X456768Y422478D01*
X435252Y418173D01*
X420246Y421174D01*
X386000Y414323D01*
X364098Y418703D01*
X329365Y411756D01*
X296272Y418375D01*
X275017Y414124D01*
X262268Y405631D01*
X258044Y399291D01*
X248608Y352099D01*
X258466Y302805D01*
X248842Y254676D01*
X252518Y236290D01*
X252519D01*
X249250Y219960D01*
X223216Y180911D01*
X163695Y141222D01*
X154668Y132196D01*
X115260Y115873D01*
X73299D01*
X70651Y114776D01*
X61199D01*
X60700Y115275D01*
Y116750D01*
G01X520860Y416209D02*
X512856D01*
X504328Y414504D01*
X455842Y424201D01*
X434162Y419864D01*
X420246Y422648D01*
X386000Y415797D01*
X364098Y420177D01*
X329131Y413183D01*
X296226Y419764D01*
X274120Y415345D01*
X260765Y406446D01*
X256908Y400662D01*
X247191Y352050D01*
X257020Y302901D01*
X247372Y254655D01*
X250969Y236672D01*
X247681Y220249D01*
X222905Y183089D01*
X161304Y142004D01*
X152798Y133498D01*
X126298Y122527D01*
X110049Y119277D01*
X107021Y117258D01*
X91716Y117295D01*
Y117294D01*
X76533Y117331D01*
X68463Y120674D01*
X68462Y120675D01*
X65875D01*
X65405Y120205D01*
Y118730D01*
G01X521664Y420092D02*
X511533D01*
X503308Y418450D01*
X454775Y428156D01*
X434093Y424018D01*
X420246Y426788D01*
X385999Y419937D01*
X364907Y424155D01*
X328896Y416953D01*
X295936Y423546D01*
X272457Y418853D01*
X257868Y409131D01*
X253296Y402269D01*
X243328Y352399D01*
X253257Y302752D01*
X243436Y253638D01*
X246972Y235955D01*
X244256Y222397D01*
X244257D01*
X219905Y185875D01*
X155727Y143055D01*
X153522Y140851D01*
X150566Y139626D01*
X149717Y139978D01*
X148470Y139461D01*
X148118Y138612D01*
X146871Y138095D01*
X146022Y138447D01*
X144774Y137930D01*
X144423Y137081D01*
X143176Y136564D01*
X142326Y136916D01*
X141079Y136399D01*
X140727Y135550D01*
X121660Y127650D01*
X118430D01*
X112277Y125100D01*
X76454D01*
X67461Y128825D01*
X61281D01*
X60831Y129275D01*
Y130750D01*
G01X65687Y132750D02*
Y134225D01*
X66137Y134675D01*
X70797D01*
X71247Y134225D01*
Y132001D01*
X72370Y130878D01*
X75374D01*
X76497Y132001D01*
Y134225D01*
X77272Y135000D01*
X79264D01*
X95784Y128158D01*
X99725D01*
X119202Y136226D01*
X129097Y134214D01*
X155923Y145328D01*
X219411Y187678D01*
X242889Y222890D01*
X245385Y235341D01*
X241768Y253430D01*
X251710Y303150D01*
X241832Y352547D01*
X252127Y404065D01*
Y404067D01*
X255752Y409505D01*
X271608Y420071D01*
X295934Y424933D01*
X328125Y418495D01*
X364990Y425868D01*
X386203Y421626D01*
X420698Y428527D01*
X433354Y425995D01*
X452935Y429912D01*
X503052Y419889D01*
X514839Y422246D01*
X523118D01*
G01X60831Y144750D02*
Y143332D01*
X61315Y142848D01*
X64561D01*
X69217Y140920D01*
X74615D01*
X96533Y132077D01*
X98958D01*
X116067Y139320D01*
X127675Y142388D01*
X128954Y142821D01*
X129361Y143646D01*
X130639Y144079D01*
X131463Y143672D01*
X132742Y144105D01*
X133149Y144929D01*
X134427Y145363D01*
X135252Y144956D01*
X147577Y149133D01*
X147984Y149957D01*
X149262Y150390D01*
X150086Y149983D01*
X151365Y150416D01*
X151772Y151241D01*
X153050Y151674D01*
X153875Y151267D01*
X155153Y151700D01*
X155560Y152525D01*
X156839Y152958D01*
X157663Y152551D01*
X158942Y152984D01*
X159349Y153808D01*
X160627Y154242D01*
X161451Y153835D01*
X162730Y154268D01*
X215522Y189489D01*
X239226Y225039D01*
X241251Y235142D01*
X241250D01*
X237602Y253381D01*
X247727Y304000D01*
X237833Y353473D01*
X248087Y404805D01*
X252930Y412072D01*
X270248Y423613D01*
X295721Y428701D01*
X328133Y422220D01*
X365216Y429637D01*
X385753Y425530D01*
X420050Y432390D01*
X432022Y429994D01*
X451664Y433923D01*
X502657Y423723D01*
X514378Y426067D01*
X524063D01*
G01X567029Y652238D02*
Y650263D01*
X566624Y649859D01*
X565504Y649911D01*
X564376Y648980D01*
X563799Y648211D01*
X563424Y646734D01*
X563089Y644824D01*
X562567Y644459D01*
X561533Y644641D01*
X561168Y645163D01*
X562652Y653570D01*
X561739Y654874D01*
X559766Y655223D01*
X558466Y654313D01*
X556781Y644763D01*
X556258Y644396D01*
X555225Y644578D01*
X554861Y645101D01*
X556353Y653555D01*
X555443Y654858D01*
X553469Y655204D01*
X552165Y654294D01*
X550486Y644760D01*
X549964Y644395D01*
X548931Y644576D01*
X548566Y645098D01*
X550057Y653554D01*
X549147Y654857D01*
X547173Y655203D01*
X545869Y654293D01*
X544187Y644741D01*
X543665Y644377D01*
X542632Y644558D01*
X542266Y645078D01*
X543766Y653587D01*
X542856Y654890D01*
X540882Y655237D01*
X539582Y654326D01*
X537891Y644744D01*
X537368Y644376D01*
X536334Y644559D01*
X535969Y645080D01*
X537469Y653588D01*
X536560Y654889D01*
X534587Y655237D01*
X533284Y654327D01*
X531615Y644857D01*
X531092Y644490D01*
X530059Y644671D01*
X529695Y645193D01*
X531172Y653570D01*
X530262Y654873D01*
X528289Y655218D01*
X526986Y654309D01*
X525317Y644853D01*
X524796Y644489D01*
X523764Y644671D01*
X523399Y645193D01*
X524877Y653568D01*
X523966Y654872D01*
X521992Y655218D01*
X520689Y654309D01*
X519022Y644837D01*
X518498Y644472D01*
X517466Y644652D01*
X517101Y645176D01*
X518587Y653601D01*
X517676Y654905D01*
X515702Y655251D01*
X514399Y654342D01*
X512733Y644885D01*
X512173Y644493D01*
X511205Y644663D01*
X510814Y645223D01*
X512291Y653601D01*
X511381Y654904D01*
X509408Y655251D01*
X508105Y654341D01*
X506467Y645081D01*
X505945Y644716D01*
X504911Y644898D01*
X504547Y645420D01*
X506024Y653798D01*
X505087Y655140D01*
X503179Y655475D01*
X501839Y654536D01*
X500173Y645080D01*
X499651Y644716D01*
X498616Y644898D01*
X498251Y645420D01*
X499737Y653844D01*
X498826Y655151D01*
X496855Y655495D01*
X495549Y654586D01*
X493883Y645113D01*
X493361Y644749D01*
X492326Y644931D01*
X491961Y645453D01*
X493439Y653828D01*
X492528Y655132D01*
X490557Y655479D01*
X489255Y654569D01*
X487586Y645113D01*
X487064Y644749D01*
X486030Y644930D01*
X485666Y645451D01*
X487143Y653827D01*
X486233Y655132D01*
X484259Y655478D01*
X482956Y654564D01*
X481288Y645095D01*
X480766Y644730D01*
X479732Y644913D01*
X479369Y645435D01*
X480869Y653942D01*
X479957Y655243D01*
X477983Y655592D01*
X476680Y654676D01*
X474990Y645095D01*
X474470Y644731D01*
X473436Y644913D01*
X473072Y645434D01*
X474572Y653945D01*
X473657Y655245D01*
X471688Y655590D01*
X470385Y654681D01*
X468702Y645129D01*
X468179Y644764D01*
X467145Y644946D01*
X466781Y645467D01*
X468272Y653923D01*
X467360Y655227D01*
X465388Y655572D01*
X464085Y654662D01*
X462407Y645128D01*
X461884Y644763D01*
X460849Y644945D01*
X460485Y645466D01*
X461977Y653919D01*
X461068Y655224D01*
X459094Y655572D01*
X457790Y654658D01*
X456106Y645108D01*
X455587Y644745D01*
X454553Y644928D01*
X454186Y645452D01*
X455670Y653858D01*
X454759Y655162D01*
X452785Y655509D01*
X451484Y654597D01*
X451072Y652260D01*
X450903Y651594D01*
X450141Y650578D01*
X449511Y650099D01*
X449033D01*
X448593Y650539D01*
Y652514D01*
G01X567029Y646238D02*
Y648213D01*
X566531Y648711D01*
X565894Y648741D01*
X565215Y648180D01*
X564858Y647704D01*
X564550Y646492D01*
X564139Y644155D01*
X562837Y643243D01*
X560863Y643590D01*
X559952Y644894D01*
X561436Y653300D01*
X561069Y653824D01*
X560035Y654007D01*
X559516Y653644D01*
X557832Y644094D01*
X556528Y643180D01*
X554554Y643528D01*
X553645Y644833D01*
X555137Y653286D01*
X554773Y653807D01*
X553738Y653989D01*
X553215Y653624D01*
X551537Y644090D01*
X550234Y643180D01*
X548262Y643525D01*
X547350Y644829D01*
X548841Y653285D01*
X548477Y653806D01*
X547443Y653988D01*
X546920Y653623D01*
X545237Y644071D01*
X543934Y643162D01*
X541965Y643507D01*
X541050Y644807D01*
X542550Y653318D01*
X542186Y653839D01*
X541152Y654021D01*
X540632Y653657D01*
X538942Y644076D01*
X537639Y643160D01*
X535665Y643509D01*
X534753Y644810D01*
X536253Y653317D01*
X535890Y653839D01*
X534856Y654022D01*
X534334Y653657D01*
X532666Y644188D01*
X531363Y643274D01*
X529389Y643620D01*
X528479Y644925D01*
X529956Y653301D01*
X529592Y653822D01*
X528558Y654003D01*
X528036Y653639D01*
X526367Y644183D01*
X525065Y643273D01*
X523094Y643620D01*
X522183Y644924D01*
X523661Y653299D01*
X523296Y653821D01*
X522261Y654003D01*
X521739Y653639D01*
X520073Y644166D01*
X518767Y643257D01*
X516796Y643601D01*
X515885Y644908D01*
X517371Y653332D01*
X517006Y653854D01*
X515971Y654036D01*
X515449Y653672D01*
X513783Y644216D01*
X512443Y643277D01*
X510535Y643612D01*
X509598Y644954D01*
X511075Y653332D01*
X510711Y653854D01*
X509677Y654036D01*
X509155Y653671D01*
X507517Y644411D01*
X506214Y643501D01*
X504241Y643848D01*
X503331Y645151D01*
X504808Y653529D01*
X504417Y654089D01*
X503449Y654259D01*
X502889Y653867D01*
X501223Y644410D01*
X499920Y643501D01*
X497946Y643847D01*
X497035Y645151D01*
X498521Y653576D01*
X498156Y654100D01*
X497124Y654280D01*
X496600Y653915D01*
X494933Y644443D01*
X493630Y643534D01*
X491656Y643880D01*
X490745Y645184D01*
X492223Y653559D01*
X491858Y654081D01*
X490826Y654263D01*
X490305Y653899D01*
X488636Y644443D01*
X487333Y643534D01*
X485360Y643879D01*
X484450Y645182D01*
X485927Y653559D01*
X485563Y654081D01*
X484530Y654262D01*
X484007Y653895D01*
X482338Y644425D01*
X481035Y643515D01*
X479062Y643863D01*
X478153Y645164D01*
X479653Y653672D01*
X479288Y654193D01*
X478254Y654376D01*
X477731Y654008D01*
X476040Y644426D01*
X474740Y643515D01*
X472766Y643862D01*
X471856Y645165D01*
X473356Y653674D01*
X472990Y654194D01*
X471957Y654375D01*
X471435Y654011D01*
X469753Y644459D01*
X468449Y643549D01*
X466475Y643895D01*
X465565Y645198D01*
X467056Y653654D01*
X466691Y654176D01*
X465658Y654357D01*
X465136Y653992D01*
X463457Y644458D01*
X462153Y643548D01*
X460179Y643894D01*
X459269Y645197D01*
X460761Y653651D01*
X460397Y654174D01*
X459364Y654356D01*
X458841Y653989D01*
X457156Y644439D01*
X455856Y643529D01*
X453883Y643878D01*
X452970Y645182D01*
X454454Y653589D01*
X454089Y654111D01*
X453055Y654293D01*
X452534Y653928D01*
X452198Y652018D01*
X451962Y651088D01*
X450965Y649759D01*
X449899Y648949D01*
X449053D01*
X448593Y648489D01*
Y646514D01*
G01X498800Y205800D02*
Y188228D01*
X516799Y170229D01*
X524701Y160823D01*
X552606Y149557D01*
X582732Y150671D01*
X647565Y135226D01*
X667354Y133930D01*
X680186Y124633D01*
X689985Y121463D01*
X689986Y121462D01*
X706967Y122181D01*
X760898Y124464D01*
X769215Y127280D01*
X784463Y123299D01*
X836501Y136480D01*
X875578Y133552D01*
X932603Y129278D01*
X933307Y129308D01*
X950891Y131559D01*
X964648Y125470D01*
X990300D01*
X1012267Y134572D01*
X1021074Y137213D01*
X1029779Y138885D01*
X1041766Y135295D01*
X1110681Y146143D01*
Y146144D01*
X1110870Y146173D01*
X1142885Y140586D01*
X1158125Y143682D01*
X1168921Y150939D01*
X1179966Y167501D01*
X1183943Y172685D01*
X1183833Y173527D01*
X1184654Y174599D01*
X1185497Y174709D01*
X1186318Y175780D01*
X1186208Y176622D01*
X1187029Y177694D01*
X1187870Y177804D01*
X1188693Y178877D01*
X1188582Y179716D01*
X1189404Y180788D01*
X1190244Y180899D01*
X1191188Y182129D01*
X1191077Y182969D01*
X1191898Y184041D01*
X1192741Y184151D01*
X1193562Y185222D01*
X1194630Y187952D01*
X1194731Y188210D01*
X1194630Y188441D01*
X1194391Y188988D01*
X1194630Y189600D01*
X1194882Y190246D01*
X1195661Y190586D01*
X1196152Y191843D01*
X1195812Y192621D01*
X1196303Y193879D01*
X1197082Y194219D01*
X1197573Y195476D01*
X1198105Y197011D01*
X1197734Y197775D01*
X1198176Y199051D01*
X1198941Y199422D01*
X1200618Y204262D01*
X1200247Y205026D01*
X1200689Y206302D01*
X1201454Y206673D01*
X1203172Y211634D01*
Y213108D01*
G01X494692Y220096D02*
X493431Y218835D01*
X492212D01*
X490924Y217547D01*
Y213435D01*
X494806Y198695D01*
X494807Y198694D01*
Y185894D01*
X513644Y167057D01*
X520519Y158392D01*
X552683Y145143D01*
X577720Y146329D01*
X639547Y131562D01*
X666704Y129414D01*
X678770Y120764D01*
X689006Y117454D01*
X760628Y120487D01*
X769169Y123118D01*
X783919Y119085D01*
X835922Y132555D01*
Y132556D01*
X875578Y129612D01*
X933264Y125330D01*
X934147Y125402D01*
X950171Y127575D01*
X963394Y121820D01*
X991643D01*
X1007728Y128484D01*
X1020327Y132776D01*
X1029535Y134954D01*
X1041707Y131447D01*
X1110931Y142302D01*
X1112226Y142101D01*
X1142018Y136575D01*
X1159364Y140039D01*
X1171755Y148334D01*
X1176997Y156195D01*
X1198068Y179971D01*
X1209453Y205931D01*
X1207129Y215490D01*
Y216837D01*
G01X497650Y205800D02*
Y187750D01*
X515950Y169450D01*
X524004Y159863D01*
X552403Y148398D01*
X582618Y149515D01*
X647393Y134084D01*
X666948Y132804D01*
X679658Y123594D01*
X689829Y120304D01*
X706967Y121030D01*
X761111Y123321D01*
X769258Y126080D01*
X784459Y122111D01*
X836603Y135319D01*
X875578Y132398D01*
X932584Y128126D01*
X933405Y128161D01*
X950719Y130377D01*
X964404Y124320D01*
X990529D01*
X1012653Y133487D01*
X1021349Y136094D01*
X1029719Y137702D01*
X1041687Y134118D01*
X1110860Y145007D01*
X1142901Y139415D01*
X1158577Y142600D01*
X1169752Y150111D01*
X1180902Y166831D01*
X1194574Y184651D01*
X1194630Y184794D01*
X1198662Y195100D01*
X1204322Y211437D01*
Y213108D01*
G01X494692Y216196D02*
X493203Y217685D01*
X492689D01*
X492074Y217070D01*
Y213584D01*
X495957Y198844D01*
Y186371D01*
X514504Y167825D01*
Y167824D01*
X521234Y159342D01*
X552884Y146304D01*
X577829Y147486D01*
X639727Y132702D01*
X667114Y130536D01*
X679295Y121804D01*
X689163Y118613D01*
Y118612D01*
X760431Y121630D01*
X769150Y124316D01*
X783927Y120276D01*
X835818Y133717D01*
X875578Y130766D01*
X933260Y126484D01*
X934023Y126546D01*
X950335Y128758D01*
X963634Y122970D01*
X991414D01*
X1007322Y129561D01*
X1020008Y133883D01*
X1029564Y136143D01*
X1041781Y132623D01*
X1110930Y143466D01*
X1112418Y143236D01*
X1142010Y137747D01*
X1158914Y141122D01*
X1170924Y149163D01*
X1176084Y156899D01*
X1181565Y163084D01*
X1181514Y163931D01*
X1182409Y164942D01*
X1183257Y164993D01*
X1184152Y166003D01*
X1184101Y166850D01*
X1184996Y167861D01*
X1185844Y167912D01*
X1186739Y168922D01*
X1186688Y169769D01*
X1187583Y170780D01*
X1188431Y170831D01*
X1189326Y171841D01*
X1189275Y172688D01*
X1190170Y173699D01*
X1191018Y173750D01*
X1191913Y174760D01*
X1191862Y175607D01*
X1192757Y176618D01*
X1193605Y176669D01*
X1194500Y177679D01*
X1194449Y178526D01*
X1194630Y178730D01*
X1195344Y179537D01*
X1196192Y179588D01*
X1197087Y180598D01*
X1198780Y184460D01*
X1198472Y185250D01*
X1199014Y186488D01*
X1199805Y186796D01*
X1200347Y188032D01*
X1200038Y188822D01*
X1200580Y190059D01*
X1201371Y190368D01*
X1201913Y191604D01*
X1201604Y192394D01*
X1202146Y193631D01*
X1202937Y193940D01*
X1203479Y195176D01*
X1203171Y195966D01*
X1203713Y197204D01*
X1204504Y197512D01*
X1205046Y198748D01*
X1204738Y199538D01*
X1205280Y200776D01*
X1206071Y201084D01*
X1206613Y202320D01*
X1206304Y203111D01*
X1206846Y204348D01*
X1207638Y204657D01*
X1208243Y206037D01*
X1205979Y215352D01*
Y216837D01*
G01X1162591Y204687D02*
Y201893D01*
X1154254Y190308D01*
X1145641Y184064D01*
X1134819Y180492D01*
X1133896Y180187D01*
X1129036Y178893D01*
X1041227Y157622D01*
X1029788Y161142D01*
X1015647Y159213D01*
X982744Y145592D01*
X970942D01*
X956180Y153893D01*
X931237Y150634D01*
X875578Y155162D01*
X834343Y158517D01*
X783781Y145623D01*
X776123Y147858D01*
Y147857D01*
X767787Y150291D01*
X755837Y145671D01*
Y145672D01*
X740605Y145073D01*
X718117Y149412D01*
X710880Y150809D01*
X704578Y154078D01*
X683500Y166600D01*
X672900Y168900D01*
X656895Y167578D01*
X637147Y167881D01*
X630581Y169342D01*
X613832Y166861D01*
X577319Y175423D01*
X565066Y175703D01*
X564480Y176318D01*
X563130Y176349D01*
X562516Y175763D01*
X560633Y175805D01*
X557443Y176890D01*
X557069Y177651D01*
X555790Y178086D01*
X555029Y177712D01*
X553699Y178164D01*
X553326Y178925D01*
X552047Y179360D01*
X551285Y178986D01*
X549732Y179514D01*
X549357Y180276D01*
X548078Y180711D01*
X547317Y180337D01*
X546039Y180771D01*
X545665Y181533D01*
X544386Y181968D01*
X543624Y181594D01*
X542347Y182028D01*
X541973Y182790D01*
X540694Y183225D01*
X539932Y182850D01*
X538655Y183285D01*
X527823Y194117D01*
G01X1165424Y204115D02*
Y199074D01*
X1156081Y187543D01*
X1147540Y181762D01*
X1138844Y178834D01*
X1134400Y177634D01*
X1041162Y154824D01*
X1030544Y158268D01*
X1016610Y156321D01*
X1003039Y151035D01*
X983807Y143068D01*
X970285D01*
X955801Y150920D01*
X931475Y148104D01*
X875578Y152562D01*
X834542Y155835D01*
X784174Y142823D01*
X767604Y147360D01*
X756698Y143070D01*
X740183Y142411D01*
X710130Y148141D01*
X682700Y163700D01*
X672500Y165300D01*
X657035Y164529D01*
X637852Y164823D01*
X629381Y166548D01*
X614601Y164400D01*
X613721Y164301D01*
X578800Y172152D01*
X569082Y171989D01*
X568587Y172469D01*
X567235Y172445D01*
X566756Y171949D01*
X565406Y171925D01*
X564911Y172405D01*
X563559Y172381D01*
X563080Y171885D01*
X561612Y171859D01*
X560474Y171860D01*
X556244Y173302D01*
X555870Y174064D01*
X554591Y174499D01*
X553829Y174125D01*
X552552Y174560D01*
X552178Y175323D01*
X550899Y175758D01*
X550137Y175384D01*
X548860Y175819D01*
X548486Y176581D01*
X547207Y177017D01*
X546800Y176817D01*
X546445Y176643D01*
X545168Y177078D01*
X544794Y177840D01*
X543515Y178276D01*
X542753Y177902D01*
X541476Y178337D01*
X541102Y179099D01*
X539823Y179535D01*
X539061Y179161D01*
X537784Y179596D01*
X520907Y196473D01*
Y202056D01*
G01X1170175Y203464D02*
Y197793D01*
X1160258Y185363D01*
X1160173Y185267D01*
X1159630Y184724D01*
X1148594Y177849D01*
X1143369Y176066D01*
X1041029Y150794D01*
X1030656Y154297D01*
X1017399Y152460D01*
X1002839Y146899D01*
X984721Y139395D01*
X969402D01*
X954498Y147010D01*
X931903Y144365D01*
X875578Y148571D01*
X834034Y151674D01*
X784086Y138933D01*
X768082Y143420D01*
X757046Y139166D01*
X740044Y138487D01*
X708438Y144540D01*
X680098Y160238D01*
X672761Y160850D01*
X665336D01*
X663265Y160880D01*
X637280D01*
X629345Y162268D01*
X613587Y160493D01*
X581866Y167414D01*
X557925Y167178D01*
X535760Y175691D01*
X516301Y195151D01*
Y200882D01*
G01X1172149Y201226D02*
Y195849D01*
X1162932Y184273D01*
X1149115Y176281D01*
X1145436Y175043D01*
X1041114Y149244D01*
X1030470Y152810D01*
X1017950Y151131D01*
X1004751Y146009D01*
X985438Y138008D01*
X969104D01*
X954098Y145256D01*
X932158Y142801D01*
X875578Y147098D01*
X834594Y150210D01*
X783714Y137412D01*
X768151Y141768D01*
X757404Y137790D01*
X739258Y137066D01*
X709480Y142682D01*
X709347Y142722D01*
X706485Y144028D01*
Y144030D01*
X703555Y145368D01*
X680400Y158300D01*
X674800Y159200D01*
X670600Y159050D01*
X665309D01*
X636703Y159463D01*
X629196Y160528D01*
X613172Y159093D01*
X583105Y165493D01*
X564326Y164988D01*
X563710Y165572D01*
X562360Y165536D01*
X561776Y164919D01*
X560427Y164883D01*
X559811Y165467D01*
X558461Y165431D01*
X557877Y164814D01*
X556528Y164778D01*
X554065Y165769D01*
X553732Y166550D01*
X552479Y167054D01*
X551699Y166723D01*
X550445Y167226D01*
X550113Y168007D01*
X548860Y168511D01*
X548080Y168179D01*
X546826Y168683D01*
X546800Y168744D01*
X546495Y169464D01*
X545241Y169968D01*
X544461Y169635D01*
X543209Y170139D01*
X542877Y170921D01*
X541623Y171425D01*
X540843Y171092D01*
X539591Y171596D01*
X539259Y172378D01*
X538005Y172882D01*
X537225Y172549D01*
X535973Y173053D01*
X514046Y194980D01*
Y203996D01*
G01X1176934Y199797D02*
Y197460D01*
X1170057Y178909D01*
X1170047Y178879D01*
X1163780Y161973D01*
X1159640Y155765D01*
X1154662Y152501D01*
X1141578Y150377D01*
X1111315Y155659D01*
X1041168Y145135D01*
X1029935Y148880D01*
X1017857Y147190D01*
X986840Y134320D01*
X968346D01*
X953405Y141404D01*
X931909Y138860D01*
X875578Y143190D01*
X875288Y143212D01*
X834759Y146328D01*
X783579Y133526D01*
X782187Y133873D01*
X768555Y137752D01*
X758543Y134164D01*
X738581Y133371D01*
X708763Y138988D01*
X708497Y139071D01*
X701274Y142368D01*
X701196Y142408D01*
X679186Y154559D01*
X667463Y154938D01*
X666325Y154951D01*
X635127Y155305D01*
X629450Y156219D01*
X628654Y156363D01*
X614178Y155382D01*
X612725Y155399D01*
X586205Y160671D01*
X586187Y160675D01*
Y160674D01*
X586186Y160675D01*
X586174Y160677D01*
X581836Y161543D01*
X581134Y161505D01*
X555674Y160662D01*
X533980Y169119D01*
X509002Y194097D01*
Y205003D01*
G01X1180994Y196766D02*
Y193582D01*
X1169258Y164857D01*
X1162297Y154410D01*
X1155666Y149968D01*
X1142371Y147584D01*
X1111493Y153010D01*
X1041429Y142244D01*
X1029356Y146183D01*
X1017604Y144269D01*
X987542Y131820D01*
X967218D01*
X952893Y138763D01*
X931972Y136306D01*
X875578Y140483D01*
X834886Y143497D01*
X783453Y130773D01*
X768627Y134974D01*
X758801Y131587D01*
X738186Y130767D01*
X707140Y135884D01*
X706831Y135980D01*
X691240Y143418D01*
X691132Y143478D01*
X678261Y151419D01*
X675854Y151954D01*
X670660Y152136D01*
X669898D01*
X634230Y152545D01*
X628120Y153692D01*
X614602Y152767D01*
X612541Y152791D01*
X584681Y158275D01*
X581418D01*
X554805Y157439D01*
X532381Y166484D01*
X505677Y193118D01*
Y205358D01*
G01X1183489Y191921D02*
Y190314D01*
X1182929Y189086D01*
X1182133Y188789D01*
X1181573Y187560D01*
X1181870Y186765D01*
X1181310Y185537D01*
X1180514Y185241D01*
X1179954Y184011D01*
X1180251Y183216D01*
X1179691Y181988D01*
X1178895Y181692D01*
X1178335Y180462D01*
X1178632Y179667D01*
X1178072Y178439D01*
X1177276Y178143D01*
X1176716Y176913D01*
X1177012Y176118D01*
X1176452Y174890D01*
X1175656Y174594D01*
X1175096Y173364D01*
X1175393Y172569D01*
X1174833Y171341D01*
X1174037Y171045D01*
X1173477Y169815D01*
X1173773Y169020D01*
X1172431Y166078D01*
X1171683Y164955D01*
X1170850Y164789D01*
X1170101Y163664D01*
X1170268Y162832D01*
X1164572Y154286D01*
X1156112Y148622D01*
X1141941Y146050D01*
X1110833Y151479D01*
X1041355Y140758D01*
Y140759D01*
X1029363Y144698D01*
X1018171Y142807D01*
X987755Y130470D01*
X966843D01*
X952060Y137110D01*
X932033Y134705D01*
X875578Y138943D01*
X837626Y141792D01*
X834898Y142056D01*
X784313Y129110D01*
X768558Y133350D01*
X760200Y130054D01*
X737853Y129143D01*
X703956Y133014D01*
X703681Y133066D01*
X669000Y142727D01*
X664822Y146905D01*
X657662Y147601D01*
X647140Y148624D01*
X627309Y151880D01*
X614887Y151102D01*
X613325Y151122D01*
X583679Y156788D01*
X554349Y155553D01*
X531695Y164472D01*
X503962Y192204D01*
Y205301D01*
G01X1193191Y197020D02*
X1192200Y195375D01*
X1188026Y188063D01*
X1180411Y171268D01*
X1167351Y151672D01*
X1157278Y144922D01*
X1142442Y142196D01*
X1110562Y147701D01*
X1041517Y136827D01*
X1029994Y140520D01*
X1018592Y138544D01*
X1008869Y135003D01*
X989117Y126820D01*
X965415D01*
X951492Y133288D01*
X932681Y130962D01*
X932193Y130943D01*
X835188Y138296D01*
X784728Y125065D01*
X768687Y129135D01*
Y129134D01*
X760104Y125854D01*
X716289Y124241D01*
X666000Y137620D01*
X654826Y138332D01*
X644570Y141310D01*
X639921Y142295D01*
X632679Y145325D01*
X629634Y145417D01*
X629542Y145425D01*
X610658Y147508D01*
X582853Y152872D01*
Y152871D01*
X554013Y151336D01*
X529991Y160749D01*
X525613Y162658D01*
X518705Y170783D01*
X500246Y189236D01*
Y205672D01*
G01X1145284Y207769D02*
Y206879D01*
X1144584Y206179D01*
Y205289D01*
X1145284Y204589D01*
Y203699D01*
X1144584Y202999D01*
Y202109D01*
X1145284Y201409D01*
Y198916D01*
X1138520Y194211D01*
X1125129Y188626D01*
X1041509Y168943D01*
X1031164Y171872D01*
X1011361Y169843D01*
X1010600Y169792D01*
X976222Y175379D01*
X948804Y169738D01*
X933166Y161415D01*
X875578Y166184D01*
X835375Y169513D01*
X784521Y157054D01*
X750448Y169722D01*
X725351Y168833D01*
X715234Y167173D01*
X664039Y185555D01*
X648499Y188478D01*
X628450Y183893D01*
X614596Y178156D01*
X567612Y188790D01*
X561034Y191515D01*
X560744Y192216D01*
X559625Y192678D01*
X558926Y192389D01*
X556727Y193300D01*
X556354Y194202D01*
X555522Y194547D01*
X554620Y194174D01*
X553622Y194587D01*
X553249Y195489D01*
X552416Y195834D01*
X551515Y195460D01*
X549509Y196291D01*
X548207Y197593D01*
Y198570D01*
X547570Y199207D01*
X546593D01*
X545100Y200700D01*
G01X1152625Y208465D02*
Y206442D01*
X1149048Y196608D01*
X1140327Y190128D01*
X1140030Y189967D01*
X1127226Y185367D01*
X1041885Y165002D01*
X1030403Y168053D01*
X1012917Y165697D01*
X979805Y151983D01*
X972876D01*
X957675Y161260D01*
X932624Y157443D01*
X875578Y162348D01*
X835937Y165757D01*
X784276Y152936D01*
X751105Y165269D01*
X739842Y160924D01*
X713176Y163612D01*
X662270Y182179D01*
X649038Y184709D01*
X629336Y180266D01*
X614477Y174114D01*
X568282Y184738D01*
X543027Y191696D01*
X542557Y192251D01*
X541116Y192984D01*
G01X1154885Y209371D02*
Y205785D01*
X1154285Y205185D01*
Y203835D01*
X1154885Y203235D01*
Y201885D01*
X1154090Y200795D01*
X1153250Y200664D01*
X1152455Y199572D01*
X1152586Y198734D01*
X1150528Y195914D01*
X1149293Y194408D01*
X1147967Y193328D01*
X1147123Y193414D01*
X1146076Y192561D01*
X1145989Y191716D01*
X1142556Y188919D01*
X1127177Y183845D01*
X1041208Y163342D01*
X1031370Y166196D01*
X1030394Y166508D01*
X1013309Y164147D01*
X980657Y150624D01*
X972381D01*
X957412Y159638D01*
X931567Y155864D01*
X840854Y163844D01*
X836089Y164355D01*
X784179Y151249D01*
X765392Y156647D01*
X754835Y152688D01*
X743350Y154428D01*
X741294Y155249D01*
X717490Y161741D01*
X713762Y161979D01*
X690771Y170262D01*
X688763Y170986D01*
X665584Y179338D01*
Y179339D01*
X662147Y180578D01*
X648396Y183039D01*
X629639Y178875D01*
X615394Y172901D01*
X614670Y172620D01*
X613197Y172916D01*
X568587Y182791D01*
X558272Y184184D01*
X556996Y184624D01*
X556625Y185388D01*
X555348Y185828D01*
X554585Y185456D01*
X553309Y185896D01*
X552938Y186660D01*
X551661Y187100D01*
X550898Y186728D01*
X549429Y187234D01*
X549057Y187998D01*
X547780Y188439D01*
X547017Y188067D01*
X546800Y188142D01*
X545353Y188641D01*
X544981Y189405D01*
X543704Y189845D01*
X542941Y189473D01*
X540291Y190387D01*
X534388Y195876D01*
Y200588D01*
G01X1158279Y206300D02*
Y201237D01*
X1152599Y193657D01*
X1151159Y191849D01*
X1143653Y186252D01*
X1134014Y183068D01*
X1118077Y178929D01*
X1041757Y160560D01*
X1030134Y163852D01*
X1014265Y161697D01*
X981437Y148101D01*
X971647D01*
X956645Y156889D01*
X947197Y155401D01*
X931279Y153275D01*
X875578Y157992D01*
X835458Y161389D01*
X784031Y148489D01*
X767942Y153048D01*
X754999Y148177D01*
X741710Y147666D01*
X710938Y153574D01*
X683888Y169558D01*
X676721Y172461D01*
X676691Y172474D01*
X668176Y175546D01*
X666223Y176251D01*
X660889Y178176D01*
X649228Y180378D01*
X633803Y177121D01*
X631542Y176703D01*
X614056Y169516D01*
X574346Y178827D01*
X565458Y179290D01*
X564890Y179921D01*
X563541Y179991D01*
X562911Y179423D01*
X561563Y179493D01*
X558075Y180624D01*
X557690Y181380D01*
X556404Y181797D01*
X555649Y181411D01*
X554365Y181827D01*
X553980Y182583D01*
X552694Y183000D01*
X551939Y182614D01*
X550655Y183030D01*
X550270Y183786D01*
X548984Y184203D01*
X548229Y183817D01*
X546945Y184233D01*
X546560Y184989D01*
X545274Y185406D01*
X544519Y185020D01*
X543235Y185436D01*
X542850Y186192D01*
X541564Y186609D01*
X540809Y186223D01*
X539525Y186639D01*
X538888Y186881D01*
X535083Y190418D01*
X533377Y192124D01*
G01X1163741Y204736D02*
Y201522D01*
X1155080Y189485D01*
X1146172Y183027D01*
X1134819Y179280D01*
X1134224Y179084D01*
X1129319Y177778D01*
X1041191Y156429D01*
X1029692Y159968D01*
X1015950Y158093D01*
X982973Y144442D01*
X970640D01*
X955950Y152702D01*
X931265Y149477D01*
X875578Y154006D01*
X834432Y157352D01*
X783761Y144430D01*
X767839Y149077D01*
X761956Y146803D01*
Y146804D01*
X756073Y144529D01*
X740517Y143918D01*
X717900Y148283D01*
X710498Y149711D01*
X704019Y153072D01*
X683073Y165515D01*
X672824Y167739D01*
X656989Y166431D01*
X637012Y166732D01*
X630539Y168173D01*
X613783Y165691D01*
X577173Y174276D01*
X560427Y174659D01*
X538031Y182282D01*
X527010Y193303D01*
G01X1166574Y204115D02*
Y198666D01*
X1156867Y186686D01*
X1148056Y180721D01*
X1139178Y177733D01*
X1134819Y176556D01*
X1134687Y176520D01*
X1041118Y153629D01*
X1030441Y157092D01*
X1016902Y155200D01*
X1003468Y149967D01*
X984036Y141918D01*
X969993D01*
X955572Y149735D01*
X931496Y146948D01*
X875578Y151408D01*
X834643Y154673D01*
X784165Y141632D01*
X767669Y146149D01*
X756938Y141928D01*
X740097Y141256D01*
X709728Y147046D01*
X682315Y162596D01*
X672439Y164145D01*
X657092Y163380D01*
X651621Y163461D01*
X637727Y163674D01*
X629348Y165381D01*
X614747Y163259D01*
X613657Y163136D01*
X578682Y170999D01*
X561621Y170708D01*
X560473Y170710D01*
X560281D01*
X537159Y178593D01*
X519757Y195996D01*
Y201956D01*
G01X517451Y200882D02*
Y195628D01*
X536401Y176678D01*
X537661Y176194D01*
X538436Y176539D01*
X539697Y176055D01*
X540042Y175279D01*
X541302Y174795D01*
X542077Y175140D01*
X543338Y174656D01*
X543683Y173880D01*
X544943Y173397D01*
X545718Y173742D01*
X546800Y173327D01*
X546979Y173258D01*
X547324Y172481D01*
X548584Y171998D01*
X549359Y172343D01*
X550620Y171859D01*
X550965Y171083D01*
X552225Y170600D01*
X553000Y170945D01*
X554261Y170461D01*
X554606Y169685D01*
X558133Y168331D01*
X559482Y168344D01*
X560076Y168951D01*
X561427Y168964D01*
X562033Y168370D01*
X563382Y168383D01*
X563977Y168990D01*
X565327Y169003D01*
X565933Y168409D01*
X581984Y168566D01*
X613647Y161658D01*
X629381Y163430D01*
X637380Y162030D01*
X663274D01*
X665345Y162000D01*
X672809D01*
X680440Y161364D01*
X708835Y145635D01*
X740130Y139642D01*
X756810Y140308D01*
X768025Y144631D01*
X784100Y140124D01*
X833932Y152835D01*
X875578Y149725D01*
X931879Y145521D01*
X954711Y148193D01*
X969679Y140545D01*
X984492D01*
X1002414Y147968D01*
X1017111Y153582D01*
X1030767Y155474D01*
X1041079Y151991D01*
X1143045Y177171D01*
X1148098Y178895D01*
X1158909Y185631D01*
X1159345Y186067D01*
X1169025Y198200D01*
Y203464D01*
G01X1173299Y201226D02*
Y195447D01*
X1163696Y183386D01*
X1149591Y175227D01*
X1145758Y173937D01*
X1041066Y148047D01*
X1030358Y151634D01*
X1018238Y150009D01*
X1005180Y144941D01*
X985667Y136858D01*
X968840D01*
X953896Y144076D01*
X932179Y141646D01*
X875578Y145944D01*
X834693Y149049D01*
X783698Y136222D01*
X768200Y140559D01*
X757632Y136648D01*
X739173Y135911D01*
X709202Y141563D01*
X708937Y141645D01*
X703077Y144320D01*
X702994Y144364D01*
X680016Y157196D01*
X674729Y158046D01*
X670641Y157900D01*
X665300D01*
X636613Y158314D01*
X629166Y159370D01*
X613102Y157932D01*
X582999Y164339D01*
X556320Y163621D01*
X535325Y172073D01*
X512896Y194502D01*
Y203996D01*
G01X1175784Y199797D02*
Y197670D01*
X1173035Y190251D01*
X1172263Y189897D01*
X1171794Y188631D01*
X1172148Y187860D01*
X1171679Y186595D01*
X1170907Y186241D01*
X1170438Y184974D01*
X1170792Y184203D01*
X1170323Y182938D01*
X1169551Y182584D01*
X1169082Y181317D01*
X1169436Y180546D01*
X1168977Y179311D01*
X1168967Y179281D01*
X1168195Y178927D01*
X1167726Y177660D01*
X1168080Y176889D01*
X1167611Y175624D01*
X1166839Y175269D01*
X1166370Y174003D01*
X1166724Y173231D01*
X1166256Y171966D01*
X1165483Y171611D01*
X1165014Y170344D01*
X1165369Y169573D01*
X1164900Y168308D01*
X1164128Y167953D01*
X1163659Y166687D01*
X1164014Y165915D01*
X1162748Y162499D01*
X1158813Y156598D01*
X1154236Y153597D01*
X1141585Y151544D01*
X1111329Y156824D01*
X1041270Y146314D01*
Y146315D01*
X1041269Y146314D01*
X1030043Y150057D01*
X1017552Y148309D01*
X986610Y135470D01*
X968605D01*
X953599Y142585D01*
X931885Y140016D01*
X875578Y144344D01*
X834661Y147489D01*
X783578Y134712D01*
X782483Y134985D01*
X768515Y138960D01*
X768168Y138836D01*
Y138835D01*
X758321Y135307D01*
X738666Y134526D01*
X709042Y140106D01*
X708909Y140148D01*
X701752Y143415D01*
X679500Y155700D01*
X667500Y156088D01*
X635225Y156455D01*
X629644Y157353D01*
X628719Y157521D01*
X614146Y156533D01*
X612845Y156548D01*
X586429Y161800D01*
X586416Y161803D01*
X586399Y161806D01*
X581918Y162700D01*
X581083Y162654D01*
X555872Y161820D01*
X534623Y170103D01*
X510152Y194574D01*
Y205003D01*
G01X1179844Y196702D02*
Y193808D01*
X1177858Y188948D01*
X1177075Y188619D01*
X1176564Y187369D01*
X1176893Y186586D01*
X1176383Y185337D01*
X1175600Y185008D01*
X1175089Y183758D01*
X1175417Y182975D01*
X1174907Y181726D01*
X1174124Y181397D01*
X1173613Y180146D01*
X1173942Y179364D01*
X1173432Y178115D01*
X1172649Y177786D01*
X1172138Y176535D01*
X1172467Y175753D01*
X1171957Y174504D01*
X1171174Y174175D01*
X1170663Y172925D01*
X1170991Y172143D01*
X1170481Y170892D01*
X1169699Y170564D01*
X1169188Y169314D01*
X1169516Y168531D01*
X1168237Y165399D01*
X1167489Y164276D01*
X1167400Y164258D01*
X1166656Y164110D01*
X1165907Y162985D01*
X1166074Y162153D01*
X1161466Y155239D01*
X1155226Y151058D01*
X1142369Y148752D01*
X1111506Y154176D01*
X1041525Y143423D01*
X1029447Y147363D01*
X1017287Y145383D01*
X987313Y132970D01*
X967483D01*
X953093Y139945D01*
X931947Y137462D01*
X875578Y141637D01*
X834788Y144658D01*
X783473Y131963D01*
X768593Y136179D01*
X758586Y132730D01*
X738257Y131921D01*
X707405Y137006D01*
X707251Y137054D01*
X691736Y144457D01*
X678700Y152500D01*
X676000Y153100D01*
X670700Y153286D01*
X669911D01*
X652128Y153490D01*
X634344Y153694D01*
X628188Y154850D01*
X614570Y153918D01*
X612660Y153940D01*
X584794Y159425D01*
X581393D01*
X555011Y158597D01*
X533028Y167464D01*
X506827Y193596D01*
Y202226D01*
X507173Y202572D01*
Y203662D01*
X506827Y204008D01*
Y205358D01*
G01X1184639Y191921D02*
Y190062D01*
X1173443Y165521D01*
X1165403Y153457D01*
X1156553Y147533D01*
X1141945Y144881D01*
X1110822Y150313D01*
X1041258Y139579D01*
X1029274Y143516D01*
X1018487Y141694D01*
X987980Y129320D01*
X966596D01*
X951880Y135930D01*
X932059Y133549D01*
X875578Y137789D01*
X837527Y140646D01*
X834988Y140891D01*
X784306Y127920D01*
X768626Y132140D01*
X760441Y128912D01*
X737812Y127990D01*
X737811D01*
X703784Y131876D01*
X703419Y131945D01*
X668400Y141700D01*
X664300Y145800D01*
X657550Y146456D01*
X646991Y147483D01*
X627251Y150724D01*
X614916Y149951D01*
X613216Y149972D01*
X583594Y155633D01*
X554154Y154393D01*
X531050Y163489D01*
X502812Y191727D01*
Y205301D01*
G01X1192206Y197614D02*
X1191208Y195957D01*
X1186999Y188584D01*
X1186187Y186827D01*
X1186178Y186809D01*
X1185383Y186509D01*
X1184827Y185278D01*
X1185132Y184469D01*
X1184585Y183260D01*
X1183775Y182955D01*
X1183219Y181724D01*
X1183518Y180930D01*
X1182962Y179700D01*
X1182167Y179401D01*
X1181611Y178170D01*
X1181910Y177376D01*
X1181354Y176146D01*
X1180559Y175847D01*
X1180003Y174616D01*
X1180302Y173822D01*
X1179399Y171824D01*
X1178651Y170701D01*
X1177818Y170535D01*
X1177069Y169410D01*
X1177236Y168578D01*
X1166520Y152501D01*
X1156835Y146011D01*
X1142436Y143365D01*
X1110571Y148867D01*
X1041608Y138006D01*
X1030076Y141702D01*
X1018295Y139660D01*
X1008452Y136076D01*
X988888Y127970D01*
X965670D01*
X951678Y134470D01*
X932589Y132110D01*
X932214Y132095D01*
X835083Y139458D01*
X784723Y126253D01*
X768617Y130340D01*
X759871Y126997D01*
X716418Y125397D01*
X666186Y138761D01*
X655025Y139472D01*
X644850Y142427D01*
X640265Y143398D01*
X632927Y146469D01*
X629669Y146568D01*
X610830Y148647D01*
X582932Y154028D01*
X554201Y152498D01*
X530431Y161812D01*
X526317Y163606D01*
X525443Y164634D01*
X525512Y165480D01*
X524637Y166509D01*
X523790Y166578D01*
X522916Y167606D01*
X522985Y168452D01*
X522110Y169481D01*
X521264Y169550D01*
X519550Y171566D01*
X501396Y189713D01*
Y205672D01*
G01X1142802Y207210D02*
Y199687D01*
X1137383Y195466D01*
X1124045Y189952D01*
X1041972Y170460D01*
X1031384Y173355D01*
X1010162Y171338D01*
X976185Y176753D01*
X948486Y171149D01*
X933009Y162913D01*
X875578Y167620D01*
X834575Y170981D01*
X784555Y158588D01*
X751123Y171123D01*
X725944Y170554D01*
X715305Y168878D01*
X715129Y168850D01*
X665201Y186695D01*
X649026Y190022D01*
X628778Y185609D01*
X614522Y179725D01*
X573825Y188866D01*
X554743Y196768D01*
X551200Y200311D01*
G01X1146434Y207769D02*
Y198315D01*
X1139076Y193196D01*
X1125484Y187528D01*
X1041482Y167755D01*
X1031062Y170705D01*
X1011458Y168696D01*
X1010545Y168635D01*
X976246Y174209D01*
X949198Y168644D01*
X948691Y168374D01*
X933408Y160241D01*
X875578Y165030D01*
X835467Y168351D01*
X784451Y155852D01*
X750261Y168564D01*
X725465Y167686D01*
X715492Y166049D01*
X715462Y166045D01*
X715127Y165989D01*
X663736Y184441D01*
X648522Y187303D01*
X628801Y182793D01*
X614699Y176953D01*
X567262Y187690D01*
X548857Y195315D01*
X544286Y199886D01*
Y199887D01*
G01X1151475Y208465D02*
Y206645D01*
X1151014Y205377D01*
X1150244Y205018D01*
X1149782Y203749D01*
X1150141Y202980D01*
X1149680Y201712D01*
X1148910Y201353D01*
X1148448Y200084D01*
X1148807Y199315D01*
X1148806Y199312D01*
X1148094Y197354D01*
X1148085Y197327D01*
X1148084Y197326D01*
X1139641Y191051D01*
X1126897Y186471D01*
X1041900Y166188D01*
X1030477Y169224D01*
X1012615Y166817D01*
X979576Y153133D01*
X973200D01*
X957916Y162461D01*
X932586Y158601D01*
X875578Y163503D01*
X835845Y166920D01*
X784344Y154138D01*
X751097Y166499D01*
X739684Y162096D01*
X713435Y164742D01*
X662577Y183292D01*
X649019Y185884D01*
X628987Y181367D01*
X614377Y175318D01*
X568564Y185854D01*
X556243Y189248D01*
X555761Y190097D01*
X554893Y190336D01*
X554044Y189854D01*
X553177Y190093D01*
X552695Y190942D01*
X551827Y191181D01*
X550978Y190699D01*
X550111Y190938D01*
X549629Y191787D01*
X548760Y192026D01*
X547912Y191544D01*
X546800Y191850D01*
X543676Y192711D01*
X543294Y193161D01*
X543293Y193168D01*
X541620Y194019D01*
G01X1156035Y209371D02*
Y201509D01*
X1151438Y195210D01*
X1150110Y193589D01*
X1143118Y187893D01*
X1127491Y182737D01*
X1041179Y162152D01*
X1031034Y165095D01*
X1030293Y165332D01*
X1013613Y163028D01*
X980886Y149474D01*
X972061D01*
X957171Y158440D01*
X931600Y154706D01*
X840742Y162699D01*
X836171Y163189D01*
X784160Y150057D01*
X765440Y155436D01*
X754959Y151506D01*
X743046Y153310D01*
X740928Y154156D01*
X717300Y160600D01*
X713526Y160841D01*
X690381Y169179D01*
X688431Y169882D01*
X665194Y178256D01*
X661848Y179462D01*
X648420Y181866D01*
X634489Y178773D01*
Y178772D01*
X629989Y177774D01*
X615826Y171834D01*
X614772Y171426D01*
X612959Y171790D01*
X568385Y181657D01*
X558005Y183059D01*
X542567Y188384D01*
Y188385D01*
X539686Y189379D01*
X533238Y195374D01*
Y200588D01*
G01X1159429Y206300D02*
Y200854D01*
X1153510Y192953D01*
X1151966Y191016D01*
X1144191Y185218D01*
X1134819Y182123D01*
X1134339Y181964D01*
X1118356Y177813D01*
X1041733Y159371D01*
X1030051Y162680D01*
X1014568Y160577D01*
X981666Y146951D01*
X971334D01*
X956418Y155689D01*
X947363Y154262D01*
X931307Y152118D01*
X875578Y156837D01*
X835552Y160226D01*
X784013Y147298D01*
X767993Y151838D01*
X755230Y147035D01*
X741622Y146511D01*
X710525Y152482D01*
X683377Y168524D01*
X676271Y171402D01*
X676262Y171406D01*
X667785Y174464D01*
X665832Y175169D01*
X660585Y177063D01*
X649241Y179205D01*
X634027Y175992D01*
X631869Y175593D01*
X614152Y168312D01*
X574183Y177683D01*
X561352Y178352D01*
X539143Y185553D01*
X538269Y185885D01*
X534300Y189575D01*
X534298D01*
X532563Y191310D01*
G01X578836Y237562D02*
X583245D01*
X585531Y237296D01*
Y237297D01*
X587245Y237418D01*
X588234Y238500D01*
X610364Y262702D01*
X629756Y334224D01*
X655793Y365034D01*
X656749Y371225D01*
X682267Y397852D01*
X689934Y399373D01*
X696956Y400766D01*
X701821Y404813D01*
X708380Y405154D01*
X715633Y407000D01*
X724192Y413074D01*
X758864Y417290D01*
X775716Y428334D01*
X787329Y431094D01*
X897351Y417864D01*
X919795Y421684D01*
X976447Y410368D01*
X1036702Y422802D01*
X1051332Y423519D01*
X1094963Y419330D01*
X1107215Y420750D01*
X1142179Y406231D01*
Y406233D01*
X1142180D01*
Y406232D01*
X1146163Y405870D01*
X1152054Y405335D01*
X1192570Y415679D01*
X1201232Y413707D01*
X1201479Y413479D01*
X1211557Y404163D01*
X1219102Y369200D01*
X1223746Y347682D01*
X1211400Y315202D01*
X1211057Y314300D01*
X1210733Y313448D01*
X1209611Y309109D01*
Y309107D01*
X1208828Y306081D01*
X1208765Y305802D01*
X1208764Y305798D01*
X1208423Y304292D01*
Y303841D01*
G01X558113Y277221D02*
X560522D01*
X562896Y279595D01*
X565594Y281132D01*
X565762Y281747D01*
X566936Y282416D01*
X567549Y282248D01*
X582776Y290927D01*
X593109Y304655D01*
X604673Y347314D01*
X629360Y376530D01*
X632321Y395683D01*
X677099Y438403D01*
X732569Y463181D01*
X768520Y461366D01*
X897482Y445899D01*
X976274Y459314D01*
X1017836Y449526D01*
X1051981Y451206D01*
X1094701Y447104D01*
X1150603Y453585D01*
X1215167Y438882D01*
X1260534Y396952D01*
X1263574Y391427D01*
X1263904Y387066D01*
X1254223Y339512D01*
X1245410Y316332D01*
X1244645Y288629D01*
X1233511Y261077D01*
X1227058Y255280D01*
X1218827D01*
G01X1216681Y252167D02*
X1227350D01*
X1236904Y260749D01*
X1240299Y269400D01*
X1247825Y288579D01*
X1248258Y304273D01*
X1248604Y316842D01*
X1250755Y322500D01*
X1256281Y337039D01*
X1266377Y386627D01*
X1266434Y386907D01*
X1266036Y392160D01*
X1262886Y397886D01*
X1262532Y398529D01*
X1216373Y441181D01*
X1150740Y456129D01*
X1146163Y455598D01*
X1094677Y449629D01*
X1052040Y453723D01*
X1018067Y452051D01*
X976354Y461875D01*
X897191Y448396D01*
X769121Y463813D01*
X732997Y466259D01*
X725851Y463957D01*
X677331Y442095D01*
X629972Y396910D01*
X626990Y377623D01*
X602408Y348542D01*
X591059Y306696D01*
X579633Y294743D01*
X569797Y290283D01*
X565228Y286312D01*
X561970Y283072D01*
X560927D01*
G01X566501Y304021D02*
X573093D01*
X574582Y304609D01*
X583926Y314382D01*
X594331Y352749D01*
X618587Y381453D01*
X621648Y401254D01*
X648978Y427329D01*
X675995Y453106D01*
X691252Y460103D01*
X707261Y467444D01*
X713610Y470356D01*
X720201Y472278D01*
X731857Y475676D01*
X764805Y473292D01*
X896970Y457378D01*
X976637Y470946D01*
X1018885Y460994D01*
X1052249Y462638D01*
X1094595Y458572D01*
X1146163Y464552D01*
X1151229Y465139D01*
X1220867Y449274D01*
X1269419Y404419D01*
X1269459Y404383D01*
X1269600Y404127D01*
X1274117Y395917D01*
X1274756Y394756D01*
X1275395Y386344D01*
X1271904Y369200D01*
X1263398Y327431D01*
X1261524Y322500D01*
X1260393Y319525D01*
X1260363Y318463D01*
X1259696Y317833D01*
X1259670Y316931D01*
X1260303Y316264D01*
X1260278Y315363D01*
X1259610Y314733D01*
X1259598Y314300D01*
X1259584Y313831D01*
X1260217Y313164D01*
X1260192Y312263D01*
X1259524Y311633D01*
X1259498Y310731D01*
X1260131Y310064D01*
X1260106Y309163D01*
X1259438Y308533D01*
X1259412Y307631D01*
X1260045Y306964D01*
X1260020Y306063D01*
X1259352Y305433D01*
X1259326Y304531D01*
X1259959Y303864D01*
X1259934Y302963D01*
X1259266Y302333D01*
X1259240Y301431D01*
X1259873Y300764D01*
X1259848Y299863D01*
X1259180Y299233D01*
X1259154Y298331D01*
X1259788Y297664D01*
X1259660Y292984D01*
X1250822Y269400D01*
X1250777Y269280D01*
X1246217Y257111D01*
X1224184Y237316D01*
X1223433Y236641D01*
X1219163D01*
G01X571079Y308191D02*
X571840D01*
X580867Y317094D01*
X591012Y354494D01*
X615127Y383030D01*
X618219Y403044D01*
X674617Y456851D01*
X690378Y463891D01*
X712720Y473870D01*
X722905Y476887D01*
X730953Y479272D01*
X765808Y476908D01*
X897058Y461106D01*
X976753Y474680D01*
X1019222Y464676D01*
X1052335Y466308D01*
X1094560Y462254D01*
X1122836Y465534D01*
Y465535D01*
X1146163Y468240D01*
X1151428Y468850D01*
X1222732Y452605D01*
X1272039Y407039D01*
X1272319Y406780D01*
X1278346Y395825D01*
X1279084Y386112D01*
X1275640Y369200D01*
X1266564Y324628D01*
X1265755Y322500D01*
X1264611Y319489D01*
X1264467Y314300D01*
X1263902Y293853D01*
X1254734Y269400D01*
X1250777Y258845D01*
X1249332Y254990D01*
X1224783Y232931D01*
X1219811D01*
G01X579055Y239250D02*
X586048D01*
X596515Y250400D01*
X597642Y251600D01*
X609318Y264038D01*
X628521Y334866D01*
X654507Y365618D01*
X655545Y372330D01*
X681123Y399012D01*
X696352Y402033D01*
X701510Y406322D01*
X708205Y406670D01*
X715159Y408440D01*
X723170Y414121D01*
X758068Y418365D01*
X775506Y429861D01*
X787088Y432614D01*
X897733Y419309D01*
X919807Y423065D01*
X976519Y411770D01*
X1036508Y424154D01*
X1051364Y424883D01*
X1094950Y420697D01*
X1107409Y422141D01*
X1142514Y407566D01*
X1146163Y407235D01*
X1151943Y406711D01*
X1192597Y417095D01*
X1201984Y414958D01*
X1202490Y414490D01*
X1212771Y404987D01*
X1220493Y369200D01*
X1222926Y357926D01*
X1225411Y346406D01*
X1222265Y338143D01*
X1222263Y338137D01*
X1221667Y337871D01*
X1221347Y337028D01*
X1221615Y336433D01*
X1221303Y335616D01*
X1221294Y335589D01*
X1220699Y335323D01*
X1220379Y334480D01*
X1220647Y333885D01*
X1220646Y333882D01*
X1220327Y333044D01*
X1220326Y333041D01*
X1219731Y332775D01*
X1219411Y331932D01*
X1219679Y331337D01*
X1219358Y330493D01*
X1218763Y330227D01*
X1218443Y329384D01*
X1218711Y328789D01*
X1218390Y327945D01*
X1217795Y327679D01*
X1217475Y326836D01*
X1217743Y326241D01*
X1217428Y325415D01*
X1217422Y325397D01*
X1216827Y325131D01*
X1216507Y324288D01*
X1216775Y323693D01*
X1216455Y322852D01*
X1216454Y322849D01*
X1215859Y322583D01*
X1215827Y322500D01*
X1215539Y321740D01*
X1215807Y321145D01*
X1215806Y321142D01*
X1215486Y320301D01*
X1214891Y320035D01*
X1214571Y319192D01*
X1214839Y318597D01*
X1214518Y317753D01*
X1213923Y317487D01*
X1213603Y316644D01*
X1213871Y316049D01*
X1213206Y314300D01*
X1212254Y311795D01*
X1211400Y308106D01*
X1211210Y307285D01*
X1210997Y304273D01*
X1210212Y293157D01*
X1209672Y291423D01*
X1208985Y290736D01*
Y290735D01*
X1207312Y289062D01*
X1206673D01*
X1205439Y290296D01*
G01X565805Y271032D02*
X567972D01*
X587516Y284394D01*
X597665Y297879D01*
X610282Y344392D01*
X635194Y373874D01*
X637844Y391013D01*
X664293Y416768D01*
X688443Y425192D01*
X688448Y425207D01*
X690008Y426107D01*
X703051Y437767D01*
X732778Y452217D01*
X761277Y455330D01*
X774062Y454469D01*
X897406Y439626D01*
X976077Y453019D01*
X1017268Y443319D01*
X1051836Y445019D01*
X1094760Y440897D01*
X1110265Y442695D01*
X1146163Y427795D01*
X1147387Y427287D01*
X1150108Y427041D01*
X1192215Y437779D01*
X1211400Y433415D01*
X1211665Y433355D01*
X1231091Y415408D01*
X1239835Y374835D01*
X1241049Y369200D01*
X1242450Y362700D01*
X1247281Y340278D01*
X1246600Y338486D01*
X1242698Y328221D01*
X1238114Y316164D01*
X1238062Y314300D01*
X1238030Y313171D01*
X1237484Y312656D01*
X1237458Y311754D01*
X1237976Y311208D01*
X1237950Y310307D01*
X1237404Y309792D01*
X1237378Y308890D01*
X1237896Y308344D01*
X1237870Y307443D01*
X1237324Y306928D01*
X1237298Y306026D01*
X1237816Y305480D01*
X1237790Y304579D01*
X1237466Y304273D01*
X1237244Y304064D01*
X1237218Y303162D01*
X1237736Y302616D01*
X1237710Y301715D01*
X1237164Y301200D01*
X1237138Y300298D01*
X1237656Y299752D01*
X1237630Y298851D01*
X1237084Y298336D01*
X1237058Y297434D01*
X1237576Y296888D01*
X1237550Y295987D01*
X1237004Y295472D01*
X1236978Y294570D01*
X1237496Y294024D01*
X1237470Y293123D01*
X1236924Y292608D01*
X1236898Y291706D01*
X1237417Y291160D01*
X1237341Y288296D01*
X1230625Y272707D01*
X1228475Y269400D01*
X1226452Y266288D01*
X1225875Y265806D01*
X1224693D01*
G01X578836Y236412D02*
X583178D01*
X585505Y236141D01*
X587784Y236303D01*
X611402Y262131D01*
X630800Y333676D01*
X656881Y364538D01*
X657831Y370691D01*
X682847Y396794D01*
X697467Y399694D01*
X702263Y403684D01*
X708553Y404011D01*
X716124Y405938D01*
X724620Y411967D01*
X759270Y416180D01*
X776178Y427261D01*
X787395Y429927D01*
X897379Y416702D01*
X919778Y420514D01*
X976451Y409194D01*
X1036847Y421657D01*
X1051305Y422366D01*
X1094974Y418173D01*
X1107050Y419573D01*
X1140315Y405759D01*
X1141900Y405101D01*
X1142075Y405085D01*
X1142076Y405084D01*
Y405086D01*
X1152147Y404171D01*
X1192585Y414495D01*
X1200657Y412657D01*
X1200677Y412653D01*
X1200686Y412645D01*
X1210509Y403565D01*
X1211400Y399436D01*
X1220814Y355814D01*
X1222549Y347772D01*
X1216797Y332641D01*
X1216173Y332362D01*
X1215852Y331520D01*
X1216134Y330895D01*
X1215813Y330053D01*
X1215189Y329774D01*
X1214868Y328932D01*
X1215150Y328307D01*
X1214833Y327477D01*
X1214829Y327465D01*
X1214205Y327186D01*
X1213884Y326344D01*
X1214166Y325719D01*
X1213847Y324883D01*
X1213845Y324877D01*
X1213221Y324598D01*
X1212900Y323756D01*
X1213182Y323131D01*
X1212941Y322500D01*
X1212862Y322292D01*
X1212861Y322289D01*
X1212237Y322010D01*
X1211916Y321168D01*
X1212198Y320543D01*
X1211400Y318443D01*
X1209826Y314300D01*
X1209635Y313797D01*
X1208461Y309256D01*
Y309254D01*
X1207714Y306369D01*
Y306367D01*
X1207640Y306081D01*
X1207635Y306056D01*
X1207273Y304418D01*
Y303841D01*
G01X566835Y276474D02*
X569866Y279505D01*
X585275Y288653D01*
X594805Y301316D01*
X606960Y346133D01*
X607134Y346339D01*
X607138Y346344D01*
X631732Y375448D01*
X634671Y394455D01*
X677922Y435721D01*
X689151Y440696D01*
X698572Y441823D01*
X729808Y456344D01*
X745123Y457676D01*
X760321Y458999D01*
X774502Y458124D01*
X897386Y443336D01*
X976194Y456753D01*
X1017605Y447001D01*
X1051922Y448689D01*
X1069909Y446962D01*
X1069911D01*
X1069930Y446961D01*
X1069935D01*
X1069941Y446960D01*
X1069949Y446959D01*
X1069954D01*
X1069959Y446958D01*
X1069965Y446957D01*
X1094723Y444579D01*
X1150450Y451039D01*
X1213629Y436664D01*
X1234388Y417485D01*
X1251203Y339460D01*
X1242377Y316245D01*
X1241601Y288243D01*
X1230404Y262252D01*
X1228102Y260050D01*
X1226658D01*
X1225908Y259300D01*
G01X1218827Y256430D02*
X1226617D01*
X1232544Y261755D01*
X1235633Y269400D01*
X1243501Y288869D01*
X1243534Y290041D01*
X1243034Y290566D01*
X1243059Y291467D01*
X1243587Y291967D01*
X1243612Y292869D01*
X1243112Y293394D01*
X1243137Y294295D01*
X1243665Y294795D01*
X1243690Y295697D01*
X1243190Y296222D01*
X1243215Y297123D01*
X1243743Y297623D01*
X1243768Y298525D01*
X1243268Y299050D01*
X1243293Y299951D01*
X1243821Y300451D01*
X1243846Y301353D01*
X1243346Y301878D01*
X1243371Y302779D01*
X1243899Y303279D01*
X1243924Y304181D01*
X1243836Y304273D01*
X1243424Y304706D01*
X1243449Y305607D01*
X1243977Y306107D01*
X1244002Y307009D01*
X1243502Y307534D01*
X1243527Y308435D01*
X1244055Y308935D01*
X1244080Y309837D01*
X1243580Y310362D01*
X1243605Y311263D01*
X1244133Y311763D01*
X1244158Y312665D01*
X1243658Y313190D01*
X1243683Y314091D01*
X1243904Y314300D01*
X1244211Y314591D01*
X1244265Y316559D01*
X1252750Y338876D01*
X1253114Y339833D01*
X1259093Y369200D01*
X1261686Y381936D01*
X1262745Y387139D01*
X1262446Y391091D01*
X1260190Y395190D01*
X1259616Y396234D01*
X1214612Y437828D01*
X1150540Y452419D01*
X1146163Y451912D01*
X1094712Y445947D01*
X1051954Y450053D01*
X1017730Y448369D01*
X976237Y458141D01*
X897511Y444737D01*
X768422Y460219D01*
X732787Y462018D01*
X677750Y437433D01*
X633398Y395121D01*
X630448Y376034D01*
X605717Y346766D01*
X594161Y304140D01*
X583553Y290045D01*
X563600Y278672D01*
X560999Y276071D01*
X558113D01*
G01X560927Y281922D02*
X562445D01*
X566012Y285469D01*
X570425Y289305D01*
X580311Y293787D01*
X592093Y306112D01*
X603452Y347994D01*
X628078Y377127D01*
X631049Y396348D01*
X677983Y441127D01*
X726265Y462882D01*
X733140Y465096D01*
X769013Y462667D01*
X897219Y447234D01*
X976317Y460702D01*
X1017961Y450894D01*
X1052013Y452570D01*
X1094688Y448472D01*
X1146163Y454440D01*
X1150677Y454963D01*
X1215818Y440127D01*
X1261614Y397811D01*
X1262039Y397039D01*
X1264908Y391824D01*
X1265275Y386980D01*
X1255172Y337360D01*
X1249523Y322500D01*
X1247459Y317069D01*
X1247389Y314551D01*
X1247124Y314300D01*
X1246735Y313931D01*
X1246709Y313029D01*
X1247330Y312376D01*
X1247304Y311475D01*
X1246649Y310855D01*
X1246623Y309953D01*
X1247244Y309300D01*
X1247218Y308399D01*
X1246563Y307779D01*
X1246537Y306877D01*
X1246600Y306811D01*
X1247158Y306224D01*
X1247132Y305323D01*
X1246600Y304819D01*
X1246477Y304703D01*
X1246465Y304273D01*
X1246451Y303801D01*
X1246600Y303644D01*
X1247072Y303148D01*
X1247046Y302247D01*
X1246600Y301825D01*
X1246391Y301627D01*
X1246365Y300725D01*
X1246600Y300478D01*
X1246986Y300072D01*
X1246960Y299171D01*
X1246600Y298830D01*
X1246305Y298551D01*
X1246279Y297649D01*
X1246600Y297311D01*
X1246900Y296996D01*
X1246874Y296095D01*
X1246600Y295836D01*
X1246219Y295475D01*
X1246193Y294573D01*
X1246600Y294144D01*
X1246814Y293919D01*
X1246747Y291369D01*
X1246751Y291366D01*
X1246680Y288812D01*
X1239063Y269400D01*
X1235933Y261423D01*
X1226909Y253317D01*
X1216681D01*
G01X566501Y305171D02*
X572874D01*
X573925Y305586D01*
X582892Y314966D01*
X593287Y353297D01*
X617499Y381949D01*
X620571Y401816D01*
X648184Y428162D01*
X675340Y454072D01*
X690773Y461149D01*
X706782Y468491D01*
X713207Y471437D01*
X719878Y473382D01*
X731734Y476839D01*
X764915Y474438D01*
X764923Y474437D01*
X764943Y474435D01*
X896942Y458540D01*
X936808Y465330D01*
X976674Y472119D01*
X1018991Y462151D01*
X1052276Y463791D01*
X1094584Y459729D01*
X1146163Y465710D01*
X1151292Y466305D01*
X1221422Y450328D01*
X1270234Y405234D01*
X1270377Y405101D01*
X1274117Y398304D01*
X1275884Y395092D01*
X1276554Y386271D01*
X1264507Y327110D01*
X1261538Y319298D01*
X1261400Y314300D01*
X1260875Y295293D01*
X1260874D01*
X1260805Y292760D01*
X1252750Y271265D01*
X1252051Y269400D01*
X1247196Y256443D01*
X1246600Y255908D01*
X1224999Y236501D01*
X1223874Y235491D01*
X1219163D01*
G01X579055Y240400D02*
X585550D01*
X594938Y250400D01*
X596064Y251600D01*
X608283Y264616D01*
X627477Y335414D01*
X653419Y366114D01*
X654463Y372865D01*
X680543Y400070D01*
X695841Y403105D01*
X701069Y407451D01*
X708032Y407813D01*
X714668Y409502D01*
X722742Y415228D01*
X757660Y419475D01*
X775042Y430933D01*
X787022Y433781D01*
X897705Y420471D01*
X919823Y424235D01*
X976515Y412944D01*
X1036363Y425299D01*
X1051391Y426036D01*
X1094939Y421854D01*
X1107574Y423318D01*
X1142793Y408696D01*
X1146163Y408391D01*
X1151850Y407875D01*
X1192581Y418279D01*
X1202539Y416012D01*
X1203304Y415304D01*
X1213819Y405585D01*
X1226512Y346762D01*
X1226608Y346316D01*
X1222694Y336024D01*
X1222693Y336021D01*
X1222382Y335204D01*
X1222373Y335177D01*
X1219789Y328381D01*
X1219788Y328378D01*
X1218505Y325004D01*
X1218499Y324986D01*
X1217554Y322500D01*
X1217532Y322442D01*
X1217531Y322439D01*
X1216884Y320737D01*
X1216883Y320734D01*
X1213357Y311459D01*
X1212351Y307114D01*
X1212150Y304273D01*
X1211400Y293651D01*
X1211350Y292943D01*
X1210686Y290810D01*
X1210135Y290259D01*
Y290258D01*
X1207789Y287912D01*
X1206755D01*
X1205439Y286596D01*
G01X573201Y253255D02*
X579188D01*
X581842Y254417D01*
X600762Y275299D01*
X618357Y340174D01*
X643837Y370328D01*
X644789Y376492D01*
X644791Y376493D01*
X645173Y378977D01*
X676470Y411601D01*
X687158Y415330D01*
Y415329D01*
X697378Y418894D01*
X704410Y424963D01*
X707671Y426269D01*
X723500Y428800D01*
X741569Y428006D01*
X745593Y427464D01*
X746103Y427472D01*
X752698Y428601D01*
X770233Y442936D01*
X772846Y444370D01*
X776833Y445170D01*
X837221Y437906D01*
X897609Y430641D01*
X919951Y434444D01*
X976498Y423199D01*
X1035071Y435291D01*
X1047446Y435899D01*
Y435898D01*
X1051627Y436104D01*
X1094845Y431954D01*
X1109000Y433595D01*
X1145226Y418557D01*
X1146163Y418472D01*
X1151041Y418030D01*
X1192457Y428606D01*
X1207387Y425206D01*
X1222992Y410783D01*
X1232353Y367353D01*
X1234969Y355219D01*
X1237583Y343089D01*
X1226822Y314785D01*
X1226809Y314300D01*
X1226533Y304273D01*
X1226305Y296022D01*
X1226300Y296018D01*
X1226245Y293841D01*
X1221397Y281453D01*
X1217887Y277943D01*
G01X565805Y272182D02*
X567616D01*
X586711Y285237D01*
X596613Y298394D01*
X609238Y344940D01*
X634106Y374370D01*
X636766Y391569D01*
X663673Y417770D01*
X687857Y426207D01*
X687873Y426203D01*
X689330Y427044D01*
X702404Y438732D01*
X732455Y453339D01*
X761253Y456485D01*
X774170Y455615D01*
X897378Y440788D01*
X976114Y454192D01*
X1017374Y444476D01*
X1051863Y446172D01*
X1094749Y442054D01*
X1110430Y443872D01*
X1146163Y429040D01*
X1147665Y428417D01*
X1150015Y428205D01*
X1192200Y438962D01*
X1211400Y434595D01*
X1212220Y434409D01*
X1232139Y416006D01*
X1248478Y340187D01*
X1239259Y315937D01*
X1239214Y314300D01*
X1238936Y304273D01*
X1238485Y288043D01*
X1231643Y272162D01*
X1229847Y269400D01*
X1227322Y265516D01*
X1226293Y264656D01*
X1224693D01*
G01X563242Y293035D02*
X564139D01*
X579051Y298453D01*
X589061Y308925D01*
X600123Y349719D01*
X624618Y378705D01*
X627621Y398136D01*
X676584Y444852D01*
X726238Y467019D01*
X732622Y468937D01*
X750302Y467741D01*
X766761Y466628D01*
X897129Y450932D01*
X976434Y464436D01*
X1018298Y454576D01*
X1052099Y456240D01*
X1094652Y452154D01*
X1146163Y458126D01*
X1150878Y458673D01*
X1217589Y443479D01*
X1264540Y400086D01*
X1264734Y399734D01*
X1268498Y392893D01*
X1268790Y389040D01*
X1268964Y386748D01*
X1265391Y369200D01*
X1258339Y334561D01*
X1251729Y317170D01*
X1251650Y314300D01*
X1251036Y292145D01*
X1251027Y292144D01*
X1250947Y288676D01*
X1243900Y269400D01*
X1240778Y260859D01*
X1227187Y248648D01*
X1215917D01*
X1215470Y248644D01*
G01X563075Y311153D02*
X566544D01*
X579874Y323036D01*
X588674Y355615D01*
X612754Y384112D01*
X615730Y403354D01*
Y403360D01*
X615745Y403458D01*
Y403462D01*
X615932Y404668D01*
X629837Y417934D01*
X629838D01*
X672623Y458753D01*
X711199Y476027D01*
X730914Y481873D01*
X763568Y479655D01*
X896818Y463612D01*
X976836Y477241D01*
X1019453Y467201D01*
X1052394Y468825D01*
X1094534Y464779D01*
X1151567Y471393D01*
X1223944Y454903D01*
X1274309Y408370D01*
X1280808Y396558D01*
X1281614Y385953D01*
X1267658Y317425D01*
X1267039Y295076D01*
X1251465Y253529D01*
X1225721Y230400D01*
X1216002D01*
X1214873Y229271D01*
X1213574D01*
X1212199Y227896D01*
G01X562507Y313184D02*
X566588D01*
X578637Y323927D01*
X588544Y360462D01*
X589115Y360790D01*
X589352Y361661D01*
X589023Y362230D01*
X589258Y363092D01*
X589260Y363100D01*
X589831Y363428D01*
X590068Y364299D01*
X589739Y364868D01*
X589966Y365706D01*
X590089Y367384D01*
X590727Y367937D01*
X590794Y368838D01*
X590240Y369475D01*
X590307Y370374D01*
X590945Y370927D01*
X591012Y371828D01*
X590458Y372465D01*
X590525Y373364D01*
X591163Y373917D01*
X591230Y374818D01*
X590676Y375455D01*
X590743Y376354D01*
X591381Y376907D01*
X591448Y377808D01*
X590894Y378445D01*
X590961Y379344D01*
X591599Y379897D01*
X591666Y380798D01*
X591112Y381435D01*
X591179Y382334D01*
X591817Y382887D01*
X591884Y383788D01*
X591330Y384425D01*
X591872Y392004D01*
X593654Y395230D01*
X598031Y399269D01*
X610531Y401153D01*
X670939Y459674D01*
X709516Y476918D01*
X731370Y483397D01*
X761498Y481347D01*
X897041Y465030D01*
X977018Y478652D01*
X1019774Y468579D01*
X1052426Y470189D01*
X1094516Y466147D01*
X1146163Y472136D01*
X1151643Y472771D01*
X1224802Y456100D01*
X1275236Y409507D01*
X1282142Y396955D01*
X1282294Y394956D01*
X1282985Y385867D01*
X1282294Y382476D01*
X1279589Y369200D01*
X1270075Y322500D01*
X1269142Y317918D01*
X1269113Y316887D01*
X1269041Y314300D01*
X1268511Y295128D01*
X1258865Y269400D01*
X1252750Y253089D01*
X1252621Y252745D01*
X1226194Y228996D01*
X1218680D01*
G01X571079Y307041D02*
X572312D01*
X581896Y316493D01*
X592056Y353946D01*
X616215Y382534D01*
X619296Y402482D01*
X646762Y428685D01*
Y428686D01*
X675268Y455881D01*
X690848Y462840D01*
X713120Y472789D01*
X723232Y475784D01*
X731082Y478110D01*
X765700Y475762D01*
X897086Y459944D01*
X976716Y473507D01*
X1019116Y463519D01*
X1052308Y465155D01*
X1094571Y461097D01*
X1146163Y467081D01*
X1151365Y467684D01*
X1222177Y451551D01*
X1270865Y406558D01*
X1271225Y406225D01*
X1271401Y406062D01*
X1277218Y395489D01*
X1277217D01*
X1277925Y386184D01*
X1274466Y369200D01*
X1274117Y367486D01*
X1265455Y324949D01*
X1264524Y322500D01*
X1263466Y319716D01*
X1263410Y317666D01*
X1262852Y317137D01*
X1262826Y316237D01*
X1263356Y315680D01*
X1263330Y314778D01*
X1262826Y314300D01*
X1262772Y314249D01*
X1262746Y313349D01*
X1263276Y312792D01*
X1263250Y311890D01*
X1262692Y311361D01*
X1262666Y310461D01*
X1263196Y309904D01*
X1263170Y309002D01*
X1262612Y308473D01*
X1262586Y307573D01*
X1263116Y307016D01*
X1263090Y306114D01*
X1262532Y305585D01*
X1262506Y304685D01*
X1263036Y304128D01*
X1263010Y303226D01*
X1262452Y302697D01*
X1262426Y301797D01*
X1262956Y301240D01*
X1262930Y300338D01*
X1262372Y299809D01*
X1262346Y298909D01*
X1262876Y298352D01*
X1262850Y297450D01*
X1262292Y296921D01*
X1262266Y296021D01*
X1262796Y295464D01*
X1262777Y294771D01*
Y294772D01*
X1262757Y294077D01*
X1253505Y269400D01*
X1248353Y255658D01*
X1225963Y235537D01*
X1224342Y234081D01*
X1219811D01*
G01X563075Y310003D02*
X566983D01*
X580895Y322405D01*
X589718Y355068D01*
X613842Y383616D01*
X616880Y403264D01*
Y403271D01*
X616882Y403286D01*
X617009Y404106D01*
X673274Y457784D01*
X711599Y474946D01*
X731043Y480711D01*
X763460Y478509D01*
X896846Y462450D01*
X976799Y476068D01*
X1019347Y466044D01*
X1052367Y467672D01*
X1094545Y463622D01*
X1151504Y470227D01*
X1223389Y453849D01*
X1273391Y407652D01*
X1279680Y396222D01*
X1280455Y386026D01*
X1266511Y317557D01*
X1266492Y316885D01*
X1265906Y316331D01*
X1265880Y315429D01*
X1266436Y314846D01*
X1266410Y313945D01*
X1265824Y313391D01*
X1265798Y312489D01*
X1266354Y311906D01*
X1266328Y311005D01*
X1265742Y310451D01*
X1265716Y309549D01*
X1266272Y308966D01*
X1266246Y308065D01*
X1265660Y307511D01*
X1265634Y306609D01*
X1266190Y306026D01*
X1266164Y305125D01*
X1265578Y304571D01*
X1265552Y303669D01*
X1266108Y303086D01*
X1266082Y302185D01*
X1265496Y301631D01*
X1265470Y300729D01*
X1266026Y300146D01*
X1266000Y299245D01*
X1265414Y298691D01*
X1265388Y297789D01*
X1265944Y297205D01*
X1265894Y295300D01*
X1250486Y254197D01*
X1225280Y231550D01*
X1215525D01*
X1214396Y230421D01*
X1213575D01*
X1212199Y231797D01*
G01X562507Y314334D02*
X566149D01*
X577616Y324558D01*
X588827Y365900D01*
X590451Y388304D01*
X590454Y388306D01*
X590742Y392339D01*
X592737Y395949D01*
X597251Y400114D01*
X597250D01*
X597512Y400355D01*
X609995Y402236D01*
X670284Y460642D01*
X709116Y477999D01*
X731241Y484559D01*
X761606Y482493D01*
X829308Y474343D01*
X829309D01*
X897013Y466192D01*
X977055Y479825D01*
X1019880Y469736D01*
X1052453Y471342D01*
X1094505Y467304D01*
X1122947Y470603D01*
Y470602D01*
X1146163Y473294D01*
X1151706Y473937D01*
X1225357Y457154D01*
X1275671Y410671D01*
X1276154Y410225D01*
X1283270Y397291D01*
X1284144Y385794D01*
X1280763Y369200D01*
X1271249Y322500D01*
X1270865Y320614D01*
X1270289Y317786D01*
X1270233Y315767D01*
X1270193Y314300D01*
X1269946Y305337D01*
X1269945D01*
X1269656Y294904D01*
X1260094Y269400D01*
X1253600Y252077D01*
X1226635Y227846D01*
X1218680D01*
G01X1123459Y210132D02*
X1107032D01*
X1095660Y198761D01*
X1042263Y185235D01*
X1033128Y187817D01*
X1011184Y185789D01*
X1008821Y185636D01*
X984489Y189335D01*
X975551Y190901D01*
X942091Y184038D01*
X929362Y177277D01*
X875578Y181936D01*
X832513Y185666D01*
X785175Y173352D01*
X774763Y177444D01*
Y177445D01*
X764355Y181535D01*
X754354Y185206D01*
X727621Y185032D01*
X716411Y184633D01*
X706967Y187744D01*
X692132Y192631D01*
X692110Y192639D01*
X692102Y192641D01*
X667756Y200979D01*
X649914Y205099D01*
X629946Y201439D01*
X613310Y194550D01*
X599307Y197664D01*
X590740Y203904D01*
X589661Y205743D01*
X567663Y220744D01*
X566464Y221243D01*
G01X1123706Y206626D02*
X1118984D01*
X1115908Y203550D01*
X1106008D01*
X1097978Y196727D01*
X1042675Y182365D01*
X1032554Y185108D01*
X1009322Y183098D01*
X975891Y188245D01*
X942722Y181433D01*
X929956Y174656D01*
X875578Y179344D01*
X832761Y183035D01*
X784900Y170631D01*
X762059Y179698D01*
X754010Y182604D01*
X725594Y182354D01*
X716294Y181675D01*
X667394Y198300D01*
X649261Y202267D01*
X630028Y198625D01*
X613691Y191865D01*
X597525Y195455D01*
X581435Y207356D01*
X573902Y211979D01*
X573690Y212860D01*
X572830Y213389D01*
X571949Y213177D01*
X568462Y215317D01*
X566806Y215990D01*
G01X1123463Y201550D02*
X1120958D01*
X1120587Y201224D01*
X1115701Y197127D01*
X1115700D01*
X1114108Y195791D01*
X1043549Y178549D01*
X1042879Y178385D01*
X1031884Y181284D01*
X1010311Y179446D01*
X1008811Y179349D01*
X976086Y184514D01*
X944379Y177996D01*
X930836Y170801D01*
X875578Y175587D01*
X833971Y179191D01*
X820026Y175906D01*
X784720Y166719D01*
X756738Y177635D01*
X753324Y178857D01*
X750434D01*
X726496Y178702D01*
X725865Y178635D01*
X716117Y177595D01*
X715874Y177678D01*
Y177679D01*
X667095Y194485D01*
X648934Y198199D01*
X629883Y194604D01*
X613787Y187937D01*
X594939Y192241D01*
X591040Y193501D01*
X577914Y198944D01*
X571747Y203486D01*
X571674Y203971D01*
X567700Y206900D01*
G01X1136926Y205925D02*
Y203748D01*
X1134899Y201908D01*
X1134898D01*
X1134819Y201836D01*
X1132532Y199763D01*
X1123184Y195168D01*
X1042454Y175848D01*
X1031783Y178598D01*
X1009756Y176674D01*
X975768Y181887D01*
X946168Y175800D01*
X932180Y168374D01*
X931832Y168189D01*
X875578Y173003D01*
X834277Y176538D01*
X784468Y164038D01*
X752891Y176229D01*
X752669Y176307D01*
X725689Y176027D01*
X715675Y174630D01*
X665292Y192170D01*
X649127Y195523D01*
X629393Y191563D01*
X613972Y185178D01*
X591907Y190214D01*
X565248Y201250D01*
X564510D01*
X560776Y202797D01*
X559923Y203650D01*
X558687D01*
G01X1138839Y203223D02*
Y201773D01*
X1137929Y201123D01*
X1137928D01*
X1137025Y201274D01*
X1136222Y200701D01*
X1136071Y199798D01*
X1134819Y198905D01*
X1134117Y198404D01*
X1123932Y193962D01*
X1042179Y174297D01*
X1031548Y177204D01*
X1010506Y175335D01*
X1009568Y175273D01*
X976110Y180465D01*
X947044Y174584D01*
X932232Y166701D01*
X875578Y171354D01*
X834287Y174746D01*
X833701Y174603D01*
X784481Y162564D01*
X752322Y174928D01*
X725453Y174438D01*
X715883Y172840D01*
X664756Y190800D01*
X649671Y194021D01*
X628322Y189570D01*
X614380Y183798D01*
X587703Y189790D01*
X575604Y194800D01*
X573549D01*
X572073Y195411D01*
X571739Y196218D01*
X570772Y196619D01*
X569966Y196284D01*
X568428Y196921D01*
X568054Y197823D01*
X567222Y198168D01*
X566320Y197794D01*
X565489Y198138D01*
X565115Y199040D01*
X564283Y199385D01*
X563381Y199011D01*
X562550Y199355D01*
X562177Y200257D01*
X561345Y200602D01*
X560443Y200228D01*
X559612Y200572D01*
X559091Y201093D01*
G01X1141652Y207282D02*
Y200249D01*
X1136799Y196469D01*
X1123690Y191050D01*
X1041992Y171647D01*
X1031484Y174520D01*
X1010199Y172497D01*
X976161Y177922D01*
X948093Y172244D01*
X932767Y164087D01*
X875578Y168774D01*
X834481Y172143D01*
X784625Y159791D01*
X751319Y172278D01*
X725841Y171702D01*
X715305Y170042D01*
X715244Y170033D01*
X715240Y170032D01*
X665515Y187805D01*
X665512Y187806D01*
X649019Y191198D01*
X628433Y186711D01*
X614419Y180927D01*
X574174Y189967D01*
X571344Y191139D01*
X570971Y192041D01*
X570139Y192386D01*
X569237Y192012D01*
X568406Y192356D01*
X568032Y193258D01*
X567200Y193603D01*
X566298Y193229D01*
X565467Y193573D01*
X565093Y194475D01*
X564261Y194820D01*
X563359Y194446D01*
X562528Y194790D01*
X562154Y195692D01*
X561322Y196037D01*
X560420Y195663D01*
X559589Y196007D01*
X559215Y196909D01*
X558383Y197254D01*
X557481Y196880D01*
X555395Y197744D01*
X552139Y201000D01*
G01X1123459Y208982D02*
X1107509D01*
X1096250Y197723D01*
X1042247Y184044D01*
X1033021Y186652D01*
X1011274Y184642D01*
X1008771Y184480D01*
X984303Y188200D01*
X975568Y189730D01*
X942485Y182944D01*
X929602Y176101D01*
X875578Y180781D01*
X832611Y184503D01*
X785102Y172144D01*
X763946Y180459D01*
X759051Y182256D01*
X759050Y182257D01*
X754153Y184054D01*
X727645Y183882D01*
X716246Y183476D01*
X706967Y186533D01*
X691772Y191539D01*
X691758Y191543D01*
X691754Y191544D01*
X691740Y191549D01*
X691735Y191551D01*
X667439Y199871D01*
X649887Y203924D01*
X630273Y200329D01*
X613415Y193348D01*
X598824Y196593D01*
X589869Y203115D01*
X588799Y204938D01*
X567112Y219727D01*
X566022Y220181D01*
G01X1123706Y205476D02*
X1119461D01*
X1116385Y202400D01*
X1106431D01*
X1098522Y195680D01*
X1042669Y181175D01*
X1032450Y183944D01*
X1009284Y181940D01*
X975920Y187076D01*
X943116Y180339D01*
X930196Y173480D01*
X875578Y178189D01*
X832859Y181872D01*
X784825Y169423D01*
X761651Y178622D01*
X753814Y181452D01*
X725641Y181204D01*
X716145Y180511D01*
X667085Y197190D01*
X649244Y201093D01*
X630359Y197516D01*
X613796Y190663D01*
X597037Y194385D01*
X580791Y206401D01*
X573300Y210999D01*
Y210998D01*
X567946Y214284D01*
X566373Y214924D01*
G01X1123463Y202700D02*
X1120524D01*
X1119838Y202097D01*
X1116611Y199391D01*
X1116047Y199441D01*
X1115012Y198572D01*
X1114962Y198009D01*
X1113574Y196845D01*
X1042890Y179572D01*
X1031985Y182447D01*
X1010225Y180593D01*
X1008864Y180505D01*
X976059Y185683D01*
X943985Y179090D01*
X930596Y171977D01*
X875578Y176742D01*
X833887Y180353D01*
X819749Y177023D01*
X784795Y167927D01*
X757182Y178699D01*
X753531Y180007D01*
X750430D01*
X726431Y179852D01*
X716250Y178766D01*
X667399Y195597D01*
X648943Y199372D01*
X629551Y195712D01*
X613686Y189140D01*
X595244Y193351D01*
X591438Y194581D01*
X578484Y199953D01*
X572814Y204130D01*
X572741Y204614D01*
X568362Y207841D01*
G01X1135776Y205925D02*
Y204258D01*
X1134819Y203390D01*
X1134479Y203081D01*
X1133871Y203111D01*
X1132797Y202135D01*
X1132768Y201530D01*
X1131879Y200724D01*
X1129545Y199577D01*
X1128842Y199816D01*
X1127723Y199268D01*
X1127483Y198563D01*
X1122792Y196257D01*
X1122791D01*
X1042464Y177033D01*
X1042121Y177121D01*
X1031879Y179761D01*
X1009794Y177832D01*
X975738Y183056D01*
X945774Y176894D01*
X931592Y169364D01*
X875578Y174158D01*
X834183Y177701D01*
X784544Y165243D01*
X768917Y171275D01*
Y171276D01*
X753290Y177309D01*
X752864Y177460D01*
X725603Y177177D01*
X715791Y175808D01*
X665599Y193281D01*
X649131Y196697D01*
X629056Y192669D01*
X613871Y186381D01*
X592257Y191314D01*
X571391Y199952D01*
X571051Y200772D01*
X570085Y201172D01*
X569265Y200832D01*
X568434Y201176D01*
X568115Y201945D01*
X567077Y202375D01*
X566308Y202056D01*
X565477Y202400D01*
X564739D01*
X561428Y203773D01*
X560400Y204800D01*
X558687D01*
G01X1139989Y203223D02*
Y201180D01*
X1134687Y197397D01*
X1124299Y192867D01*
X1042161Y173109D01*
X1031444Y176040D01*
X1010595Y174188D01*
X1009517Y174117D01*
X976137Y179297D01*
X947437Y173489D01*
X932474Y165527D01*
X875578Y170200D01*
X834379Y173584D01*
X784404Y161361D01*
X752119Y173773D01*
X725559Y173289D01*
X715781Y171656D01*
X664444Y189690D01*
X649668Y192845D01*
X628662Y188466D01*
X614483Y182595D01*
X587354Y188689D01*
X575375Y193650D01*
X573320D01*
X558960Y199596D01*
X558277Y200279D01*
G01X567649Y275660D02*
X570578Y278589D01*
X586058Y287779D01*
X595857Y300801D01*
X608004Y345585D01*
X608012Y345596D01*
X632820Y374952D01*
X635748Y393893D01*
X678572Y434750D01*
X689459Y439574D01*
X698891Y440702D01*
X730110Y455215D01*
X760336Y457845D01*
X774397Y456978D01*
X897414Y442174D01*
X976157Y455580D01*
X1017499Y445844D01*
X1051895Y447536D01*
X1069820Y445815D01*
X1069826Y445814D01*
X1069831D01*
X1069839Y445813D01*
X1069844Y445812D01*
X1069855D01*
X1094734Y443422D01*
X1119552Y446298D01*
X1120317Y445692D01*
X1121212Y445796D01*
X1121818Y446562D01*
X1150387Y449873D01*
X1213074Y435610D01*
X1233340Y416887D01*
X1250006Y339551D01*
X1241232Y316472D01*
X1241196Y315199D01*
X1240618Y314653D01*
X1240592Y313751D01*
X1241141Y313172D01*
X1241115Y312271D01*
X1240536Y311725D01*
X1240510Y310823D01*
X1241059Y310244D01*
X1241033Y309343D01*
X1240454Y308797D01*
X1240428Y307895D01*
X1240977Y307316D01*
X1240951Y306415D01*
X1240372Y305869D01*
X1240346Y304967D01*
X1240895Y304388D01*
X1240869Y303487D01*
X1240290Y302941D01*
X1240264Y302039D01*
X1240813Y301460D01*
X1240787Y300559D01*
X1240208Y300013D01*
X1240182Y299111D01*
X1240731Y298532D01*
X1240705Y297631D01*
X1240126Y297085D01*
X1240100Y296183D01*
X1240649Y295604D01*
X1240623Y294703D01*
X1240044Y294157D01*
X1240018Y293255D01*
X1240567Y292676D01*
X1240541Y291775D01*
X1239962Y291229D01*
X1239936Y290327D01*
X1240487Y289748D01*
X1240491Y289744D01*
X1240457Y288496D01*
X1229440Y262922D01*
X1227640Y261200D01*
X1226508D01*
X1225908Y261800D01*
G01X580378Y243575D02*
X584235D01*
X606075Y266081D01*
X625196Y336603D01*
X651046Y367195D01*
X652183Y374547D01*
X678752Y402272D01*
X694726Y405444D01*
X694725D01*
X699895Y409745D01*
X707327Y410130D01*
X713241Y411636D01*
X721365Y417398D01*
X756015Y421611D01*
X773191Y432933D01*
X787271Y436279D01*
X897643Y423007D01*
X908556Y424864D01*
Y424866D01*
X919840Y426785D01*
X976526Y415513D01*
X1036105Y427800D01*
X1051450Y428553D01*
X1094915Y424379D01*
X1107931Y425888D01*
X1143402Y411161D01*
X1151648Y410414D01*
X1192553Y420860D01*
X1203751Y418310D01*
X1216105Y406892D01*
X1229406Y345256D01*
X1217173Y313080D01*
X1215195Y298613D01*
Y296500D01*
G01X585282Y247205D02*
X590585Y252508D01*
X605227Y268153D01*
X623960Y337245D01*
X649763Y367781D01*
X650946Y375435D01*
X677814Y403472D01*
X694122Y406711D01*
X699374Y411078D01*
X706967Y411473D01*
X712388Y412969D01*
X720448Y418449D01*
X755499Y422718D01*
X773945Y437630D01*
X778486Y438707D01*
X838046Y431543D01*
Y431542D01*
X897604Y424380D01*
X919866Y428168D01*
X976521Y416901D01*
X1035908Y429152D01*
X1051482Y429917D01*
X1094903Y425747D01*
X1108125Y427280D01*
X1143731Y412497D01*
X1151539Y411789D01*
X1192533Y422258D01*
X1204405Y419556D01*
X1217345Y407598D01*
X1230931Y344618D01*
X1219441Y314395D01*
X1219407Y313478D01*
X1218792Y312907D01*
X1218758Y312005D01*
X1219329Y311392D01*
X1219295Y310492D01*
X1218680Y309921D01*
X1218646Y309019D01*
X1219217Y308406D01*
X1219183Y307506D01*
X1218568Y306935D01*
X1218534Y306033D01*
X1219105Y305420D01*
X1219071Y304520D01*
X1218456Y303949D01*
X1218422Y303047D01*
X1218993Y302434D01*
X1218959Y301534D01*
X1218344Y300963D01*
X1218310Y300061D01*
X1218881Y299448D01*
X1218847Y298548D01*
X1218232Y297977D01*
X1218198Y297075D01*
X1218771Y296462D01*
X1218736Y295310D01*
X1218375Y294546D01*
X1217662Y294291D01*
X1217277Y293475D01*
X1217534Y292762D01*
X1215783Y289042D01*
X1215782Y289040D01*
G01X569660Y249575D02*
X579984D01*
X584930Y252347D01*
X602034Y270376D01*
X620638Y338987D01*
X646301Y369357D01*
X647553Y377459D01*
X675682Y406780D01*
X691472Y409917D01*
X706621Y422984D01*
X720979Y425170D01*
X746309D01*
X754240Y426518D01*
X772999Y441679D01*
X777150Y442613D01*
X897514Y428078D01*
X919913Y431891D01*
X976507Y420637D01*
X1035430Y432794D01*
X1049488Y433486D01*
Y433485D01*
X1051568Y433587D01*
X1094869Y429429D01*
X1108646Y431026D01*
X1128523Y422772D01*
Y422773D01*
X1144610Y416092D01*
X1146163Y415951D01*
X1151243Y415491D01*
X1192486Y426023D01*
X1206174Y422907D01*
X1220680Y409500D01*
X1229373Y369200D01*
X1230230Y365230D01*
X1232847Y353097D01*
X1234852Y343802D01*
X1226754Y322500D01*
X1223711Y314494D01*
X1223706Y314300D01*
X1223428Y304273D01*
X1223166Y294797D01*
X1218354Y283001D01*
X1217356Y282003D01*
G01X573201Y252105D02*
X579429D01*
X582529Y253462D01*
X601800Y274731D01*
X619401Y339626D01*
X644925Y369832D01*
X646255Y378443D01*
X661683Y394524D01*
X661682D01*
X677110Y410605D01*
X697964Y417880D01*
X705016Y423966D01*
X707980Y425153D01*
X707982Y425154D01*
X707983D01*
Y425153D01*
X723566Y427645D01*
X741467Y426859D01*
X745525Y426312D01*
X746210Y426323D01*
X753191Y427518D01*
X770880Y441978D01*
X773245Y443277D01*
X776879Y444006D01*
X897637Y429479D01*
X919935Y433274D01*
X976502Y422025D01*
X1035216Y434146D01*
X1051600Y434951D01*
X1094856Y430797D01*
X1108835Y432418D01*
X1144947Y417427D01*
X1151134Y416866D01*
X1192472Y427422D01*
X1206832Y424152D01*
X1221944Y410185D01*
X1236386Y343180D01*
X1225677Y315012D01*
X1225614Y312744D01*
X1225033Y312194D01*
X1225007Y311292D01*
X1225559Y310713D01*
X1225533Y309812D01*
X1224951Y309262D01*
X1224925Y308360D01*
X1225477Y307781D01*
X1225451Y306880D01*
X1224869Y306330D01*
X1224843Y305428D01*
X1225395Y304849D01*
X1225369Y303948D01*
X1224787Y303398D01*
X1224761Y302496D01*
X1225313Y301917D01*
X1225287Y301016D01*
X1224705Y300466D01*
X1224679Y299564D01*
X1225231Y298985D01*
X1225205Y298084D01*
X1224623Y297534D01*
X1224597Y296632D01*
X1225149Y296052D01*
X1225100Y294072D01*
X1220413Y282097D01*
X1217074Y278758D01*
G01X574021Y256689D02*
X576450D01*
X583774Y260964D01*
X588803Y267289D01*
X600039Y282219D01*
X616079Y341371D01*
X616671Y342072D01*
X641225Y371129D01*
X642603Y380042D01*
X643156Y380618D01*
X674910Y413716D01*
X694999Y420723D01*
X702007Y426768D01*
X705752Y428298D01*
X726738Y432860D01*
X744811Y437163D01*
X749315Y436116D01*
X753140Y436396D01*
X772367Y446975D01*
X776604Y447731D01*
X897565Y433180D01*
X919988Y436997D01*
X976488Y425762D01*
X1034660Y437785D01*
X1051686Y438621D01*
X1094819Y434479D01*
X1109361Y436164D01*
X1145832Y421023D01*
X1146163Y420993D01*
X1150838Y420569D01*
X1192421Y431187D01*
X1208593Y427506D01*
X1225278Y412088D01*
X1234466Y369466D01*
X1234523Y369200D01*
X1237081Y357331D01*
X1240307Y342364D01*
X1232754Y322500D01*
X1229921Y315048D01*
X1229900Y314300D01*
X1229623Y304273D01*
X1229336Y293889D01*
X1224138Y279454D01*
X1222761Y278077D01*
G01X574489Y264600D02*
X575746D01*
X584490Y268281D01*
X600678Y289792D01*
X614842Y342011D01*
X639939Y371711D01*
X642413Y387717D01*
X668004Y412746D01*
X693206Y421537D01*
X702219Y429313D01*
X748946Y446360D01*
X751389Y447251D01*
X771985Y449653D01*
X897237Y434504D01*
X920005Y438380D01*
X976416Y427163D01*
X1034496Y439139D01*
X1051718Y439985D01*
X1094808Y435847D01*
X1109541Y437555D01*
X1146163Y422360D01*
X1146170Y422357D01*
X1150729Y421943D01*
X1192401Y432587D01*
X1209254Y428749D01*
X1226518Y412794D01*
X1235609Y370609D01*
X1235913Y369200D01*
X1238225Y358475D01*
X1241834Y341729D01*
X1234524Y322500D01*
X1231825Y315402D01*
X1231793Y314300D01*
X1231791Y314215D01*
X1231255Y313708D01*
X1231229Y312806D01*
X1231737Y312271D01*
X1231711Y311371D01*
X1231175Y310864D01*
X1231149Y309962D01*
X1231657Y309427D01*
X1231631Y308527D01*
X1231095Y308020D01*
X1231069Y307118D01*
X1231577Y306583D01*
X1231551Y305683D01*
X1231015Y305176D01*
X1230989Y304274D01*
X1230990Y304273D01*
X1231497Y303739D01*
X1231471Y302839D01*
X1230935Y302332D01*
X1230909Y301430D01*
X1231417Y300895D01*
X1231391Y299995D01*
X1230855Y299488D01*
X1230829Y298586D01*
X1231338Y298051D01*
X1231261Y295011D01*
X1225920Y278327D01*
X1220741Y273149D01*
G01X573617Y268429D02*
X574552D01*
X582423Y273030D01*
X597924Y293626D01*
X611518Y343750D01*
X636480Y373292D01*
X639067Y390024D01*
X665477Y415741D01*
X690239Y424380D01*
X703173Y435536D01*
X733797Y451000D01*
X767521Y453434D01*
X775625Y452908D01*
X897440Y438252D01*
X976034Y451631D01*
X1017143Y441951D01*
X1051804Y443655D01*
X1094772Y439529D01*
X1110069Y441302D01*
X1146163Y426322D01*
X1147055Y425952D01*
X1150433Y425646D01*
X1192347Y436350D01*
X1192349Y436353D01*
X1211019Y432101D01*
X1229854Y414695D01*
X1238692Y373692D01*
X1239660Y369200D01*
X1241307Y361557D01*
X1245756Y340915D01*
X1236130Y315596D01*
X1236094Y314300D01*
X1235817Y304273D01*
X1235557Y294879D01*
X1230380Y276888D01*
X1230084Y276368D01*
X1230088Y276358D01*
X1230086Y276355D01*
X1224688Y269867D01*
X1223556Y268735D01*
G01X563242Y291885D02*
X564342D01*
X579697Y297463D01*
X590095Y308341D01*
X601167Y349171D01*
X625706Y378209D01*
X628698Y397574D01*
X677235Y443882D01*
X726640Y465938D01*
X732753Y467775D01*
X733564Y467720D01*
X750225Y466593D01*
X766653Y465482D01*
X897157Y449770D01*
X976397Y463263D01*
X1018192Y453419D01*
X1052072Y455087D01*
X1094663Y450997D01*
X1146163Y456968D01*
X1150815Y457507D01*
X1217034Y442425D01*
X1263622Y399368D01*
X1263887Y398887D01*
X1267370Y392557D01*
X1267600Y389524D01*
X1267718Y387968D01*
X1267805Y386821D01*
X1267600Y385814D01*
X1264217Y369200D01*
X1257230Y334882D01*
X1252750Y323095D01*
X1252524Y322500D01*
X1250584Y317397D01*
X1250521Y315141D01*
X1249914Y314566D01*
X1249906Y314300D01*
X1249888Y313663D01*
X1250463Y313058D01*
X1250437Y312157D01*
X1249830Y311582D01*
X1249804Y310679D01*
X1250379Y310074D01*
X1250353Y309173D01*
X1249746Y308598D01*
X1249720Y307695D01*
X1250295Y307090D01*
X1250269Y306189D01*
X1249662Y305614D01*
X1249636Y304711D01*
X1250052Y304273D01*
X1250211Y304106D01*
X1250185Y303205D01*
X1249578Y302630D01*
X1249552Y301727D01*
X1250127Y301122D01*
X1250101Y300221D01*
X1249494Y299646D01*
X1249468Y298743D01*
X1250043Y298138D01*
X1250017Y297237D01*
X1249410Y296662D01*
X1249384Y295759D01*
X1249959Y295154D01*
X1249933Y294253D01*
X1249326Y293678D01*
X1249300Y292775D01*
X1249877Y292170D01*
X1249801Y288893D01*
X1242675Y269400D01*
X1239796Y261523D01*
X1226746Y249798D01*
X1215911D01*
X1215460Y249794D01*
G01X580378Y242425D02*
X584722D01*
X607108Y265493D01*
X626240Y336055D01*
X652134Y366699D01*
X653265Y374013D01*
X679332Y401214D01*
X695237Y404373D01*
X700337Y408615D01*
X707501Y408987D01*
X713729Y410571D01*
X721792Y416290D01*
X756423Y420501D01*
X773655Y431860D01*
X787337Y435112D01*
X897671Y421845D01*
X919824Y425615D01*
X976530Y414339D01*
X1036250Y426655D01*
X1051423Y427400D01*
X1094926Y423222D01*
X1107766Y424711D01*
X1143123Y410031D01*
X1151741Y409250D01*
X1192568Y419676D01*
X1203196Y417256D01*
X1215057Y406294D01*
X1228209Y345346D01*
X1216051Y313366D01*
X1215845Y311866D01*
X1215266Y311426D01*
X1215143Y310533D01*
X1215585Y309953D01*
X1215462Y309060D01*
X1214882Y308620D01*
X1214759Y307727D01*
X1215201Y307147D01*
X1215078Y306254D01*
X1214498Y305814D01*
X1214375Y304921D01*
X1214817Y304341D01*
X1214694Y303448D01*
X1214114Y303008D01*
X1213991Y302115D01*
X1214433Y301535D01*
X1214045Y298692D01*
Y296500D01*
G01X584469Y248019D02*
X589758Y253308D01*
X604191Y268730D01*
X622916Y337793D01*
X648675Y368277D01*
X649864Y375969D01*
X677234Y404530D01*
X693611Y407782D01*
X693610D01*
X698933Y412207D01*
X706782Y412615D01*
X711898Y414028D01*
X720032Y419557D01*
X755032Y423820D01*
X773425Y438689D01*
X778420Y439874D01*
X897576Y425542D01*
X919882Y429338D01*
X976517Y418075D01*
X1035763Y430297D01*
X1051509Y431070D01*
X1094892Y426904D01*
X1108290Y428457D01*
X1144010Y413627D01*
X1151446Y412953D01*
X1192517Y423442D01*
X1204960Y420610D01*
X1218393Y408196D01*
X1232128Y344528D01*
X1220584Y314163D01*
X1219877Y295033D01*
X1216823Y288551D01*
G01X569660Y248425D02*
X580285D01*
X585645Y251428D01*
X585808Y251600D01*
X603068Y269795D01*
X621682Y338439D01*
X647389Y368861D01*
X648635Y376924D01*
X676262Y405722D01*
X684127Y407283D01*
Y407285D01*
X691994Y408848D01*
X707122Y421896D01*
X721067Y424020D01*
X746407D01*
X754729Y425434D01*
X773514Y440615D01*
X777209Y441447D01*
X897542Y426916D01*
X919897Y430721D01*
X976511Y419463D01*
X1035575Y431649D01*
X1043557Y432040D01*
Y432041D01*
X1051541Y432434D01*
X1094880Y428272D01*
X1108481Y429849D01*
X1144331Y414962D01*
X1146163Y414796D01*
X1147822Y414646D01*
X1151336Y414327D01*
X1192502Y424839D01*
X1199060Y423346D01*
Y423347D01*
X1205619Y421853D01*
X1207819Y419819D01*
X1219632Y408902D01*
X1219631D01*
X1228196Y369200D01*
X1229261Y364261D01*
X1231878Y352128D01*
X1233655Y343892D01*
X1222566Y314721D01*
X1222554Y314300D01*
X1222523Y313218D01*
X1221944Y312672D01*
X1221918Y311770D01*
X1222468Y311191D01*
X1222442Y310290D01*
X1221862Y309744D01*
X1221836Y308842D01*
X1222386Y308263D01*
X1222360Y307362D01*
X1221780Y306816D01*
X1221754Y305914D01*
X1222304Y305335D01*
X1222278Y304434D01*
X1221698Y303888D01*
X1221672Y302986D01*
X1222222Y302407D01*
X1222196Y301506D01*
X1221616Y300960D01*
X1221590Y300058D01*
X1222140Y299479D01*
X1222114Y298578D01*
X1221534Y298032D01*
X1221508Y297130D01*
X1222059Y296550D01*
X1222022Y295038D01*
X1217376Y283651D01*
X1216542Y282817D01*
X1216541D01*
G01X574021Y255539D02*
X576762D01*
X584541Y260079D01*
X589713Y266585D01*
X601091Y281704D01*
X617123Y340823D01*
X642313Y370633D01*
X643685Y379507D01*
X675549Y412719D01*
X675550Y412720D01*
X695585Y419708D01*
X702616Y425774D01*
X706094Y427195D01*
X726994Y431738D01*
X744814Y435981D01*
X749225Y434956D01*
X753474Y435267D01*
X772756Y445875D01*
X776637Y446568D01*
X897593Y432018D01*
X919972Y435827D01*
X976492Y424588D01*
X1034806Y436640D01*
X1051659Y437468D01*
X1094830Y433322D01*
X1109196Y434987D01*
X1145553Y419893D01*
X1150931Y419405D01*
X1192437Y430003D01*
X1208038Y426452D01*
X1224230Y411490D01*
X1239110Y342455D01*
X1228776Y315275D01*
X1228738Y313927D01*
X1228200Y313418D01*
X1228174Y312516D01*
X1228684Y311979D01*
X1228658Y311079D01*
X1228120Y310570D01*
X1228094Y309668D01*
X1228604Y309131D01*
X1228578Y308231D01*
X1228040Y307722D01*
X1228014Y306820D01*
X1228524Y306283D01*
X1228498Y305383D01*
X1227960Y304874D01*
X1227934Y303972D01*
X1228444Y303435D01*
X1228418Y302535D01*
X1227880Y302026D01*
X1227854Y301124D01*
X1228364Y300587D01*
X1228338Y299687D01*
X1227800Y299178D01*
X1227774Y298276D01*
X1228285Y297739D01*
X1228191Y294105D01*
X1223144Y280088D01*
X1221947Y278891D01*
G01X574489Y265750D02*
X575513D01*
X583757Y269221D01*
X599626Y290307D01*
X613798Y342559D01*
X638851Y372207D01*
X641334Y388272D01*
X667382Y413747D01*
X692620Y422552D01*
X701627Y430322D01*
X748551Y447440D01*
X751122Y448378D01*
X771987Y450812D01*
X897209Y435666D01*
X920021Y439550D01*
X976412Y428337D01*
X1034351Y440284D01*
X1051745Y441138D01*
X1094797Y437004D01*
X1109706Y438732D01*
X1146163Y423606D01*
X1146449Y423487D01*
X1150636Y423107D01*
X1192386Y433771D01*
X1209809Y429803D01*
X1227566Y413392D01*
X1236578Y371578D01*
X1237091Y369200D01*
X1239194Y359444D01*
X1243031Y341638D01*
X1232970Y315175D01*
X1232946Y314300D01*
X1232669Y304273D01*
X1232407Y294816D01*
X1226931Y277710D01*
X1221555Y272336D01*
G01X573617Y267279D02*
X574864D01*
X583204Y272153D01*
X598976Y293111D01*
X612562Y343202D01*
X637568Y372796D01*
X640145Y389468D01*
X666097Y414739D01*
X690825Y423365D01*
X703818Y434572D01*
X734110Y449869D01*
X767525Y452281D01*
X775519Y451762D01*
X897468Y437090D01*
X975997Y450458D01*
X1017037Y440794D01*
X1051777Y442502D01*
X1094783Y438372D01*
X1109904Y440125D01*
X1146163Y425076D01*
X1146776Y424822D01*
X1150526Y424482D01*
X1192370Y435168D01*
X1210464Y431047D01*
X1228806Y414097D01*
X1237723Y372723D01*
X1238482Y369200D01*
X1240338Y360588D01*
X1244559Y341006D01*
X1237523Y322500D01*
X1234985Y315823D01*
X1234955Y314785D01*
X1234442Y314300D01*
X1234414Y314274D01*
X1234388Y313372D01*
X1234901Y312833D01*
X1234875Y311933D01*
X1234334Y311422D01*
X1234308Y310520D01*
X1234821Y309981D01*
X1234795Y309081D01*
X1234254Y308570D01*
X1234228Y307668D01*
X1234741Y307129D01*
X1234715Y306229D01*
X1234174Y305718D01*
X1234148Y304816D01*
X1234661Y304277D01*
Y304273D01*
X1234635Y303377D01*
X1234094Y302866D01*
X1234068Y301964D01*
X1234581Y301425D01*
X1234555Y300525D01*
X1234014Y300014D01*
X1233988Y299112D01*
X1234502Y298573D01*
X1234411Y295057D01*
X1229313Y277342D01*
X1229085Y276938D01*
X1229084D01*
X1229070Y276934D01*
X1223837Y270644D01*
X1222741Y269549D01*
G01X571809Y299639D02*
X574137D01*
X577693Y301087D01*
X586963Y310785D01*
X597842Y350909D01*
X622244Y379787D01*
X625279Y399414D01*
X674233Y446118D01*
X674764Y446513D01*
X680095Y450483D01*
X715287Y466336D01*
X731412Y471538D01*
X763594Y469348D01*
X775779Y468119D01*
X897230Y453496D01*
X976514Y466997D01*
X1018529Y457101D01*
X1052158Y458757D01*
X1094628Y454679D01*
X1146163Y460654D01*
X1151016Y461217D01*
X1218797Y445778D01*
X1266542Y401656D01*
X1266582Y401582D01*
X1270865Y393799D01*
X1270960Y393626D01*
X1271494Y386589D01*
X1267953Y369200D01*
X1260396Y332082D01*
X1254787Y317325D01*
X1254703Y314300D01*
X1254004Y289010D01*
X1246655Y269400D01*
X1242873Y259307D01*
X1221996Y240550D01*
X1216749D01*
X1215550Y241749D01*
Y242678D01*
X1214732Y243496D01*
G01X560275Y297165D02*
X561202D01*
X565309Y301272D01*
X573347D01*
X576228Y302413D01*
X586076Y312715D01*
X596608Y351553D01*
X620958Y380366D01*
X623998Y400031D01*
X677671Y451233D01*
X714929Y467707D01*
X731472Y473045D01*
X740575Y472563D01*
X766056Y470575D01*
X897033Y454842D01*
X976557Y468385D01*
X1018654Y458469D01*
X1052190Y460121D01*
X1094618Y456047D01*
X1146163Y462026D01*
X1151089Y462597D01*
X1219457Y447021D01*
X1267569Y402569D01*
X1267600Y402541D01*
X1267615Y402527D01*
X1272294Y394023D01*
X1272865Y386503D01*
X1269341Y369200D01*
X1261339Y329906D01*
X1258524Y322500D01*
X1256909Y318253D01*
X1256865Y316696D01*
X1256278Y316140D01*
X1256252Y315238D01*
X1256810Y314653D01*
X1256800Y314300D01*
X1256784Y313752D01*
X1256196Y313196D01*
X1256170Y312294D01*
X1256728Y311709D01*
X1256702Y310808D01*
X1256114Y310252D01*
X1256088Y309350D01*
X1256646Y308765D01*
X1256620Y307864D01*
X1256032Y307308D01*
X1256006Y306406D01*
X1256564Y305821D01*
X1256538Y304920D01*
X1255950Y304364D01*
X1255924Y303462D01*
X1256482Y302877D01*
X1256456Y301976D01*
X1255868Y301420D01*
X1255842Y300518D01*
X1256400Y299933D01*
X1256374Y299032D01*
X1255786Y298476D01*
X1255760Y297574D01*
X1256318Y296989D01*
X1256292Y296088D01*
X1255704Y295532D01*
X1255678Y294630D01*
X1256236Y294044D01*
X1256150Y290815D01*
X1248137Y269400D01*
X1244084Y258568D01*
X1222504Y239178D01*
X1220374D01*
G01X571809Y298489D02*
X574364D01*
X578355Y300114D01*
X587997Y310201D01*
X598886Y350361D01*
X623332Y379291D01*
X626356Y398852D01*
X674977Y445237D01*
X675452Y445590D01*
X680682Y449485D01*
X683558Y450781D01*
X684153Y450555D01*
X685385Y451110D01*
X685610Y451706D01*
X686840Y452260D01*
X687436Y452034D01*
X688667Y452589D01*
X688893Y453185D01*
X690123Y453739D01*
X690719Y453513D01*
X691950Y454068D01*
X692175Y454662D01*
X715701Y465261D01*
X731555Y470375D01*
X763497Y468201D01*
X775652Y466975D01*
X897258Y452334D01*
X976477Y465824D01*
X1018423Y455944D01*
X1052131Y457604D01*
X1094639Y453522D01*
X1146163Y459496D01*
X1150953Y460051D01*
X1218242Y444724D01*
X1265624Y400938D01*
X1265735Y400735D01*
X1269600Y393712D01*
X1269832Y393290D01*
X1269831D01*
X1270335Y386662D01*
X1266779Y369200D01*
X1259287Y332403D01*
X1255523Y322500D01*
X1253642Y317552D01*
X1253599Y316021D01*
X1253043Y315494D01*
X1253017Y314592D01*
X1253295Y314300D01*
X1253545Y314037D01*
X1253519Y313137D01*
X1252963Y312610D01*
X1252937Y311708D01*
X1253465Y311153D01*
X1253439Y310253D01*
X1252883Y309726D01*
X1252857Y308824D01*
X1253385Y308269D01*
X1253359Y307369D01*
X1252803Y306842D01*
X1252777Y305940D01*
X1253305Y305385D01*
X1253279Y304485D01*
X1252750Y303984D01*
X1252723Y303958D01*
X1252697Y303056D01*
X1252750Y303000D01*
X1253225Y302501D01*
X1253199Y301601D01*
X1252750Y301175D01*
X1252643Y301074D01*
X1252617Y300172D01*
X1252750Y300032D01*
X1253145Y299617D01*
X1253119Y298717D01*
X1252750Y298367D01*
X1252563Y298190D01*
X1252537Y297288D01*
X1252750Y297064D01*
X1253065Y296733D01*
X1253039Y295833D01*
X1252750Y295559D01*
X1252483Y295306D01*
X1252457Y294404D01*
X1252985Y293849D01*
X1252959Y292949D01*
X1252750Y292751D01*
X1252403Y292422D01*
X1252377Y291520D01*
X1252905Y290965D01*
X1252859Y289234D01*
X1252750Y288943D01*
X1245426Y269400D01*
X1241894Y259975D01*
X1221555Y241700D01*
X1217226D01*
X1216700Y242226D01*
Y242706D01*
X1217476Y243482D01*
G01X560275Y298315D02*
X560725D01*
X564832Y302422D01*
X573127D01*
X575571Y303390D01*
X585042Y313299D01*
X595564Y352101D01*
X619870Y380862D01*
X622921Y400593D01*
X677022Y452204D01*
X714518Y468784D01*
X714575Y468802D01*
X731321Y474205D01*
X740636Y473712D01*
X740650Y473711D01*
X766169Y471720D01*
X897004Y456004D01*
X976594Y469558D01*
X1018760Y459626D01*
X1052217Y461274D01*
X1094607Y457204D01*
X1122721Y460466D01*
Y460465D01*
X1146163Y463184D01*
X1151152Y463763D01*
X1151344Y463720D01*
Y463719D01*
X1220012Y448075D01*
X1268383Y403383D01*
X1268533Y403245D01*
X1269600Y401306D01*
X1273422Y394359D01*
X1274024Y386430D01*
X1270865Y370919D01*
X1270515Y369200D01*
X1262448Y329585D01*
X1259755Y322500D01*
X1258054Y318026D01*
X1257951Y314300D01*
X1257345Y292399D01*
X1257343Y292400D01*
X1257295Y290592D01*
X1249366Y269400D01*
X1245063Y257900D01*
X1223470Y238500D01*
X1223223Y238277D01*
X1222945Y238028D01*
X1220374D01*
G01X1026374Y197475D02*
X1025819Y196514D01*
X1019089Y189785D01*
X1005606D01*
X1002377Y193014D01*
X979809D01*
X977573Y195250D01*
X959939D01*
X952963Y188274D01*
X821967D01*
X819450Y185757D01*
X808996D01*
X806739Y183500D01*
X796424D01*
X786132Y193792D01*
X766969D01*
X765677Y192500D01*
X740028D01*
X724250Y208278D01*
Y228685D01*
X714535Y238400D01*
X704104D01*
X702489Y240015D01*
X698773D01*
X696185Y242603D01*
Y263635D01*
X692697Y267123D01*
Y278732D01*
X697100Y283135D01*
Y290983D01*
X691150Y296933D01*
Y301360D01*
X693433Y303643D01*
X695414D01*
X697120Y305349D01*
G01X1025378Y198050D02*
X1024898Y197221D01*
X1018612Y190935D01*
X1017597D01*
X1016947Y191585D01*
X1015597D01*
X1014947Y190935D01*
X1013597D01*
X1012947Y191585D01*
X1011597D01*
X1010947Y190935D01*
X1009597D01*
X1008947Y191585D01*
X1007597D01*
X1006947Y190935D01*
X1006083D01*
X1002854Y194164D01*
X980286D01*
X978050Y196400D01*
X959462D01*
X952486Y189424D01*
X821490D01*
X818973Y186907D01*
X808519D01*
X806262Y184650D01*
X796901D01*
X786609Y194942D01*
X766492D01*
X765200Y193650D01*
X740505D01*
X725400Y208755D01*
Y229162D01*
X722298Y232264D01*
Y233183D01*
X721343Y234138D01*
X720424D01*
X719470Y235092D01*
Y236012D01*
X718516Y236966D01*
X717596D01*
X715012Y239550D01*
X704581D01*
X702966Y241165D01*
X699250D01*
X697335Y243080D01*
Y244430D01*
X697985Y245080D01*
Y246430D01*
X697335Y247080D01*
Y248430D01*
X697985Y249080D01*
Y250430D01*
X697335Y251080D01*
Y252430D01*
X697985Y253080D01*
Y254430D01*
X697335Y255080D01*
Y256430D01*
X697985Y257080D01*
Y258430D01*
X697335Y259080D01*
Y264112D01*
X693847Y267600D01*
Y278255D01*
X698250Y282658D01*
Y291460D01*
X692300Y297410D01*
Y300883D01*
X693910Y302493D01*
X694976D01*
X697120Y300349D01*
G01X1028357Y203420D02*
X1026310Y201883D01*
X1019246D01*
X1013663Y196300D01*
X981473D01*
X979323Y198450D01*
X959228D01*
X952528Y191750D01*
X821278D01*
X818496Y188968D01*
X795866D01*
X787764Y197070D01*
X763870D01*
X762550Y195750D01*
X743844D01*
X727350Y212244D01*
Y230917D01*
X722595Y235672D01*
Y244223D01*
X724940Y246568D01*
X725903D01*
X728202Y248867D01*
Y251028D01*
X724760Y254470D01*
X711260D01*
X706600Y259130D01*
Y268199D01*
X700636Y274163D01*
Y295617D01*
X699495Y296758D01*
Y306994D01*
X696051Y310438D01*
X688939D01*
X683650Y315727D01*
Y333823D01*
X670918Y346555D01*
Y350298D01*
X670010Y351206D01*
X669194D01*
G01X1027666Y204340D02*
X1025926Y203033D01*
X1018769D01*
X1013186Y197450D01*
X1011836D01*
X1011186Y198100D01*
X1009836D01*
X1009186Y197450D01*
X1007836D01*
X1007186Y198100D01*
X1005836D01*
X1005186Y197450D01*
X1003836D01*
X1003186Y198100D01*
X1001836D01*
X1001186Y197450D01*
X999836D01*
X999186Y198100D01*
X997836D01*
X997186Y197450D01*
X981950D01*
X979800Y199600D01*
X958751D01*
X952051Y192900D01*
X820801D01*
X818019Y190118D01*
X796343D01*
X788241Y198220D01*
X763393D01*
X762073Y196900D01*
X744321D01*
X728500Y212721D01*
Y231394D01*
X723745Y236149D01*
Y243746D01*
X725417Y245418D01*
X726380D01*
X729352Y248390D01*
Y251505D01*
X725237Y255620D01*
X711737D01*
X707750Y259607D01*
Y268676D01*
X701786Y274640D01*
Y296094D01*
X700645Y297235D01*
Y307471D01*
X696528Y311588D01*
X689416D01*
X684800Y316204D01*
Y334300D01*
X672068Y347032D01*
Y350418D01*
X672856Y351206D01*
X674194D01*
G01X1004783Y201816D02*
X1000795D01*
X999398Y200419D01*
X985730D01*
X980999Y205150D01*
X967300D01*
X964450Y202300D01*
X961250D01*
X960600Y202950D01*
X955550D01*
X947200Y194600D01*
X941595D01*
X940959Y195236D01*
X819112D01*
X815996Y192120D01*
X797328D01*
X789091Y200357D01*
X761757D01*
X760250Y198850D01*
X745246D01*
X730450Y213646D01*
Y228900D01*
X731742Y230192D01*
Y243572D01*
X733320Y245150D01*
Y254553D01*
X725753Y262120D01*
X719099D01*
X712777Y268442D01*
Y283124D01*
X706935Y288966D01*
Y295028D01*
X702683Y299280D01*
Y308211D01*
X696131Y314763D01*
X693510D01*
X690723Y317550D01*
Y335637D01*
X681210Y345150D01*
Y350170D01*
X680174Y351206D01*
X679194D01*
G01X1004783Y202966D02*
X1000318D01*
X998921Y201569D01*
X986207D01*
X981476Y206300D01*
X966823D01*
X963973Y203450D01*
X961727D01*
X961077Y204100D01*
X955073D01*
X946723Y195750D01*
X942072D01*
X941436Y196386D01*
X937438D01*
X936788Y197036D01*
X935438D01*
X934788Y196386D01*
X933438D01*
X932788Y197036D01*
X931438D01*
X930788Y196386D01*
X929438D01*
X928788Y197036D01*
X927438D01*
X926788Y196386D01*
X818635D01*
X815519Y193270D01*
X797805D01*
X789568Y201507D01*
X761280D01*
X759773Y200000D01*
X745723D01*
X731600Y214123D01*
Y228423D01*
X732892Y229715D01*
Y243095D01*
X734470Y244673D01*
Y255030D01*
X726230Y263270D01*
X719576D01*
X713927Y268919D01*
Y283601D01*
X708085Y289443D01*
Y295505D01*
X703833Y299757D01*
Y308688D01*
X696608Y315913D01*
X693987D01*
X691873Y318027D01*
Y336114D01*
X687054Y340933D01*
Y341852D01*
X686099Y342807D01*
X685180D01*
X682360Y345627D01*
Y350330D01*
X683236Y351206D01*
X684194D01*
G01X1088815Y401429D02*
X1084844Y405400D01*
X1053173D01*
X1046923Y399150D01*
X997596D01*
X992996Y394550D01*
X971978D01*
X969178Y397350D01*
X959706D01*
X944649Y403574D01*
X917779D01*
X910941Y396736D01*
X901034D01*
X899911Y395613D01*
Y393509D01*
X901034Y392386D01*
X909145D01*
X909595Y391936D01*
Y390786D01*
X909145Y390336D01*
X899507D01*
X888780Y401063D01*
X864581Y406908D01*
X864580D01*
X840562Y412710D01*
X804062D01*
X799352Y408000D01*
X794200D01*
X790060Y403860D01*
X776541D01*
X773901Y406500D01*
X770673D01*
X767666Y403493D01*
X762130D01*
X759066Y400429D01*
X746602D01*
X716299Y370126D01*
Y322191D01*
X707963Y313855D01*
X706424D01*
X704404Y315875D01*
G01X1088002Y400614D02*
X1084366Y404250D01*
X1082966D01*
X1082316Y403600D01*
X1080916D01*
X1080266Y404250D01*
X1078866D01*
X1078216Y403600D01*
X1076816D01*
X1076166Y404250D01*
X1053650D01*
X1047400Y398000D01*
X998073D01*
X993473Y393400D01*
X971501D01*
X968701Y396200D01*
X959477D01*
X944420Y402424D01*
X918256D01*
X911418Y395586D01*
X901511D01*
X901061Y395136D01*
Y393986D01*
X901511Y393536D01*
X909622D01*
X910745Y392413D01*
Y390309D01*
X909622Y389186D01*
X899030D01*
X888195Y400020D01*
X840425Y411560D01*
X804539D01*
X799829Y406850D01*
X794677D01*
X790537Y402710D01*
X776064D01*
X773424Y405350D01*
X771150D01*
X768143Y402343D01*
X762607D01*
X759543Y399279D01*
X747079D01*
X717449Y369649D01*
Y321714D01*
X708440Y312705D01*
X706234D01*
X704404Y310875D01*
G01X1104403Y405519D02*
X1099172Y410750D01*
X1050835D01*
X1045730Y405645D01*
X995374D01*
X987179Y397450D01*
X974177D01*
X972936Y398690D01*
X953627Y406685D01*
X898072D01*
X896949Y405562D01*
Y403458D01*
X898072Y402335D01*
X908490D01*
X908940Y401885D01*
Y400735D01*
X908490Y400285D01*
X895514D01*
X891257Y404541D01*
X829275Y418750D01*
X800112D01*
X788322Y406960D01*
X777940D01*
X774900Y410000D01*
X769579D01*
X766425Y406846D01*
X760978D01*
X757792Y403660D01*
X745333D01*
X708889Y367216D01*
Y332858D01*
X699556Y323525D01*
X697972D01*
X697521Y323976D01*
Y325500D01*
G01X1103589Y404705D02*
X1098695Y409600D01*
X1090972D01*
X1090322Y408950D01*
X1088972D01*
X1088322Y409600D01*
X1086972D01*
X1086322Y408950D01*
X1084972D01*
X1084322Y409600D01*
X1051312D01*
X1046207Y404495D01*
X995851D01*
X987656Y396300D01*
X973700D01*
X972285Y397714D01*
X953398Y405535D01*
X898549D01*
X898099Y405085D01*
Y403935D01*
X898549Y403485D01*
X908967D01*
X910090Y402362D01*
Y400258D01*
X908967Y399135D01*
X895036D01*
X890677Y403493D01*
X829144Y417600D01*
X800589D01*
X788799Y405810D01*
X777463D01*
X774423Y408850D01*
X770056D01*
X766902Y405696D01*
X761455D01*
X758269Y402510D01*
X745810D01*
X710039Y366739D01*
Y332381D01*
X700033Y322375D01*
X697971D01*
X697521Y321925D01*
Y320500D01*
G01X1117919Y410888D02*
X1116630Y412177D01*
X1103595D01*
X1101833Y413939D01*
X1047740D01*
X1043374Y409573D01*
X994653D01*
X991037Y405957D01*
X964298D01*
X954299Y410096D01*
X882397D01*
X831116Y421850D01*
X798827D01*
X787037Y410060D01*
X779257D01*
X776167Y413150D01*
X768344D01*
X765140Y409946D01*
X759597D01*
X756485Y406834D01*
X744107D01*
X703961Y366688D01*
Y338461D01*
X699075Y333575D01*
X697802D01*
X697352Y334025D01*
Y335500D01*
G01X1117105Y410075D02*
X1116153Y411027D01*
X1114803D01*
X1114153Y410377D01*
X1112803D01*
X1112153Y411027D01*
X1103118D01*
X1101356Y412789D01*
X1048217D01*
X1043851Y408423D01*
X995130D01*
X991514Y404807D01*
X964069D01*
X954070Y408946D01*
X882266D01*
X830985Y420700D01*
X799304D01*
X787514Y408910D01*
X778780D01*
X775690Y412000D01*
X768821D01*
X765617Y408796D01*
X760074D01*
X756962Y405684D01*
X744584D01*
X705111Y366211D01*
Y341984D01*
X705761Y341334D01*
Y339984D01*
X705111Y339334D01*
Y337984D01*
X699552Y332425D01*
X697802D01*
X697352Y331975D01*
Y330500D01*
G01X752900Y521121D02*
X753375Y520646D01*
X757329D01*
X758650Y519325D01*
Y505307D01*
X760642Y503315D01*
X764969Y502518D01*
X834626D01*
X873613Y507949D01*
X968815D01*
X971920Y504844D01*
X1011835Y499813D01*
X1041289D01*
X1080576Y494330D01*
X1084895D01*
X1131044Y508450D01*
X1272766D01*
X1273216Y508000D01*
X1276718D01*
X1294593Y503140D01*
X1307119Y495844D01*
X1313045D01*
X1331129Y491597D01*
X1348314D01*
X1354398Y497681D01*
Y501212D01*
X1359221Y506035D01*
X1378236D01*
X1379651Y507450D01*
X1392208D01*
X1411960Y502173D01*
X1439272D01*
X1442958Y500759D01*
X1454963Y488753D01*
Y484036D01*
X1457799Y481200D01*
X1459700D01*
X1475150Y465750D01*
Y458977D01*
X1480150Y453977D01*
Y442942D01*
G01X752900Y518621D02*
X753775Y519496D01*
X756852D01*
X757500Y518848D01*
Y517130D01*
X756850Y516480D01*
Y515080D01*
X757500Y514430D01*
Y513030D01*
X756850Y512380D01*
Y510980D01*
X757500Y510330D01*
Y508930D01*
X756850Y508280D01*
Y506880D01*
X757500Y506230D01*
Y504830D01*
X760081Y502248D01*
X764863Y501368D01*
X834706D01*
X873693Y506799D01*
X968338D01*
X971385Y503752D01*
X1011762Y498663D01*
X1041209D01*
X1080496Y493180D01*
X1085067D01*
X1131216Y507300D01*
X1272289D01*
X1272739Y506850D01*
X1276564D01*
X1294145Y502070D01*
X1306808Y494694D01*
X1312911D01*
X1330995Y490447D01*
X1348791D01*
X1355548Y497204D01*
Y500735D01*
X1359698Y504885D01*
X1378713D01*
X1380128Y506300D01*
X1392057D01*
X1411809Y501023D01*
X1439058D01*
X1442317Y499772D01*
X1453813Y488276D01*
Y483559D01*
X1457322Y480050D01*
X1459223D01*
X1474000Y465273D01*
Y458500D01*
X1479000Y453500D01*
Y442942D01*
G01X1109136Y-43700D02*
X914500D01*
G03Y-46250I0J-1275D01*
G01X1109045D01*
G02Y-51100I0J-2425D01*
G01X909373D01*
X905905Y-47632D01*
X863409D01*
X858984Y-52057D01*
G01X1109136Y-42550D02*
X914500D01*
G03Y-47400I0J-2425D01*
G01X1109045D01*
G02Y-49950I0J-1275D01*
G01X909850D01*
X906382Y-46482D01*
X863409D01*
X858984Y-42057D01*
G01X1271662Y487326D02*
Y486680D01*
X1269930Y484948D01*
X1269749D01*
X1269079Y484278D01*
X1265737D01*
X1251101Y480096D01*
X1247993Y477664D01*
X1244831Y470517D01*
X1247291Y461613D01*
X1244309Y452328D01*
X1244308D01*
X1249480Y442025D01*
X1280553Y413319D01*
X1288526Y398822D01*
X1288538Y398666D01*
X1289495Y386115D01*
X1287261Y375604D01*
X1288125Y371535D01*
X1279002Y328572D01*
X1279003D01*
X1281508Y318326D01*
X1278686Y305043D01*
X1279904Y299307D01*
X1278650Y293397D01*
X1280825Y283160D01*
X1278739Y273338D01*
X1283319Y250823D01*
X1285300Y247831D01*
X1285350Y247755D01*
X1285914Y244983D01*
X1284092Y235876D01*
X1285680Y227930D01*
X1285241Y225735D01*
X1292953Y205144D01*
X1313769Y190167D01*
X1331986Y186462D01*
X1341720Y188441D01*
X1400645Y172644D01*
X1405345Y169565D01*
X1407778Y164977D01*
X1413564Y136870D01*
X1423997Y124016D01*
X1425120Y118399D01*
X1424341Y114504D01*
X1427235Y100033D01*
X1434385Y95254D01*
X1440652Y65313D01*
X1448155Y51308D01*
X1448154D01*
X1448156Y51306D01*
X1457144Y44262D01*
X1461580Y43317D01*
X1461925Y42785D01*
X1461572Y41125D01*
X1462439Y39794D01*
X1464252Y39406D01*
X1465584Y40272D01*
X1465937Y41932D01*
X1466469Y42278D01*
X1493861Y36461D01*
X1497257Y37182D01*
X1539862Y28137D01*
X1542987Y28800D01*
X1558856Y25432D01*
X1589713Y13917D01*
X1593834Y14759D01*
X1597547Y14018D01*
X1608118Y16130D01*
X1614200Y14839D01*
X1622192Y16536D01*
X1633276Y14183D01*
X1654911Y18777D01*
X1659576Y17785D01*
X1664299Y18789D01*
X1668936Y17805D01*
X1673496Y18774D01*
X1678669Y17675D01*
X1683703Y18746D01*
X1687959Y17840D01*
X1692592Y18825D01*
X1698883Y17487D01*
X1703000Y18688D01*
X1707186Y17797D01*
X1731352Y28421D01*
X1750673D01*
X1754035Y31783D01*
X1756357D01*
X1756895Y31245D01*
Y30452D01*
G01X1752000Y38865D02*
X1753011D01*
X1754842Y40696D01*
X1758911D01*
X1760932Y38675D01*
X1761459Y37523D01*
X1762020Y34956D01*
X1759265Y28284D01*
X1757519Y26531D01*
X1753228Y25539D01*
X1731009D01*
X1707378Y15149D01*
X1703098Y16060D01*
X1698897Y14834D01*
X1692494Y16197D01*
X1687973Y15237D01*
X1683718Y16142D01*
X1678771Y15090D01*
X1673597Y16189D01*
X1669001Y15212D01*
X1664364Y16196D01*
X1659679Y15200D01*
X1655013Y16192D01*
X1653280Y15823D01*
X1652235Y15051D01*
X1649897Y10855D01*
X1643798Y6398D01*
X1641036Y2318D01*
X1636169Y481D01*
X1631018Y1860D01*
X1626314Y650D01*
X1619288Y2783D01*
X1610054Y16D01*
X1605218Y1508D01*
X1600319Y4776D01*
X1596870Y5974D01*
X1591959Y4991D01*
X1573632Y8652D01*
X1568396Y7606D01*
X1562050Y8877D01*
X1553552Y7179D01*
X1547154Y8457D01*
X1538568Y6740D01*
X1525704Y9314D01*
X1495004Y29781D01*
X1485140Y31875D01*
X1480388Y30866D01*
X1475597Y31885D01*
X1469934Y30753D01*
X1465949Y31549D01*
X1461918Y30743D01*
X1455114Y32104D01*
X1438551Y63011D01*
X1432144Y93704D01*
X1424916Y98523D01*
X1421736Y114430D01*
X1421735D01*
X1421691Y114655D01*
X1422295Y117674D01*
X1421219Y123050D01*
X1411347Y135218D01*
X1405458Y163830D01*
X1403334Y167834D01*
X1399585Y170291D01*
X1341855Y185763D01*
X1331990Y183756D01*
X1312457Y187731D01*
X1291045Y203134D01*
X1281380Y217626D01*
X1279766Y223128D01*
X1279994Y224891D01*
X1282032Y227946D01*
X1282439Y229967D01*
X1281309Y235617D01*
X1283246Y245306D01*
X1282965Y246685D01*
X1280890Y249825D01*
X1276139Y273176D01*
X1278259Y283160D01*
X1276084Y293397D01*
X1277338Y299307D01*
X1276120Y305043D01*
X1278937Y318300D01*
X1276357Y328849D01*
X1285362Y371262D01*
X1285300Y371554D01*
X1284567Y375002D01*
X1285980Y381656D01*
X1286842Y385716D01*
X1285980Y397057D01*
X1285900Y398110D01*
X1285594Y398666D01*
X1285300Y399200D01*
X1278262Y411992D01*
X1247173Y440714D01*
X1241453Y452106D01*
Y475576D01*
X1248930Y486498D01*
X1252562Y489010D01*
X1255210D01*
X1256320Y490120D01*
Y490660D01*
G01X1271647Y482500D02*
Y483430D01*
X1271280Y483797D01*
X1270829D01*
X1270655Y483798D01*
X1270226D01*
X1269556Y483128D01*
X1265899D01*
X1251633Y479051D01*
X1248929Y476935D01*
X1246049Y470427D01*
X1248491Y461588D01*
X1245548Y452423D01*
X1250414Y442728D01*
X1281471Y414037D01*
X1289654Y399160D01*
X1289692Y398666D01*
X1290655Y386038D01*
X1288437Y375604D01*
X1289301Y371535D01*
X1280182Y328592D01*
X1280183Y328589D01*
X1282688Y318344D01*
X1279862Y305043D01*
X1281080Y299307D01*
X1279826Y293397D01*
X1282001Y283160D01*
X1279914Y273333D01*
X1284402Y251272D01*
X1285300Y249915D01*
X1286433Y248204D01*
X1287088Y244985D01*
X1286823Y243661D01*
X1287333Y242896D01*
X1287068Y241573D01*
X1286303Y241063D01*
X1285265Y235876D01*
X1285980Y232299D01*
X1286042Y231989D01*
X1286806Y231479D01*
X1287071Y230156D01*
X1286561Y229391D01*
X1286853Y227930D01*
X1286434Y225831D01*
X1293908Y205874D01*
X1314240Y191245D01*
X1331986Y187636D01*
X1341756Y189622D01*
X1401121Y173708D01*
X1406223Y170366D01*
X1408872Y165371D01*
X1414634Y137377D01*
X1425070Y124521D01*
X1426293Y118399D01*
X1425514Y114504D01*
X1428270Y100725D01*
Y100726D01*
X1435415Y95950D01*
X1441744Y65710D01*
X1449056Y52062D01*
X1451347Y50267D01*
X1452260Y50377D01*
X1453322Y49545D01*
X1453433Y48632D01*
X1454496Y47799D01*
X1455408Y47910D01*
X1456471Y47077D01*
X1456581Y46165D01*
X1457644Y45332D01*
X1462285Y44343D01*
X1463150Y43012D01*
X1462797Y41353D01*
X1463144Y40820D01*
X1464026Y40631D01*
X1464558Y40977D01*
X1464911Y42637D01*
X1466242Y43502D01*
X1493861Y37637D01*
X1497257Y38358D01*
X1539862Y29313D01*
X1542987Y29976D01*
X1547322Y29056D01*
X1548093Y29557D01*
X1549413Y29277D01*
X1549914Y28506D01*
X1551235Y28226D01*
X1552006Y28727D01*
X1553326Y28446D01*
X1553827Y27675D01*
X1559178Y26540D01*
X1589806Y15110D01*
X1593831Y15933D01*
X1597547Y15191D01*
X1608125Y17305D01*
X1614200Y16015D01*
X1622192Y17712D01*
X1633276Y15359D01*
X1654911Y19953D01*
X1659576Y18961D01*
X1664299Y19965D01*
X1668936Y18981D01*
X1673496Y19950D01*
X1678669Y18851D01*
X1683703Y19922D01*
X1687959Y19016D01*
X1692592Y20001D01*
X1698839Y18673D01*
X1702956Y19874D01*
X1707063Y19000D01*
X1731110Y29571D01*
X1750196D01*
X1753558Y32933D01*
X1756292D01*
X1756895Y33536D01*
Y34252D01*
G01X1755400Y37700D02*
X1754646Y38454D01*
Y38873D01*
X1755319Y39546D01*
X1758434D01*
X1759972Y38008D01*
X1760361Y37157D01*
X1760819Y35062D01*
X1758289Y28934D01*
X1756937Y27578D01*
X1753096Y26689D01*
X1730767D01*
X1707254Y16352D01*
X1703054Y17246D01*
X1698853Y16020D01*
X1692494Y17373D01*
X1687973Y16413D01*
X1683718Y17318D01*
X1678771Y16266D01*
X1673597Y17365D01*
X1669001Y16388D01*
X1664364Y17372D01*
X1659679Y16376D01*
X1655013Y17368D01*
X1652796Y16897D01*
X1651351Y15828D01*
X1649015Y11635D01*
X1647925Y10839D01*
X1647017Y10980D01*
X1645927Y10184D01*
X1645785Y9275D01*
X1642957Y7209D01*
X1640288Y3265D01*
X1636109Y1688D01*
X1631024Y3049D01*
X1626340Y1845D01*
X1619290Y3985D01*
X1610059Y1219D01*
X1607888Y1888D01*
Y1887D01*
X1605717Y2558D01*
X1600835Y5815D01*
X1596952Y7164D01*
X1591958Y6164D01*
X1590148Y6525D01*
X1589638Y7290D01*
X1588314Y7555D01*
X1587550Y7045D01*
X1586226Y7309D01*
X1585716Y8074D01*
X1584392Y8339D01*
X1583627Y7829D01*
X1573632Y9825D01*
X1568396Y8779D01*
X1562050Y10050D01*
X1553552Y8352D01*
X1547154Y9630D01*
X1538568Y7913D01*
X1526152Y10398D01*
X1525029Y11147D01*
X1524848Y12048D01*
X1523725Y12797D01*
X1522824Y12617D01*
X1521701Y13366D01*
X1521520Y14267D01*
X1520397Y15016D01*
X1519496Y14836D01*
X1518373Y15585D01*
X1518192Y16486D01*
X1517069Y17235D01*
X1516168Y17055D01*
X1515045Y17804D01*
X1514864Y18705D01*
X1513741Y19454D01*
X1512840Y19274D01*
X1495459Y30861D01*
X1485140Y33051D01*
X1480388Y32042D01*
X1475604Y33060D01*
X1469934Y31926D01*
X1465949Y32722D01*
X1461918Y31916D01*
X1455872Y33126D01*
X1439643Y63408D01*
X1433174Y94400D01*
X1425951Y99216D01*
X1422864Y114655D01*
X1423468Y117674D01*
X1422291Y123556D01*
X1412417Y135725D01*
X1406552Y164224D01*
X1404212Y168635D01*
X1400061Y171355D01*
X1341891Y186944D01*
X1331990Y184930D01*
X1312928Y188809D01*
X1291886Y203946D01*
X1289092Y208135D01*
X1289272Y209037D01*
X1288523Y210160D01*
X1287622Y210340D01*
Y210341D01*
X1286873Y211464D01*
X1287053Y212364D01*
X1286304Y213488D01*
X1285980Y213553D01*
X1285403Y213668D01*
X1285300Y213822D01*
X1284654Y214791D01*
X1284834Y215692D01*
X1284085Y216816D01*
X1283184Y216996D01*
X1282435Y218119D01*
X1280938Y223220D01*
X1281101Y224476D01*
X1283115Y227497D01*
X1283612Y229966D01*
X1282482Y235617D01*
X1284420Y245308D01*
X1284048Y247133D01*
X1281973Y250273D01*
X1277314Y273171D01*
X1279435Y283160D01*
X1277260Y293397D01*
X1278514Y299307D01*
X1277296Y305043D01*
X1280117Y318318D01*
X1277537Y328867D01*
X1285980Y368635D01*
X1286538Y371263D01*
X1285980Y373887D01*
X1285743Y375002D01*
X1288002Y385639D01*
X1287028Y398446D01*
X1286907Y398666D01*
X1279180Y412710D01*
X1248107Y441417D01*
Y441418D01*
X1242603Y452379D01*
Y453729D01*
X1243253Y454379D01*
Y455729D01*
X1242603Y456379D01*
Y457729D01*
X1243253Y458379D01*
Y459729D01*
X1242603Y460379D01*
Y461729D01*
X1243253Y462379D01*
Y463729D01*
X1242603Y464379D01*
Y465729D01*
X1243253Y466379D01*
Y467729D01*
X1242603Y468379D01*
Y475220D01*
X1243366Y476334D01*
X1244269Y476503D01*
X1245032Y477617D01*
X1244863Y478521D01*
X1245626Y479635D01*
X1246529Y479804D01*
X1247292Y480918D01*
X1247123Y481822D01*
X1249759Y485673D01*
X1252921Y487860D01*
X1255700D01*
X1256350Y487210D01*
Y486080D01*
G01X1322260Y477492D02*
Y476916D01*
X1320728Y475384D01*
X1304328D01*
X1302305Y473361D01*
X1281813D01*
X1272439Y463987D01*
Y434916D01*
X1289806Y418870D01*
X1298952Y402245D01*
X1300066Y387568D01*
X1297751Y376661D01*
X1299035Y370609D01*
X1290090Y328475D01*
X1292144Y320072D01*
X1288950Y305042D01*
X1290168Y299308D01*
X1288914Y293399D01*
X1291089Y283160D01*
X1289890Y277516D01*
X1300969Y223058D01*
X1310455Y205555D01*
X1318006Y200124D01*
X1331989Y197278D01*
X1340973Y199105D01*
X1405105Y181913D01*
X1413532Y176396D01*
X1417465Y168980D01*
X1423048Y141852D01*
X1433984Y128372D01*
X1435801Y119301D01*
X1434899Y114787D01*
X1436621Y106168D01*
X1443540Y101561D01*
X1449849Y72527D01*
X1457596Y58254D01*
X1463975Y53245D01*
X1493914Y46883D01*
X1497314Y47605D01*
X1526079Y41498D01*
X1542092Y44902D01*
X1566548Y39706D01*
X1570363Y33980D01*
X1582675Y29385D01*
X1590497Y31044D01*
X1615999Y25632D01*
X1635840Y29848D01*
X1642275Y28481D01*
X1645368Y29138D01*
X1649983Y28158D01*
X1654676Y29155D01*
X1659340Y28163D01*
X1664232Y29202D01*
X1668869Y28218D01*
X1673179Y29134D01*
X1678351Y28036D01*
X1683580Y29148D01*
X1687838Y28243D01*
X1692406Y29213D01*
X1698337Y27952D01*
X1702588Y29193D01*
X1706296Y28403D01*
X1716957Y33089D01*
X1720433Y36566D01*
Y39234D01*
X1721079Y39880D01*
X1721758D01*
G01X1262700Y461804D02*
Y463137D01*
X1263150Y463587D01*
X1266692D01*
X1268545Y461734D01*
Y460080D01*
X1268095Y459630D01*
X1265907D01*
X1264784Y458507D01*
Y456503D01*
X1265907Y455380D01*
X1268095D01*
X1268545Y454930D01*
Y453880D01*
X1268095Y453430D01*
X1265907D01*
X1264784Y452307D01*
Y450303D01*
X1265907Y449180D01*
X1268095D01*
X1268545Y448730D01*
Y447680D01*
X1268095Y447230D01*
X1265907D01*
X1264784Y446107D01*
Y444103D01*
X1265907Y442980D01*
X1268095D01*
X1268545Y442530D01*
Y436864D01*
X1270376Y433217D01*
X1287785Y417133D01*
X1287786D01*
X1296238Y401772D01*
X1297366Y386931D01*
X1295114Y376332D01*
X1296398Y370291D01*
X1287446Y328130D01*
X1289503Y319718D01*
X1286384Y305042D01*
X1287602Y299308D01*
X1286348Y293398D01*
X1288523Y283160D01*
X1287297Y277391D01*
X1297205Y228692D01*
X1296757Y228018D01*
X1295447Y227750D01*
X1294570Y226426D01*
X1294971Y224463D01*
X1296296Y223584D01*
X1297726Y223875D01*
X1298254Y223526D01*
X1298596Y221842D01*
X1300119Y219059D01*
X1299940Y218452D01*
X1298300Y217562D01*
X1297847Y216040D01*
X1298802Y214277D01*
X1300325Y213824D01*
X1301907Y214681D01*
X1302583Y214480D01*
X1303086Y213552D01*
X1302844Y212742D01*
X1301092Y211791D01*
X1300639Y210269D01*
X1301594Y208506D01*
X1303117Y208053D01*
X1305001Y209074D01*
X1305609Y208894D01*
X1308264Y203995D01*
X1308390Y203762D01*
X1316897Y197644D01*
X1331990Y194573D01*
X1341179Y196443D01*
X1403953Y179619D01*
X1411531Y174658D01*
X1414978Y168160D01*
X1420611Y140787D01*
X1431677Y127149D01*
X1433215Y119478D01*
X1432311Y114954D01*
X1434383Y104591D01*
X1441224Y100037D01*
X1447250Y71914D01*
X1455339Y56822D01*
X1462945Y50859D01*
X1493824Y44294D01*
X1493826D01*
X1497293Y45031D01*
X1526286Y38875D01*
X1542150Y42247D01*
X1547795Y41047D01*
X1548140Y40515D01*
X1547709Y38490D01*
X1548576Y37159D01*
X1550536Y36740D01*
X1551869Y37607D01*
X1552299Y39631D01*
X1552831Y39976D01*
X1556373Y39223D01*
X1561000Y33548D01*
X1581056Y26062D01*
X1591317Y28237D01*
X1615905Y23019D01*
X1635864Y27257D01*
X1642325Y25885D01*
X1645469Y26552D01*
X1650084Y25572D01*
X1654675Y26548D01*
X1659340Y25556D01*
X1664233Y26595D01*
X1668869Y25611D01*
X1673240Y26540D01*
X1678412Y25442D01*
X1683500Y26524D01*
X1687756Y25619D01*
X1692456Y26617D01*
X1698477Y25338D01*
X1702586Y26538D01*
X1706520Y25702D01*
X1727720Y35020D01*
X1729825Y37125D01*
Y38645D01*
X1730645Y39465D01*
X1731183D01*
G01X1258140Y474540D02*
Y473450D01*
X1257315Y472625D01*
X1253425D01*
X1251250Y470450D01*
Y466436D01*
X1252613Y461503D01*
X1249887Y453026D01*
X1253944Y444943D01*
X1285252Y416018D01*
X1285255Y416015D01*
X1285256D01*
X1293712Y400646D01*
X1294767Y386775D01*
X1292517Y376190D01*
X1293450Y371798D01*
X1293448Y371799D01*
X1284427Y329312D01*
X1285980Y322963D01*
X1286860Y319366D01*
X1285980Y315220D01*
X1285300Y312016D01*
X1284021Y305995D01*
X1284008Y305975D01*
X1283819Y305084D01*
X1283823Y305063D01*
X1283819Y305045D01*
Y305044D01*
X1284174Y303362D01*
X1284930Y299810D01*
X1284942Y299791D01*
X1285040Y299329D01*
X1284610Y297302D01*
X1284571Y297117D01*
X1284175Y295250D01*
X1283877Y293848D01*
X1283871Y293825D01*
X1283859Y293803D01*
X1283857Y293794D01*
X1283778Y293420D01*
X1285957Y283160D01*
X1283967Y273791D01*
X1288259Y252685D01*
X1289238Y251206D01*
X1289239Y251205D01*
X1290216Y249728D01*
X1293382Y233573D01*
X1291669Y225009D01*
X1298098Y207895D01*
X1315973Y195032D01*
X1316236Y195074D01*
X1331994Y191869D01*
X1341319Y193768D01*
X1402906Y177260D01*
X1409438Y172980D01*
X1412581Y167052D01*
X1418319Y139183D01*
X1429206Y125768D01*
X1430510Y119250D01*
X1429631Y114854D01*
X1431967Y103175D01*
X1438889Y98554D01*
X1444885Y70628D01*
X1453056Y55382D01*
X1461869Y48476D01*
X1493980Y41656D01*
X1497463Y42396D01*
X1538400Y33703D01*
X1545142Y35136D01*
X1555128Y33014D01*
X1591272Y19526D01*
X1593877Y20057D01*
X1597376Y19356D01*
X1608161Y21510D01*
X1608163Y21511D01*
X1614625Y20141D01*
X1635943Y24671D01*
X1642413Y23297D01*
X1645464Y23944D01*
X1650080Y22964D01*
X1654764Y23960D01*
X1659429Y22968D01*
X1664233Y23989D01*
X1668869Y23004D01*
X1673344Y23955D01*
X1678516Y22857D01*
X1683515Y23919D01*
X1687771Y23014D01*
X1692423Y24003D01*
X1698548Y22702D01*
X1702710Y23917D01*
X1706729Y23061D01*
X1731028Y33741D01*
X1737670D01*
X1739300Y35371D01*
Y38600D01*
X1740186Y39486D01*
X1740598D01*
G01X1271571Y479000D02*
X1269773Y477202D01*
X1267712D01*
X1260488Y479254D01*
X1252490Y477828D01*
X1249989Y475870D01*
X1247532Y470319D01*
X1249952Y461558D01*
X1247243Y453132D01*
X1247242D01*
X1247241Y453127D01*
Y453126D01*
X1247097Y452678D01*
X1247100Y452672D01*
X1251569Y443767D01*
X1251579Y443538D01*
X1283175Y414349D01*
X1291089Y399961D01*
X1291090D01*
X1292122Y386403D01*
X1289861Y375764D01*
X1290727Y371689D01*
X1281592Y328680D01*
X1284098Y318434D01*
X1281253Y305043D01*
X1282470Y299307D01*
X1281216Y293398D01*
X1283391Y283160D01*
X1281408Y273822D01*
X1285905Y251710D01*
X1285980Y251597D01*
X1287857Y248761D01*
X1290798Y233755D01*
X1288765Y223597D01*
X1294419Y208500D01*
X1294425Y208482D01*
X1295054Y206804D01*
X1314677Y192689D01*
X1331990Y189165D01*
X1341552Y191111D01*
X1401725Y174983D01*
X1407443Y171239D01*
X1410104Y166221D01*
X1415924Y137955D01*
X1426706Y124667D01*
X1427870Y118847D01*
X1427041Y114705D01*
X1429660Y101611D01*
X1436619Y96971D01*
X1442925Y67105D01*
X1449513Y54807D01*
X1460304Y46348D01*
X1460303D01*
X1460514Y46183D01*
X1494025Y39066D01*
X1497465Y39796D01*
X1538848Y31007D01*
X1543325Y31959D01*
X1555575Y29357D01*
Y29356D01*
X1555588Y29353D01*
X1555605Y29350D01*
X1589772Y16593D01*
X1589779Y16594D01*
X1593946Y17446D01*
X1593950Y17445D01*
X1597570Y16722D01*
X1607878Y18782D01*
X1614074Y17466D01*
X1622033Y19156D01*
X1628500Y17782D01*
X1633239Y16776D01*
X1654815Y21364D01*
X1659480Y20372D01*
X1664233Y21382D01*
X1668870Y20398D01*
X1673410Y21363D01*
X1678583Y20264D01*
X1683603Y21332D01*
X1687860Y20426D01*
X1692492Y21410D01*
X1698700Y20090D01*
X1702903Y21316D01*
X1706994Y20445D01*
X1731006Y31000D01*
X1747141D01*
X1748975Y32834D01*
Y35474D01*
X1749426Y35925D01*
X1750250D01*
G01X1329419Y469337D02*
Y468526D01*
X1328347Y467454D01*
X1311879D01*
X1309548Y469785D01*
X1285167D01*
X1277925Y462543D01*
Y433644D01*
X1291759Y420869D01*
X1291766Y420855D01*
X1291767D01*
X1301720Y402766D01*
X1301724Y402762D01*
X1302812Y388413D01*
X1300342Y376784D01*
X1301642Y370668D01*
X1292746Y328769D01*
X1294786Y320427D01*
X1291516Y305042D01*
X1292734Y299308D01*
X1291480Y293399D01*
X1293655Y283160D01*
X1292504Y277743D01*
X1302602Y228120D01*
X1314715Y205768D01*
X1319119Y202600D01*
X1331990Y199981D01*
X1340813Y201777D01*
X1406193Y184249D01*
X1406195D01*
X1415394Y178225D01*
X1419951Y169633D01*
X1425396Y143177D01*
X1436872Y129033D01*
X1438641Y120199D01*
X1437843Y116210D01*
X1439601Y107416D01*
X1445824Y103268D01*
X1450678Y81472D01*
X1457903Y76853D01*
X1468198Y61410D01*
X1482309Y52002D01*
X1494030Y49516D01*
X1497255Y50201D01*
X1525961Y44105D01*
X1542298Y47577D01*
X1575354Y40545D01*
X1579498Y34328D01*
X1584460Y32482D01*
X1590221Y33702D01*
X1616036Y28219D01*
X1635892Y32437D01*
X1642259Y31084D01*
X1645402Y31752D01*
X1650017Y30772D01*
X1654676Y31762D01*
X1659341Y30770D01*
X1664232Y31809D01*
X1668868Y30825D01*
X1673178Y31741D01*
X1678350Y30643D01*
X1683558Y31750D01*
X1687815Y30845D01*
X1692510Y31842D01*
X1698326Y30605D01*
X1702493Y31822D01*
X1703695Y31567D01*
X1709188Y33557D01*
X1711000Y36142D01*
Y38800D01*
X1711550Y39350D01*
X1712308D01*
G01X1322360Y472592D02*
Y473340D01*
X1321466Y474234D01*
X1304805D01*
X1302782Y472211D01*
X1282290D01*
X1281335Y471256D01*
Y470337D01*
X1280381Y469383D01*
X1279462D01*
X1278507Y468428D01*
Y467509D01*
X1277553Y466555D01*
X1276634D01*
X1273589Y463510D01*
Y460448D01*
X1274239Y459798D01*
Y458448D01*
X1273589Y457798D01*
Y456448D01*
X1274239Y455798D01*
Y454448D01*
X1273589Y453798D01*
Y435420D01*
X1290724Y419588D01*
X1300080Y402581D01*
X1301226Y387491D01*
X1298927Y376661D01*
X1300211Y370609D01*
X1291270Y328493D01*
X1293324Y320090D01*
X1290126Y305042D01*
X1291344Y299308D01*
X1290090Y293399D01*
X1292265Y283160D01*
X1291065Y277511D01*
X1302062Y223455D01*
X1303717Y220402D01*
X1304598Y220140D01*
X1305241Y218953D01*
X1304980Y218072D01*
X1305623Y216885D01*
X1306504Y216623D01*
X1307147Y215436D01*
X1306886Y214555D01*
X1307529Y213368D01*
X1308410Y213107D01*
X1309053Y211920D01*
X1308792Y211039D01*
X1309435Y209852D01*
X1310316Y209590D01*
X1310959Y208403D01*
X1310698Y207522D01*
X1311341Y206335D01*
X1318477Y201202D01*
X1331989Y198452D01*
X1341009Y200286D01*
X1405581Y182977D01*
X1414410Y177197D01*
X1418559Y169374D01*
X1424118Y142359D01*
X1435056Y128876D01*
X1436974Y119301D01*
X1436072Y114787D01*
X1437656Y106861D01*
X1444566Y102261D01*
X1450939Y72932D01*
X1452770Y69559D01*
X1453651Y69297D01*
X1454295Y68111D01*
X1454034Y67230D01*
X1454678Y66043D01*
X1455559Y65782D01*
X1456203Y64595D01*
X1455942Y63714D01*
X1456586Y62528D01*
X1457467Y62266D01*
X1458111Y61080D01*
X1457850Y60199D01*
X1458494Y59012D01*
X1464476Y54315D01*
X1493914Y48059D01*
X1497314Y48781D01*
X1526079Y42674D01*
X1542092Y46078D01*
X1567245Y40734D01*
X1571114Y34928D01*
X1582764Y30580D01*
X1590497Y32220D01*
X1615999Y26808D01*
X1635840Y31024D01*
X1642275Y29657D01*
X1645368Y30314D01*
X1649983Y29334D01*
X1654676Y30331D01*
X1659340Y29339D01*
X1664232Y30378D01*
X1668869Y29394D01*
X1673179Y30310D01*
X1678351Y29212D01*
X1683580Y30324D01*
X1687838Y29419D01*
X1692406Y30389D01*
X1698293Y29138D01*
X1702544Y30379D01*
X1706173Y29606D01*
X1716296Y34056D01*
X1719283Y37043D01*
Y39318D01*
X1718721Y39880D01*
X1717958D01*
G01X1262900Y466504D02*
Y465187D01*
X1263350Y464737D01*
X1267169D01*
X1269695Y462211D01*
Y459603D01*
X1268572Y458480D01*
X1266384D01*
X1265934Y458030D01*
Y456980D01*
X1266384Y456530D01*
X1268572D01*
X1269695Y455407D01*
Y453403D01*
X1268572Y452280D01*
X1266384D01*
X1265934Y451830D01*
Y450780D01*
X1266384Y450330D01*
X1268572D01*
X1269695Y449207D01*
Y447203D01*
X1268572Y446080D01*
X1266384D01*
X1265934Y445630D01*
Y444580D01*
X1266384Y444130D01*
X1268572D01*
X1269695Y443007D01*
Y437137D01*
X1271310Y433920D01*
X1288704Y417851D01*
X1297366Y402108D01*
X1298526Y386853D01*
X1296290Y376332D01*
X1297574Y370291D01*
X1288626Y328148D01*
X1290683Y319736D01*
X1287560Y305042D01*
X1288778Y299308D01*
X1287524Y293398D01*
X1289699Y283160D01*
X1288472Y277386D01*
X1293378Y253272D01*
Y253271D01*
X1298428Y228453D01*
X1297452Y226986D01*
X1296144Y226718D01*
X1295793Y226188D01*
X1296003Y225159D01*
X1296534Y224807D01*
X1297963Y225098D01*
X1299287Y224223D01*
X1299688Y222243D01*
X1299689Y222241D01*
X1301358Y219192D01*
X1300909Y217668D01*
X1299267Y216778D01*
X1299086Y216169D01*
X1299587Y215244D01*
X1300196Y215063D01*
X1300567Y215264D01*
Y215263D01*
X1301778Y215920D01*
X1303367Y215447D01*
X1304325Y213680D01*
X1303811Y211957D01*
X1302936Y211483D01*
X1302935Y211482D01*
X1302059Y211007D01*
X1301878Y210398D01*
X1302379Y209473D01*
X1302988Y209292D01*
X1303510Y209575D01*
Y209574D01*
X1304871Y210312D01*
X1306393Y209862D01*
X1309276Y204543D01*
Y204542D01*
X1309277Y204541D01*
X1313322Y201632D01*
X1313323D01*
X1317368Y198722D01*
X1331990Y195747D01*
X1341215Y197624D01*
X1404429Y180683D01*
X1412409Y175459D01*
X1416072Y168554D01*
X1421681Y141294D01*
X1432750Y127654D01*
X1434388Y119478D01*
X1433484Y114954D01*
X1435418Y105285D01*
X1442251Y100735D01*
X1448341Y72314D01*
X1456239Y57578D01*
X1463445Y51929D01*
X1493826Y45470D01*
X1497293Y46207D01*
X1526286Y40051D01*
X1542150Y43423D01*
X1548500Y42073D01*
X1549365Y40742D01*
X1548934Y38718D01*
X1549281Y38185D01*
X1550309Y37965D01*
X1550842Y38312D01*
X1551273Y40336D01*
X1552604Y41201D01*
X1557009Y40264D01*
X1561695Y34517D01*
X1565192Y33212D01*
X1566155Y32852D01*
X1566992Y33234D01*
X1568256Y32762D01*
X1568638Y31926D01*
X1569903Y31454D01*
X1570740Y31835D01*
X1572005Y31363D01*
X1572386Y30527D01*
X1573651Y30055D01*
X1574487Y30436D01*
X1575752Y29964D01*
X1576133Y29128D01*
X1577398Y28656D01*
X1578234Y29037D01*
X1579499Y28565D01*
X1579880Y27729D01*
X1581145Y27257D01*
X1591317Y29413D01*
X1615905Y24195D01*
X1635864Y28433D01*
X1642325Y27061D01*
X1645469Y27728D01*
X1650084Y26748D01*
X1654675Y27724D01*
X1659340Y26732D01*
X1664233Y27771D01*
X1668869Y26787D01*
X1673240Y27716D01*
X1678412Y26618D01*
X1683500Y27700D01*
X1687756Y26795D01*
X1692456Y27793D01*
X1698433Y26524D01*
X1702542Y27724D01*
X1706396Y26905D01*
X1727059Y35987D01*
X1728675Y37602D01*
Y39015D01*
X1728225Y39465D01*
X1727383D01*
G01X1258126Y469540D02*
Y470454D01*
X1257105Y471475D01*
X1253902D01*
X1252400Y469973D01*
Y466592D01*
X1253813Y461478D01*
X1253814D01*
X1251126Y453122D01*
X1254878Y445646D01*
X1285980Y416912D01*
X1286174Y416733D01*
X1294840Y400982D01*
X1295927Y386697D01*
X1293693Y376190D01*
X1294625Y371803D01*
X1294345Y370482D01*
X1294845Y369712D01*
X1294565Y368391D01*
X1293794Y367890D01*
X1293514Y366570D01*
X1294015Y365799D01*
X1293734Y364478D01*
X1292964Y363977D01*
X1292683Y362657D01*
X1293184Y361886D01*
X1292904Y360565D01*
X1292133Y360065D01*
X1291853Y358744D01*
X1292353Y357973D01*
X1292073Y356653D01*
X1291302Y356152D01*
X1288930Y344982D01*
X1289431Y344211D01*
X1289151Y342891D01*
X1288380Y342390D01*
X1288099Y341069D01*
X1288600Y340298D01*
X1288320Y338978D01*
X1287549Y338477D01*
X1285980Y331078D01*
X1285609Y329328D01*
X1285980Y327811D01*
X1286877Y324142D01*
X1288041Y319382D01*
X1285102Y305547D01*
X1285089Y305527D01*
X1284995Y305081D01*
X1284996Y305077D01*
X1284998Y305068D01*
X1284999Y305063D01*
X1284998Y305058D01*
X1284996Y305049D01*
X1284995Y305045D01*
X1285300Y303601D01*
X1285980Y300406D01*
X1286012Y300256D01*
X1286023Y300237D01*
X1286024Y300233D01*
X1286025Y300231D01*
X1286160Y299595D01*
X1286212Y299349D01*
X1286216Y299329D01*
X1286208Y299291D01*
X1286207Y299286D01*
X1285980Y298215D01*
X1285736Y297064D01*
X1285697Y296879D01*
X1285300Y295011D01*
X1284997Y293583D01*
X1284995Y293572D01*
X1284991Y293554D01*
X1284990Y293550D01*
X1284962Y293421D01*
X1284956Y293410D01*
X1285980Y288589D01*
X1287133Y283160D01*
X1285143Y273790D01*
X1287748Y260974D01*
X1288515Y260466D01*
X1288784Y259143D01*
X1288276Y258377D01*
X1288545Y257054D01*
X1289312Y256546D01*
X1289581Y255223D01*
X1289073Y254457D01*
X1289342Y253134D01*
X1291301Y250173D01*
X1294555Y233571D01*
X1292862Y225106D01*
X1299053Y208626D01*
X1299665Y208186D01*
X1316259Y196245D01*
X1316261Y196243D01*
X1322631Y194948D01*
X1331996Y193044D01*
X1341355Y194949D01*
X1403382Y178324D01*
X1410316Y173780D01*
X1413675Y167446D01*
X1419389Y139690D01*
X1430279Y126273D01*
X1431683Y119250D01*
X1430804Y114854D01*
X1433002Y103868D01*
X1439916Y99252D01*
X1445976Y71028D01*
X1453956Y56139D01*
X1462369Y49546D01*
X1493980Y42832D01*
X1497463Y43572D01*
X1530575Y36541D01*
X1531345Y37042D01*
X1532666Y36761D01*
X1533167Y35990D01*
X1534487Y35710D01*
X1535258Y36211D01*
X1536579Y35930D01*
X1537079Y35159D01*
X1538400Y34879D01*
X1545142Y36312D01*
X1555451Y34122D01*
X1591365Y20719D01*
X1593875Y21231D01*
X1597376Y20529D01*
X1608170Y22686D01*
X1614625Y21317D01*
X1635943Y25847D01*
X1642413Y24473D01*
X1645464Y25120D01*
X1650080Y24140D01*
X1654764Y25136D01*
X1659429Y24144D01*
X1664233Y25165D01*
X1668869Y24180D01*
X1673344Y25131D01*
X1678516Y24033D01*
X1683515Y25095D01*
X1687771Y24190D01*
X1692423Y25179D01*
X1698504Y23888D01*
X1702666Y25103D01*
X1706606Y24264D01*
X1730786Y34891D01*
X1737193D01*
X1738150Y35848D01*
Y38750D01*
X1737300Y39600D01*
X1736700D01*
G01X1271640Y474420D02*
X1270008Y476052D01*
X1267551D01*
X1260429Y478075D01*
X1252974Y476746D01*
X1250925Y475141D01*
X1248750Y470229D01*
X1251153Y461533D01*
X1248336Y452774D01*
X1252708Y444063D01*
Y444062D01*
X1284093Y415067D01*
X1292218Y400296D01*
X1293282Y386325D01*
X1291037Y375764D01*
X1291903Y371689D01*
X1282772Y328698D01*
X1285278Y318452D01*
X1282429Y305043D01*
X1283646Y299307D01*
X1282392Y293398D01*
X1284567Y283160D01*
X1282583Y273817D01*
X1286988Y252159D01*
X1288942Y249206D01*
X1291971Y233751D01*
X1289958Y223693D01*
X1291762Y218876D01*
X1292599Y218495D01*
X1293072Y217231D01*
X1292692Y216394D01*
X1293165Y215130D01*
X1294001Y214749D01*
X1294475Y213485D01*
X1294094Y212648D01*
X1294567Y211384D01*
X1295404Y211003D01*
X1295877Y209739D01*
X1295497Y208902D01*
X1295502Y208887D01*
X1296009Y207534D01*
X1315148Y193767D01*
X1331990Y190339D01*
X1341588Y192292D01*
X1402201Y176047D01*
X1408321Y172040D01*
X1411198Y166615D01*
X1416994Y138462D01*
X1427779Y125171D01*
X1429043Y118847D01*
X1428214Y114705D01*
X1430695Y102304D01*
X1437648Y97668D01*
X1440833Y82586D01*
X1444017Y67504D01*
X1445041Y65592D01*
X1445921Y65326D01*
X1446558Y64136D01*
X1446292Y63256D01*
X1446930Y62066D01*
X1447810Y61800D01*
X1448447Y60610D01*
X1448181Y59730D01*
X1450413Y55563D01*
X1461014Y47253D01*
X1494025Y40242D01*
X1497465Y40972D01*
X1538848Y32183D01*
X1543325Y33135D01*
X1555928Y30458D01*
X1589865Y17786D01*
X1593943Y18620D01*
X1597570Y17895D01*
X1607885Y19957D01*
X1614074Y18642D01*
X1622033Y20332D01*
X1625413Y19614D01*
X1626184Y20115D01*
X1627505Y19834D01*
X1628005Y19063D01*
Y19064D01*
X1628740Y18908D01*
X1629326Y18784D01*
Y18783D01*
X1630097Y19284D01*
X1631418Y19003D01*
X1631918Y18232D01*
X1633239Y17952D01*
X1634559Y18233D01*
X1635060Y19004D01*
X1636381Y19285D01*
X1637152Y18784D01*
X1638472Y19065D01*
X1638973Y19836D01*
X1640294Y20117D01*
X1641065Y19616D01*
X1642385Y19897D01*
X1642886Y20668D01*
X1644207Y20949D01*
X1644978Y20448D01*
Y20449D01*
X1646298Y20730D01*
X1646799Y21501D01*
X1648120Y21781D01*
X1648891Y21281D01*
X1654815Y22540D01*
X1659480Y21548D01*
X1664233Y22558D01*
X1668870Y21574D01*
X1673410Y22539D01*
X1678583Y21440D01*
X1683603Y22508D01*
X1687860Y21602D01*
X1692492Y22586D01*
X1698656Y21276D01*
X1702859Y22502D01*
X1706871Y21648D01*
X1730764Y32150D01*
X1746664D01*
X1747825Y33311D01*
Y35474D01*
X1747374Y35925D01*
X1746550D01*
G01X1329419Y464337D02*
Y465232D01*
X1328347Y466304D01*
X1311402D01*
X1309071Y468635D01*
X1285644D01*
X1279075Y462066D01*
Y434148D01*
X1292677Y421588D01*
X1302594Y403565D01*
X1302835Y403324D01*
X1303972Y388335D01*
X1301518Y376784D01*
X1302817Y370672D01*
Y370673D01*
X1302818Y370668D01*
X1302318Y368312D01*
X1302819Y367541D01*
X1302538Y366220D01*
X1301767Y365720D01*
X1301487Y364399D01*
X1301988Y363628D01*
X1301707Y362308D01*
X1300937Y361807D01*
X1300656Y360486D01*
X1301157Y359715D01*
X1300877Y358395D01*
X1300106Y357894D01*
X1299825Y356573D01*
X1300326Y355803D01*
X1300046Y354482D01*
X1299275Y353981D01*
Y353980D01*
X1293926Y328787D01*
X1293927Y328785D01*
X1293926D01*
X1295966Y320445D01*
X1292692Y305042D01*
X1293910Y299308D01*
X1292656Y293399D01*
X1294831Y283160D01*
X1293679Y277738D01*
X1303695Y228517D01*
X1309883Y217099D01*
X1310764Y216837D01*
X1311408Y215650D01*
X1311146Y214769D01*
X1311789Y213582D01*
X1312670Y213320D01*
X1313313Y212133D01*
X1313052Y211252D01*
X1313695Y210065D01*
X1314576Y209803D01*
X1315219Y208616D01*
X1314958Y207735D01*
X1315601Y206548D01*
X1319590Y203678D01*
X1331990Y201155D01*
X1340849Y202958D01*
X1406671Y185312D01*
X1416270Y179027D01*
Y179028D01*
X1416272Y179026D01*
X1421045Y170027D01*
X1426466Y143684D01*
X1437944Y129537D01*
X1439814Y120199D01*
X1439016Y116210D01*
X1440636Y108109D01*
X1446847Y103969D01*
X1451698Y82186D01*
X1458726Y77692D01*
X1459475Y76569D01*
X1460376Y76388D01*
X1461125Y75265D01*
X1460945Y74364D01*
X1461694Y73241D01*
X1462595Y73060D01*
X1463344Y71937D01*
X1463164Y71036D01*
X1463913Y69912D01*
X1464814Y69732D01*
X1465563Y68609D01*
X1465383Y67708D01*
X1466132Y66585D01*
X1467033Y66404D01*
X1467782Y65281D01*
X1467602Y64380D01*
X1469027Y62241D01*
X1482764Y53082D01*
X1494030Y50692D01*
X1497254Y51377D01*
X1525961Y45281D01*
X1542298Y48753D01*
X1576052Y41573D01*
X1580249Y35277D01*
X1584548Y33677D01*
X1590220Y34878D01*
X1616036Y29395D01*
X1635892Y33613D01*
X1642259Y32260D01*
X1645402Y32928D01*
X1650017Y31948D01*
X1654676Y32938D01*
X1659341Y31946D01*
X1664232Y32985D01*
X1668868Y32001D01*
X1673178Y32917D01*
X1678350Y31819D01*
X1683558Y32926D01*
X1687815Y32021D01*
X1692510Y33018D01*
X1698282Y31791D01*
X1702448Y33008D01*
X1703612Y32761D01*
X1708455Y34515D01*
X1709850Y36505D01*
Y38649D01*
X1709151Y39350D01*
X1708508D01*
G01X1265293Y652264D02*
Y650289D01*
X1265733Y649849D01*
X1266211D01*
X1266841Y650328D01*
X1267603Y651344D01*
X1267772Y652010D01*
X1268184Y654347D01*
X1269485Y655259D01*
X1271459Y654912D01*
X1272370Y653608D01*
X1270886Y645202D01*
X1271253Y644678D01*
X1272287Y644495D01*
X1272806Y644858D01*
X1274490Y654408D01*
X1275794Y655322D01*
X1277768Y654974D01*
X1278677Y653669D01*
X1277185Y645216D01*
X1277549Y644695D01*
X1278584Y644513D01*
X1279107Y644878D01*
X1280785Y654412D01*
X1282088Y655322D01*
X1284060Y654977D01*
X1284972Y653673D01*
X1283481Y645217D01*
X1283845Y644696D01*
X1284879Y644514D01*
X1285402Y644879D01*
X1287085Y654431D01*
X1288388Y655340D01*
X1290357Y654995D01*
X1291272Y653695D01*
X1289772Y645184D01*
X1290136Y644663D01*
X1291170Y644481D01*
X1291690Y644845D01*
X1293380Y654426D01*
X1294683Y655342D01*
X1296657Y654993D01*
X1297569Y653692D01*
X1296069Y645185D01*
X1296432Y644663D01*
X1297466Y644480D01*
X1297988Y644845D01*
X1299656Y654314D01*
X1300959Y655228D01*
X1302933Y654882D01*
X1303843Y653577D01*
X1302366Y645201D01*
X1302730Y644680D01*
X1303764Y644499D01*
X1304286Y644863D01*
X1305955Y654319D01*
X1307257Y655229D01*
X1309228Y654882D01*
X1310139Y653578D01*
X1308661Y645203D01*
X1309026Y644681D01*
X1310061Y644499D01*
X1310583Y644863D01*
X1312249Y654336D01*
X1313555Y655245D01*
X1315526Y654901D01*
X1316437Y653594D01*
X1314951Y645170D01*
X1315316Y644648D01*
X1316351Y644466D01*
X1316873Y644830D01*
X1318539Y654286D01*
X1319879Y655225D01*
X1321787Y654890D01*
X1322724Y653548D01*
X1321247Y645170D01*
X1321611Y644648D01*
X1322645Y644466D01*
X1323167Y644831D01*
X1324805Y654090D01*
X1326108Y655001D01*
X1328081Y654653D01*
X1328991Y653349D01*
X1327565Y645264D01*
X1327955Y644704D01*
X1328924Y644534D01*
X1329484Y644926D01*
X1331099Y654092D01*
X1332402Y655001D01*
X1334376Y654655D01*
X1335287Y653351D01*
X1333855Y645234D01*
X1334220Y644710D01*
X1335252Y644530D01*
X1335776Y644895D01*
X1337389Y654059D01*
X1338692Y654968D01*
X1340666Y654622D01*
X1341577Y653318D01*
X1340150Y645234D01*
X1340515Y644712D01*
X1341547Y644530D01*
X1342068Y644894D01*
X1343686Y654059D01*
X1344989Y654968D01*
X1346962Y654623D01*
X1347872Y653320D01*
X1346446Y645234D01*
X1346810Y644712D01*
X1347843Y644531D01*
X1348366Y644898D01*
X1349984Y654077D01*
X1351287Y654987D01*
X1353260Y654639D01*
X1354169Y653338D01*
X1352723Y645138D01*
X1353088Y644617D01*
X1354122Y644434D01*
X1354645Y644802D01*
X1356282Y654076D01*
X1357582Y654987D01*
X1359556Y654640D01*
X1360466Y653337D01*
X1359034Y645216D01*
X1359400Y644696D01*
X1360433Y644515D01*
X1360955Y644879D01*
X1362569Y654043D01*
X1363873Y654953D01*
X1365847Y654607D01*
X1366757Y653304D01*
X1365334Y645236D01*
X1365699Y644714D01*
X1366732Y644533D01*
X1367254Y644898D01*
X1368865Y654044D01*
X1370169Y654954D01*
X1372143Y654608D01*
X1373053Y653305D01*
X1371629Y645238D01*
X1371994Y644715D01*
X1373026Y644534D01*
X1373550Y644901D01*
X1375166Y654063D01*
X1376466Y654973D01*
X1378439Y654624D01*
X1379352Y653320D01*
X1377919Y645204D01*
X1378284Y644682D01*
X1379318Y644500D01*
X1379839Y644865D01*
X1381454Y654031D01*
X1382757Y654940D01*
X1384731Y654594D01*
X1385642Y653290D01*
X1384210Y645173D01*
X1384575Y644649D01*
X1385607Y644469D01*
X1386131Y644834D01*
X1387744Y653998D01*
X1389047Y654907D01*
X1391021Y654561D01*
X1391932Y653257D01*
X1390505Y645173D01*
X1390870Y644651D01*
X1391902Y644469D01*
X1392423Y644833D01*
X1394041Y653998D01*
X1395344Y654907D01*
X1397317Y654562D01*
X1398227Y653259D01*
X1396801Y645173D01*
X1397165Y644651D01*
X1398198Y644470D01*
X1398721Y644837D01*
X1400339Y654016D01*
X1401642Y654926D01*
X1403615Y654578D01*
X1404524Y653277D01*
X1403092Y645157D01*
X1403457Y644636D01*
X1404491Y644453D01*
X1405015Y644821D01*
X1406637Y654015D01*
X1407937Y654926D01*
X1409911Y654579D01*
X1410821Y653276D01*
X1409389Y645155D01*
X1409755Y644635D01*
X1410788Y644454D01*
X1411310Y644818D01*
X1412924Y653982D01*
X1414228Y654892D01*
X1416202Y654546D01*
X1417112Y653243D01*
X1415692Y645192D01*
X1416057Y644670D01*
X1417090Y644489D01*
X1417612Y644854D01*
X1419220Y653983D01*
X1420524Y654893D01*
X1422498Y654547D01*
X1423408Y653244D01*
X1421984Y645177D01*
X1422349Y644654D01*
X1423381Y644473D01*
X1423905Y644840D01*
X1425521Y654002D01*
X1426821Y654912D01*
X1428794Y654563D01*
X1429707Y653259D01*
X1428292Y645240D01*
X1428657Y644717D01*
X1429690Y644536D01*
X1430212Y644901D01*
X1431828Y654063D01*
X1433128Y654973D01*
X1435101Y654624D01*
X1436014Y653320D01*
X1434601Y645318D01*
X1434966Y644796D01*
X1436000Y644614D01*
X1436521Y644979D01*
X1438135Y654124D01*
X1439435Y655034D01*
X1441408Y654685D01*
X1442321Y653381D01*
X1440888Y645265D01*
X1441253Y644743D01*
X1442287Y644561D01*
X1442808Y644926D01*
X1444442Y654185D01*
X1445742Y655095D01*
X1447715Y654746D01*
X1448628Y653442D01*
X1447195Y645326D01*
X1447560Y644804D01*
X1448594Y644622D01*
X1449115Y644987D01*
X1450768Y654333D01*
X1452074Y655246D01*
X1454047Y654898D01*
X1454957Y653594D01*
X1453481Y645221D01*
X1453872Y644661D01*
X1454840Y644491D01*
X1455400Y644883D01*
X1457066Y654340D01*
X1458369Y655249D01*
X1460343Y654903D01*
X1461254Y653599D01*
X1459768Y645174D01*
X1460133Y644650D01*
X1461165Y644470D01*
X1461689Y644835D01*
X1463356Y654307D01*
X1464659Y655216D01*
X1466633Y654870D01*
X1467544Y653566D01*
X1466066Y645191D01*
X1466431Y644669D01*
X1467463Y644487D01*
X1467984Y644851D01*
X1469653Y654307D01*
X1470956Y655216D01*
X1472929Y654871D01*
X1473839Y653568D01*
X1472362Y645191D01*
X1472726Y644669D01*
X1473759Y644488D01*
X1474282Y644855D01*
X1475951Y654325D01*
X1477254Y655235D01*
X1479227Y654887D01*
X1480136Y653586D01*
X1478636Y645078D01*
X1479001Y644557D01*
X1480035Y644374D01*
X1480558Y644742D01*
X1482249Y654324D01*
X1483549Y655235D01*
X1485523Y654888D01*
X1486433Y653585D01*
X1484933Y645076D01*
X1485299Y644556D01*
X1486332Y644375D01*
X1486854Y644739D01*
X1488536Y654291D01*
X1489840Y655201D01*
X1491814Y654855D01*
X1492724Y653552D01*
X1491233Y645096D01*
X1491598Y644574D01*
X1492631Y644393D01*
X1493153Y644758D01*
X1494832Y654292D01*
X1496136Y655202D01*
X1498110Y654856D01*
X1499020Y653553D01*
X1497528Y645099D01*
X1497892Y644576D01*
X1498925Y644394D01*
X1499448Y644761D01*
X1501133Y654311D01*
X1502433Y655221D01*
X1504406Y654872D01*
X1505319Y653568D01*
X1503835Y645161D01*
X1504200Y644639D01*
X1505234Y644457D01*
X1505756Y644822D01*
X1506091Y646732D01*
X1506466Y648209D01*
X1507043Y648978D01*
X1508171Y649909D01*
X1509291Y649857D01*
X1509696Y650261D01*
Y652236D01*
G01Y646236D02*
Y648211D01*
X1509198Y648709D01*
X1508561Y648739D01*
X1507882Y648178D01*
X1507525Y647702D01*
X1507217Y646490D01*
X1506806Y644153D01*
X1505504Y643241D01*
X1503530Y643588D01*
X1502619Y644892D01*
X1504103Y653298D01*
X1503736Y653822D01*
X1502702Y654005D01*
X1502183Y653642D01*
X1500499Y644092D01*
X1499195Y643178D01*
X1497221Y643526D01*
X1496312Y644831D01*
X1497804Y653284D01*
X1497440Y653805D01*
X1496405Y653987D01*
X1495882Y653622D01*
X1494204Y644088D01*
X1492901Y643178D01*
X1490929Y643523D01*
X1490017Y644827D01*
X1491508Y653283D01*
X1491144Y653804D01*
X1490110Y653986D01*
X1489587Y653621D01*
X1487904Y644069D01*
X1486601Y643160D01*
X1484632Y643505D01*
X1483717Y644805D01*
X1485217Y653316D01*
X1484853Y653837D01*
X1483819Y654019D01*
X1483299Y653655D01*
X1481609Y644074D01*
X1480306Y643158D01*
X1478332Y643507D01*
X1477420Y644808D01*
X1478920Y653315D01*
X1478557Y653837D01*
X1477523Y654020D01*
X1477001Y653655D01*
X1475333Y644186D01*
X1474030Y643272D01*
X1472056Y643618D01*
X1471146Y644923D01*
X1472623Y653299D01*
X1472259Y653820D01*
X1471225Y654001D01*
X1470703Y653637D01*
X1469034Y644181D01*
X1467732Y643271D01*
X1465761Y643618D01*
X1464850Y644922D01*
X1466328Y653297D01*
X1465963Y653819D01*
X1464928Y654001D01*
X1464406Y653637D01*
X1462740Y644164D01*
X1461434Y643255D01*
X1459463Y643599D01*
X1458552Y644906D01*
X1460038Y653330D01*
X1459673Y653852D01*
X1458638Y654034D01*
X1458116Y653670D01*
X1456450Y644214D01*
X1455110Y643275D01*
X1453202Y643610D01*
X1452265Y644952D01*
X1453741Y653326D01*
X1453377Y653848D01*
X1452343Y654030D01*
X1451818Y653663D01*
X1450165Y644317D01*
X1448864Y643406D01*
X1446890Y643753D01*
X1445979Y645057D01*
X1447412Y653172D01*
X1447045Y653696D01*
X1446011Y653879D01*
X1445492Y653516D01*
X1443859Y644257D01*
X1442557Y643345D01*
X1440583Y643692D01*
X1439672Y644996D01*
X1441105Y653111D01*
X1440738Y653635D01*
X1439704Y653818D01*
X1439185Y653455D01*
X1437572Y644310D01*
X1436270Y643398D01*
X1434296Y643745D01*
X1433385Y645049D01*
X1434798Y653050D01*
X1434431Y653574D01*
X1433397Y653757D01*
X1432878Y653394D01*
X1431262Y644232D01*
X1429960Y643320D01*
X1427986Y643667D01*
X1427075Y644970D01*
X1428491Y652989D01*
X1428124Y653513D01*
X1427090Y653696D01*
X1426571Y653333D01*
X1424955Y644171D01*
X1423651Y643257D01*
X1421677Y643605D01*
X1420768Y644909D01*
X1422192Y652975D01*
X1421828Y653496D01*
X1420793Y653678D01*
X1420270Y653313D01*
X1418663Y644184D01*
X1417360Y643274D01*
X1415388Y643619D01*
X1414476Y644923D01*
X1415896Y652974D01*
X1415532Y653495D01*
X1414498Y653677D01*
X1413975Y653312D01*
X1412360Y644148D01*
X1411057Y643239D01*
X1409088Y643584D01*
X1408173Y644884D01*
X1409605Y653007D01*
X1409241Y653528D01*
X1408207Y653710D01*
X1407687Y653346D01*
X1406066Y644153D01*
X1404762Y643237D01*
X1402788Y643586D01*
X1401876Y644887D01*
X1403308Y653006D01*
X1402945Y653528D01*
X1401911Y653711D01*
X1401389Y653346D01*
X1399772Y644168D01*
X1398469Y643254D01*
X1396495Y643600D01*
X1395585Y644905D01*
X1397011Y652990D01*
X1396647Y653511D01*
X1395613Y653692D01*
X1395091Y653328D01*
X1393473Y644163D01*
X1392171Y643253D01*
X1390200Y643600D01*
X1389289Y644904D01*
X1390716Y652988D01*
X1390351Y653510D01*
X1389316Y653692D01*
X1388794Y653328D01*
X1387182Y644163D01*
X1385876Y643254D01*
X1383905Y643598D01*
X1382994Y644905D01*
X1384426Y653021D01*
X1384061Y653543D01*
X1383026Y653725D01*
X1382504Y653361D01*
X1380889Y644196D01*
X1379588Y643284D01*
X1377614Y643631D01*
X1376703Y644935D01*
X1378136Y653050D01*
X1377769Y653574D01*
X1376735Y653757D01*
X1376216Y653394D01*
X1374600Y644232D01*
X1373296Y643318D01*
X1371322Y643666D01*
X1370413Y644970D01*
X1371837Y653036D01*
X1371473Y653557D01*
X1370438Y653739D01*
X1369915Y653374D01*
X1368305Y644228D01*
X1367002Y643318D01*
X1365030Y643663D01*
X1364118Y644967D01*
X1365541Y653035D01*
X1365177Y653556D01*
X1364143Y653738D01*
X1363620Y653373D01*
X1362005Y644209D01*
X1360702Y643300D01*
X1358733Y643645D01*
X1357818Y644945D01*
X1359250Y653068D01*
X1358886Y653589D01*
X1357852Y653771D01*
X1357332Y653407D01*
X1355696Y644134D01*
X1354393Y643218D01*
X1352419Y643567D01*
X1351507Y644868D01*
X1352953Y653067D01*
X1352590Y653589D01*
X1351556Y653772D01*
X1351034Y653407D01*
X1349417Y644229D01*
X1348114Y643315D01*
X1346140Y643661D01*
X1345230Y644966D01*
X1346656Y653051D01*
X1346292Y653572D01*
X1345258Y653753D01*
X1344736Y653389D01*
X1343118Y644224D01*
X1341816Y643314D01*
X1339845Y643661D01*
X1338934Y644965D01*
X1340361Y653049D01*
X1339996Y653571D01*
X1338961Y653753D01*
X1338439Y653389D01*
X1336827Y644224D01*
X1335521Y643315D01*
X1333550Y643659D01*
X1332639Y644966D01*
X1334071Y653082D01*
X1333706Y653604D01*
X1332671Y653786D01*
X1332149Y653422D01*
X1330534Y644257D01*
X1329194Y643318D01*
X1327286Y643653D01*
X1326349Y644995D01*
X1327775Y653081D01*
X1327411Y653603D01*
X1326377Y653785D01*
X1325855Y653420D01*
X1324217Y644161D01*
X1322914Y643251D01*
X1320941Y643598D01*
X1320031Y644901D01*
X1321508Y653279D01*
X1321117Y653839D01*
X1320149Y654009D01*
X1319589Y653617D01*
X1317923Y644160D01*
X1316620Y643251D01*
X1314646Y643597D01*
X1313735Y644901D01*
X1315221Y653326D01*
X1314856Y653850D01*
X1313824Y654030D01*
X1313300Y653665D01*
X1311633Y644193D01*
X1310330Y643284D01*
X1308356Y643630D01*
X1307445Y644934D01*
X1308923Y653309D01*
X1308558Y653831D01*
X1307526Y654013D01*
X1307005Y653649D01*
X1305336Y644193D01*
X1304033Y643284D01*
X1302060Y643629D01*
X1301150Y644932D01*
X1302627Y653309D01*
X1302263Y653831D01*
X1301230Y654012D01*
X1300707Y653645D01*
X1299038Y644175D01*
X1297735Y643265D01*
X1295762Y643613D01*
X1294853Y644914D01*
X1296353Y653422D01*
X1295988Y653943D01*
X1294954Y654126D01*
X1294431Y653758D01*
X1292740Y644176D01*
X1291440Y643265D01*
X1289466Y643612D01*
X1288556Y644915D01*
X1290056Y653424D01*
X1289690Y653944D01*
X1288657Y654125D01*
X1288135Y653761D01*
X1286453Y644209D01*
X1285149Y643299D01*
X1283175Y643645D01*
X1282265Y644948D01*
X1283756Y653404D01*
X1283391Y653926D01*
X1282358Y654107D01*
X1281836Y653742D01*
X1280157Y644208D01*
X1278853Y643298D01*
X1276879Y643644D01*
X1275969Y644947D01*
X1277461Y653401D01*
X1277097Y653924D01*
X1276064Y654106D01*
X1275541Y653739D01*
X1273856Y644189D01*
X1272556Y643279D01*
X1270583Y643628D01*
X1269670Y644932D01*
X1271154Y653339D01*
X1270789Y653861D01*
X1269755Y654043D01*
X1269234Y653678D01*
X1268898Y651768D01*
X1268662Y650838D01*
X1267665Y649509D01*
X1266599Y648699D01*
X1265753D01*
X1265293Y648239D01*
Y646264D01*
G01X1304200Y466600D02*
Y465090D01*
X1303750Y464640D01*
X1289074D01*
X1282322Y457888D01*
Y434896D01*
X1292899Y424319D01*
X1304321Y403557D01*
X1304693Y398666D01*
X1305524Y387733D01*
X1303059Y376125D01*
X1304572Y369006D01*
X1295771Y327554D01*
X1297425Y320782D01*
X1294082Y305042D01*
X1295299Y299308D01*
X1294046Y293399D01*
X1296221Y283160D01*
X1295087Y277821D01*
X1304587Y231135D01*
X1317736Y206871D01*
X1320226Y205080D01*
X1331990Y202686D01*
X1341294Y204580D01*
X1341299Y204578D01*
X1407311Y186567D01*
X1417352Y179990D01*
X1417365Y179981D01*
X1422480Y170338D01*
X1427818Y144410D01*
X1439947Y129462D01*
X1441529Y121556D01*
X1440512Y116464D01*
X1442036Y108846D01*
X1448034Y104865D01*
X1451615Y88799D01*
X1458815Y84001D01*
X1474811Y60010D01*
X1483298Y54350D01*
X1493920Y52097D01*
X1497169Y52787D01*
X1525733Y46721D01*
X1542164Y50213D01*
X1578668Y42448D01*
X1579013Y41914D01*
X1578659Y40259D01*
X1579524Y38928D01*
X1581488Y38509D01*
X1582819Y39374D01*
X1583121Y40785D01*
X1583949Y41325D01*
X1583971Y41321D01*
X1583978Y41320D01*
X1584977Y41105D01*
X1585706Y39986D01*
X1585188Y37567D01*
X1586053Y36236D01*
X1588017Y35817D01*
X1589348Y36682D01*
X1589970Y39583D01*
X1590503Y39930D01*
X1594299Y39123D01*
X1597165Y34831D01*
X1610215Y32054D01*
X1611613Y32960D01*
X1611982Y34688D01*
X1612513Y35032D01*
X1613547Y34813D01*
X1613891Y34281D01*
X1613511Y32504D01*
X1614374Y31170D01*
X1615928Y30839D01*
X1635749Y35046D01*
X1642194Y33677D01*
X1645321Y34342D01*
X1649936Y33362D01*
X1654676Y34369D01*
X1659341Y33377D01*
X1664232Y34416D01*
X1668868Y33432D01*
X1673178Y34348D01*
X1678350Y33250D01*
X1683457Y34335D01*
X1687714Y33430D01*
X1692421Y34430D01*
X1698153Y33212D01*
X1700720Y33962D01*
X1701800Y35042D01*
Y39100D01*
X1702379Y39679D01*
X1703073D01*
G01X1699273D02*
X1699821D01*
X1700650Y38850D01*
Y35519D01*
X1700115Y34984D01*
X1700114D01*
X1698109Y34398D01*
X1692421Y35606D01*
X1687714Y34606D01*
X1683457Y35511D01*
X1678350Y34426D01*
X1673178Y35524D01*
X1668868Y34608D01*
X1664232Y35592D01*
X1659341Y34553D01*
X1654676Y35545D01*
X1649936Y34538D01*
X1645321Y35518D01*
X1642194Y34853D01*
X1635749Y36222D01*
X1615928Y32015D01*
X1615081Y32196D01*
X1614736Y32729D01*
X1615116Y34506D01*
X1614254Y35840D01*
X1612286Y36256D01*
X1610957Y35395D01*
X1610587Y33667D01*
X1609989Y33278D01*
X1597862Y35859D01*
X1594996Y40151D01*
X1590277Y41154D01*
X1588944Y40290D01*
X1588323Y37388D01*
X1588322D01*
X1587790Y37042D01*
X1586759Y37262D01*
X1586413Y37794D01*
X1586931Y40213D01*
X1585683Y42131D01*
X1584218Y42444D01*
X1583320Y42288D01*
X1582095Y41490D01*
X1581794Y40080D01*
X1581793D01*
X1581261Y39734D01*
X1580230Y39954D01*
X1579884Y40486D01*
X1580238Y42139D01*
X1579375Y43474D01*
X1542164Y51389D01*
X1533709Y49592D01*
X1533708D01*
X1525733Y47897D01*
X1497169Y53963D01*
X1493920Y53273D01*
X1483753Y55430D01*
X1475641Y60840D01*
X1459645Y84831D01*
X1452637Y89500D01*
X1449056Y105567D01*
X1443070Y109540D01*
X1441685Y116464D01*
X1442702Y121556D01*
X1441020Y129967D01*
X1428888Y144917D01*
X1423574Y170732D01*
X1418243Y180782D01*
X1417983Y180952D01*
X1407789Y187629D01*
X1341333Y205762D01*
X1331990Y203860D01*
X1320697Y206158D01*
X1318622Y207651D01*
X1309492Y224498D01*
X1309754Y225379D01*
X1309110Y226566D01*
X1308229Y226828D01*
X1307586Y228015D01*
X1307848Y228896D01*
X1307204Y230083D01*
X1306323Y230345D01*
X1305680Y231532D01*
X1296262Y277816D01*
X1297397Y283160D01*
X1295222Y293399D01*
X1296475Y299308D01*
X1295258Y305042D01*
X1295538Y306363D01*
X1296309Y306863D01*
X1296590Y308184D01*
X1296089Y308955D01*
X1296369Y310276D01*
X1297140Y310776D01*
X1297421Y312097D01*
X1296920Y312868D01*
X1297201Y314189D01*
X1297971Y314689D01*
X1298252Y316010D01*
X1297751Y316781D01*
X1298605Y320800D01*
Y320801D01*
X1296952Y327570D01*
X1303415Y358017D01*
X1304186Y358518D01*
X1304467Y359839D01*
X1303966Y360609D01*
X1304246Y361930D01*
X1305017Y362431D01*
X1305297Y363751D01*
X1304796Y364522D01*
X1305748Y369006D01*
X1304235Y376125D01*
X1306684Y387655D01*
Y387656D01*
X1305847Y398666D01*
X1305449Y403893D01*
X1304798Y405076D01*
X1305054Y405959D01*
X1304404Y407141D01*
X1303521Y407398D01*
X1302870Y408581D01*
X1303126Y409464D01*
X1302476Y410646D01*
X1301593Y410903D01*
X1300942Y412086D01*
X1301198Y412969D01*
X1300548Y414151D01*
X1300195Y414254D01*
X1299665Y414408D01*
X1299014Y415591D01*
X1299270Y416474D01*
X1298620Y417656D01*
X1297737Y417913D01*
X1293828Y425017D01*
X1283472Y435373D01*
Y457411D01*
X1289551Y463490D01*
X1303850D01*
X1304200Y463140D01*
Y462030D01*
G01X1388741Y493623D02*
Y495287D01*
X1389242Y495788D01*
X1390843Y495790D01*
X1392480Y496974D01*
Y500187D01*
X1390817Y501850D01*
X1381837D01*
X1380518Y500531D01*
X1361646D01*
X1359902Y498787D01*
Y495579D01*
X1354463Y490140D01*
Y478328D01*
X1356062Y475783D01*
X1361171Y472871D01*
X1410889Y462299D01*
X1414646Y459430D01*
X1417617Y445430D01*
X1413921Y428029D01*
X1410245Y425580D01*
X1409350Y423900D01*
Y410443D01*
X1404838Y389185D01*
X1408243Y373153D01*
X1408242D01*
X1407105Y367795D01*
X1412809Y340935D01*
Y331729D01*
X1407128Y326048D01*
Y315245D01*
X1410626Y311749D01*
Y290873D01*
X1410625Y290872D01*
X1410626D01*
X1403625Y275708D01*
X1402471Y269761D01*
X1403958Y265143D01*
X1408149Y259214D01*
X1413785Y232686D01*
X1409679Y213360D01*
X1411304Y208596D01*
X1411963Y206663D01*
X1410625Y199973D01*
X1411087Y197658D01*
X1426263Y171520D01*
X1431589Y144873D01*
X1442914Y130922D01*
X1444775Y121639D01*
X1443813Y116820D01*
X1445064Y110558D01*
X1450999Y106618D01*
X1453850Y105989D01*
X1454691Y104866D01*
X1457270Y93271D01*
X1478106Y62012D01*
X1485327Y57197D01*
X1494039Y55347D01*
X1497126Y56002D01*
X1525696Y49937D01*
X1542055Y53413D01*
X1607171Y39572D01*
X1632474Y44946D01*
X1648846Y41671D01*
X1651889Y42319D01*
X1657780Y41064D01*
X1666133Y42841D01*
X1672574Y41471D01*
X1674459Y41854D01*
X1677905Y41153D01*
Y41152D01*
X1678134Y41106D01*
X1682907Y42077D01*
X1684462Y43106D01*
X1687222Y43668D01*
X1697338Y41609D01*
X1705945Y43357D01*
X1705954Y43371D01*
X1713864Y41691D01*
X1726665Y44411D01*
X1735388Y42558D01*
X1739798Y43437D01*
X1748647Y41668D01*
X1756413Y43221D01*
X1759835Y42528D01*
X1762056Y40930D01*
X1763353Y38680D01*
X1764239Y34763D01*
X1761003Y26907D01*
X1758302Y24206D01*
Y21278D01*
X1757031Y20007D01*
X1756992D01*
G01X1760693Y20045D02*
X1760578D01*
X1759452Y21171D01*
Y23729D01*
X1761979Y26256D01*
X1765442Y34662D01*
X1764437Y39104D01*
X1762929Y41719D01*
X1760306Y43606D01*
X1756414Y44395D01*
X1748647Y42841D01*
X1739798Y44610D01*
X1735395Y43733D01*
X1726665Y45587D01*
X1713864Y42867D01*
X1705954Y44547D01*
X1705926Y44528D01*
X1697338Y42783D01*
X1687222Y44842D01*
X1684013Y44189D01*
X1682458Y43160D01*
X1678134Y42280D01*
X1674459Y43028D01*
X1674230Y42982D01*
Y42981D01*
X1672580Y42646D01*
X1666133Y44017D01*
X1657780Y42240D01*
X1651889Y43495D01*
X1648840Y42846D01*
X1632467Y46121D01*
X1607171Y40748D01*
X1542055Y54589D01*
X1525696Y51113D01*
X1497127Y57178D01*
X1494039Y56523D01*
X1485782Y58277D01*
X1478936Y62842D01*
X1458347Y93731D01*
X1455761Y105358D01*
X1454515Y107020D01*
X1451456Y107695D01*
X1446099Y111252D01*
X1444986Y116820D01*
X1445948Y121639D01*
X1443987Y131427D01*
X1432662Y145378D01*
X1427354Y171934D01*
X1412178Y198071D01*
X1411799Y199974D01*
X1413152Y206741D01*
X1413148Y206752D01*
X1410870Y213431D01*
X1411636Y217033D01*
X1412406Y217534D01*
X1412687Y218855D01*
X1412186Y219625D01*
X1412467Y220946D01*
X1413238Y221447D01*
X1413519Y222768D01*
X1413018Y223539D01*
X1413299Y224859D01*
X1414069Y225360D01*
X1414350Y226681D01*
X1413849Y227451D01*
X1414130Y228772D01*
X1414901Y229273D01*
X1415181Y230594D01*
X1414680Y231364D01*
X1414961Y232685D01*
X1409226Y259683D01*
X1404999Y265663D01*
X1403657Y269832D01*
X1404728Y275352D01*
X1411776Y290619D01*
Y312226D01*
X1408278Y315722D01*
Y325571D01*
X1413959Y331252D01*
Y341056D01*
X1412024Y350170D01*
X1412025Y350171D01*
X1412525Y350942D01*
X1412245Y352263D01*
X1411474Y352763D01*
X1411194Y354084D01*
X1411694Y354855D01*
X1411414Y356175D01*
X1410643Y356676D01*
X1410362Y357997D01*
X1410863Y358767D01*
X1410583Y360088D01*
X1409812Y360589D01*
X1409531Y361909D01*
X1410032Y362680D01*
X1409751Y364001D01*
X1408981Y364501D01*
X1408281Y367795D01*
X1409419Y373155D01*
X1406014Y389185D01*
X1410500Y410322D01*
Y418182D01*
X1411150Y418832D01*
Y420182D01*
X1410500Y420832D01*
Y423612D01*
X1411124Y424783D01*
X1414949Y427332D01*
X1418793Y445430D01*
X1415684Y460085D01*
X1411382Y463371D01*
X1361585Y473959D01*
X1356883Y476640D01*
X1355613Y478660D01*
Y489663D01*
X1358224Y492274D01*
X1359143D01*
X1360097Y493228D01*
Y494147D01*
X1361052Y495102D01*
Y498310D01*
X1362123Y499381D01*
X1372995D01*
X1373645Y498731D01*
X1374995D01*
X1375645Y499381D01*
X1376995D01*
X1377645Y498731D01*
X1378995D01*
X1379645Y499381D01*
X1380995D01*
X1382314Y500700D01*
X1390340D01*
X1391330Y499710D01*
Y497562D01*
X1390470Y496940D01*
X1389240Y496938D01*
X1389170D01*
X1388719Y497387D01*
Y498745D01*
G01X1738168Y22312D02*
X1736912D01*
X1736340Y21740D01*
Y20567D01*
X1737547Y19360D01*
X1757593Y15108D01*
X1767022D01*
X1773926Y18075D01*
X1775440Y25175D01*
X1773121Y36103D01*
X1773900Y39999D01*
X1772969Y44655D01*
X1748368Y61052D01*
X1735955Y63536D01*
X1731843Y62463D01*
X1730003Y61233D01*
X1692094Y53647D01*
X1688158Y54448D01*
X1683210Y53442D01*
X1680576Y51698D01*
X1679301Y51442D01*
X1675400Y52234D01*
X1673209Y53682D01*
X1669804Y54374D01*
X1648182Y49816D01*
X1639958Y51460D01*
Y51461D01*
X1632201Y53011D01*
X1606137Y47471D01*
X1540703Y61380D01*
X1524513Y57938D01*
X1495926Y64011D01*
X1493606Y63518D01*
X1488530Y64597D01*
X1484248Y67451D01*
X1464693Y96791D01*
X1459670Y120413D01*
X1450767Y133767D01*
X1443827Y142310D01*
X1440737Y156075D01*
X1439818Y158109D01*
X1436123Y162799D01*
X1433392Y176451D01*
X1426349Y186951D01*
X1423818Y199602D01*
X1421776Y205589D01*
X1427120Y221771D01*
X1421629Y233029D01*
X1414910Y264651D01*
X1415540Y267798D01*
X1414728Y271859D01*
X1418127Y287861D01*
Y287862D01*
X1420846Y296547D01*
X1423750Y299451D01*
Y360160D01*
X1427016Y375528D01*
Y391462D01*
X1424159Y405411D01*
Y412735D01*
X1423509Y413385D01*
Y414735D01*
X1424159Y415385D01*
Y416735D01*
X1423509Y417385D01*
Y418735D01*
X1424159Y419385D01*
Y426640D01*
X1423509Y427290D01*
Y428640D01*
X1424159Y429290D01*
Y430640D01*
X1423509Y431290D01*
Y432640D01*
X1424159Y433290D01*
Y437965D01*
X1425954Y446419D01*
X1422309Y463582D01*
X1413906Y469999D01*
X1381482Y476891D01*
X1377251Y481122D01*
Y483977D01*
X1378824Y485550D01*
X1384468D01*
X1386241Y487323D01*
G01X1366341Y481823D02*
X1368050Y483532D01*
X1371303D01*
X1372258Y482577D01*
Y481658D01*
X1373212Y480704D01*
X1374131D01*
X1375086Y479749D01*
Y478830D01*
X1376040Y477876D01*
X1376959D01*
X1377914Y476921D01*
Y476002D01*
X1378868Y475048D01*
X1379787D01*
X1380749Y474086D01*
X1413223Y467184D01*
X1420103Y461928D01*
X1423375Y446521D01*
X1420908Y434907D01*
Y430469D01*
X1420258Y429819D01*
Y428469D01*
X1420908Y427819D01*
Y426469D01*
X1420258Y425819D01*
Y424469D01*
X1420908Y423819D01*
Y422469D01*
X1420258Y421819D01*
Y420469D01*
X1420908Y419819D01*
Y418469D01*
X1420258Y417819D01*
Y416469D01*
X1420908Y415819D01*
Y408760D01*
X1424514Y391148D01*
Y377038D01*
X1421250Y361648D01*
Y301050D01*
X1418591Y298391D01*
X1416230Y290850D01*
X1408729Y274594D01*
X1407847Y270036D01*
X1408509Y267985D01*
X1412946Y261705D01*
X1419794Y229480D01*
X1416379Y213392D01*
X1421061Y199665D01*
X1423753Y186210D01*
X1431029Y175293D01*
X1436670Y147079D01*
X1448871Y132056D01*
X1457284Y119436D01*
X1462013Y96009D01*
X1482205Y65713D01*
X1488009Y61845D01*
X1493428Y60692D01*
X1496436Y61332D01*
X1525061Y55251D01*
X1541280Y58695D01*
X1606363Y44860D01*
X1632386Y50383D01*
X1648203Y47219D01*
X1659292Y49577D01*
X1660259Y49376D01*
Y49375D01*
X1660262Y49376D01*
X1672379Y46870D01*
X1672382D01*
X1673988Y47196D01*
X1678094Y46362D01*
X1680268Y46806D01*
X1681286Y47484D01*
X1682573Y49429D01*
X1684439Y50664D01*
X1685707Y50924D01*
X1687520Y50556D01*
X1690450Y48618D01*
X1691668Y48370D01*
X1715318Y53146D01*
X1717977Y54916D01*
X1720488Y55418D01*
X1729343Y53647D01*
X1743223Y56596D01*
X1753195Y54602D01*
X1755040Y53372D01*
X1755221Y52471D01*
X1756344Y51722D01*
X1757245Y51902D01*
X1760592Y49672D01*
X1760772Y48771D01*
X1761895Y48022D01*
X1762797Y48203D01*
X1763920Y47454D01*
X1764100Y46552D01*
X1765224Y45804D01*
X1766125Y45984D01*
X1767249Y45235D01*
X1767429Y44334D01*
X1768552Y43585D01*
X1769454Y43766D01*
X1770577Y43017D01*
X1771190Y39952D01*
X1770466Y36329D01*
X1772819Y25256D01*
X1771693Y19962D01*
X1766216Y17608D01*
X1757882D01*
X1748522Y19597D01*
X1746227Y21913D01*
Y22747D01*
X1746677Y23197D01*
X1748152D01*
G01X1368441Y492723D02*
Y494098D01*
X1368891Y494548D01*
X1369859D01*
X1370821Y493586D01*
Y492025D01*
X1368994Y490198D01*
X1359214D01*
X1357066Y488050D01*
Y479346D01*
X1358124Y477660D01*
X1362441Y475198D01*
X1412224Y464614D01*
X1417895Y460283D01*
X1419051Y454839D01*
X1418550Y454068D01*
X1418831Y452747D01*
X1419602Y452247D01*
X1419882Y450926D01*
X1419381Y450155D01*
X1419662Y448834D01*
X1420433Y448334D01*
X1420713Y447013D01*
X1417706Y432861D01*
Y414604D01*
X1417256Y414154D01*
X1414038D01*
X1412915Y413031D01*
Y411027D01*
X1414038Y409904D01*
X1417256D01*
X1417706Y409454D01*
Y408404D01*
X1417256Y407954D01*
X1414038D01*
X1412915Y406831D01*
Y404827D01*
X1414038Y403704D01*
X1417256D01*
X1417706Y403254D01*
Y398980D01*
X1416310Y397584D01*
Y389290D01*
X1413425Y386405D01*
Y365866D01*
X1418000Y361291D01*
Y325265D01*
X1416055Y323320D01*
Y300844D01*
X1413653Y291344D01*
X1406277Y275369D01*
X1405200Y269960D01*
X1406266Y266646D01*
X1410512Y260639D01*
X1416854Y230776D01*
X1412921Y212264D01*
X1414933Y206363D01*
X1414700Y205200D01*
X1413560Y199494D01*
X1413858Y198002D01*
X1415927Y194440D01*
X1417461Y194032D01*
X1418074Y194389D01*
X1418689Y194225D01*
X1419142Y193446D01*
X1418978Y192831D01*
X1418365Y192475D01*
X1417957Y190941D01*
X1428912Y172076D01*
X1434090Y145807D01*
X1448113Y128534D01*
X1452543Y121886D01*
X1452362Y120984D01*
X1453111Y119861D01*
X1454012Y119680D01*
X1454761Y118557D01*
X1455450Y115111D01*
X1455098Y114583D01*
X1454259Y114415D01*
X1453376Y113095D01*
X1453740Y111275D01*
X1455062Y110393D01*
X1455902Y110561D01*
X1456430Y110208D01*
X1459523Y94747D01*
X1479968Y64072D01*
X1486741Y59558D01*
X1493794Y58057D01*
X1496664Y58668D01*
X1525071Y52633D01*
X1541420Y56105D01*
X1606640Y42242D01*
X1632227Y47674D01*
X1647811Y44556D01*
X1659116Y46960D01*
X1672461Y44120D01*
X1674226Y44480D01*
X1678032Y43706D01*
X1681870Y44489D01*
X1683346Y45466D01*
X1687802Y46372D01*
X1697602Y44379D01*
X1701962Y45258D01*
X1703852Y46506D01*
X1718430Y49475D01*
X1722625Y48622D01*
X1722627Y48620D01*
X1722628D01*
X1722640Y48616D01*
X1725276Y48091D01*
X1729682Y48993D01*
X1729945Y48819D01*
X1729946Y48818D01*
X1730211Y48643D01*
X1730466Y47398D01*
X1731792Y46523D01*
X1733610Y46895D01*
X1734485Y48221D01*
X1734230Y49465D01*
X1734580Y49995D01*
X1738306Y50758D01*
X1738313D01*
X1742909Y49842D01*
X1744231Y50724D01*
X1744621Y52665D01*
X1745150Y53018D01*
X1746033Y52840D01*
X1746386Y52311D01*
X1745996Y50370D01*
X1746877Y49048D01*
X1748698Y48682D01*
X1750019Y49563D01*
X1750409Y51504D01*
X1750938Y51857D01*
X1751821Y51679D01*
X1752174Y51150D01*
X1751784Y49209D01*
X1752665Y47888D01*
X1758780Y46660D01*
X1764284Y42699D01*
X1766780Y38605D01*
X1767551Y35083D01*
X1764793Y28387D01*
Y25443D01*
X1763360Y24010D01*
G01X1386241Y482623D02*
X1384464Y484400D01*
X1379301D01*
X1378401Y483500D01*
Y481599D01*
X1382055Y477946D01*
X1414399Y471071D01*
X1423346Y464238D01*
X1427130Y446419D01*
X1425309Y437844D01*
Y405528D01*
X1428166Y391579D01*
Y375407D01*
X1424900Y360039D01*
Y298974D01*
X1421859Y295932D01*
X1419241Y287569D01*
X1415903Y271852D01*
X1416713Y267798D01*
X1416085Y264658D01*
X1422725Y233406D01*
X1428359Y221855D01*
X1422990Y205595D01*
X1424931Y199902D01*
X1427432Y187401D01*
X1434475Y176901D01*
X1437198Y163295D01*
X1440809Y158711D01*
X1441834Y156442D01*
X1444891Y142826D01*
X1451694Y134450D01*
X1460749Y120868D01*
X1465772Y97246D01*
X1485078Y68281D01*
X1488985Y65676D01*
X1493606Y64694D01*
X1495926Y65187D01*
X1524513Y59114D01*
X1540703Y62556D01*
X1606137Y48647D01*
X1632194Y54186D01*
X1648176Y50991D01*
X1669800Y55549D01*
X1673657Y54765D01*
X1675848Y53317D01*
X1679302Y52616D01*
X1680128Y52782D01*
X1682761Y54525D01*
X1688158Y55622D01*
X1692096Y54821D01*
X1729553Y62317D01*
X1731365Y63527D01*
X1735921Y64716D01*
X1748817Y62135D01*
X1774004Y45348D01*
X1775073Y39999D01*
X1774296Y36110D01*
X1776616Y25174D01*
X1774927Y17253D01*
X1767259Y13958D01*
X1757472D01*
X1736974Y18305D01*
Y18306D01*
X1735190Y20090D01*
Y21810D01*
X1734688Y22312D01*
X1733168D01*
G01X1366309Y486618D02*
Y486255D01*
X1367882Y484682D01*
X1371780D01*
X1380600Y475862D01*
X1380601D01*
X1381322Y475141D01*
X1413716Y468256D01*
X1421140Y462584D01*
X1424551Y446521D01*
X1422058Y434786D01*
Y408877D01*
X1425664Y391265D01*
Y376917D01*
X1422400Y361527D01*
Y300573D01*
X1419605Y297777D01*
X1417306Y290435D01*
X1409832Y274239D01*
X1409033Y270108D01*
X1409550Y268506D01*
X1414023Y262176D01*
X1420970Y229480D01*
X1417570Y213463D01*
X1422174Y199965D01*
X1424836Y186659D01*
X1432112Y175742D01*
X1437743Y147584D01*
X1449798Y132739D01*
X1458367Y119886D01*
X1463096Y96459D01*
X1483035Y66543D01*
X1488464Y62924D01*
X1493428Y61868D01*
X1496436Y62508D01*
X1525061Y56427D01*
X1541280Y59871D01*
X1606367Y46037D01*
X1632379Y51558D01*
X1648196Y48395D01*
X1659289Y50753D01*
X1672381Y48044D01*
X1673988Y48370D01*
X1674217Y48324D01*
Y48323D01*
X1678093Y47536D01*
X1679818Y47888D01*
X1679817D01*
Y47889D01*
X1680454Y48313D01*
X1681743Y50259D01*
X1683990Y51746D01*
X1685706Y52098D01*
X1687968Y51639D01*
X1690899Y49701D01*
X1691668Y49544D01*
X1714869Y54229D01*
X1717528Y56000D01*
X1720488Y56591D01*
X1729336Y54822D01*
X1743216Y57771D01*
X1753644Y55685D01*
X1771612Y43710D01*
X1772363Y39952D01*
X1771641Y36336D01*
X1773995Y25255D01*
X1772694Y19140D01*
X1772695D01*
X1766453Y16458D01*
X1757761D01*
X1747947Y18543D01*
X1745077Y21439D01*
Y22747D01*
X1744627Y23197D01*
X1743152D01*
G01X1368441Y497523D02*
Y496148D01*
X1368891Y495698D01*
X1370336D01*
X1371971Y494063D01*
Y491548D01*
X1369471Y489048D01*
X1359691D01*
X1358216Y487573D01*
Y479677D01*
X1358945Y478516D01*
X1362855Y476286D01*
X1412717Y465686D01*
X1418932Y460939D01*
X1421889Y447013D01*
X1418856Y432740D01*
Y414127D01*
X1417733Y413004D01*
X1414515D01*
X1414065Y412554D01*
Y411504D01*
X1414515Y411054D01*
X1417733D01*
X1418856Y409931D01*
Y407927D01*
X1417733Y406804D01*
X1414515D01*
X1414065Y406354D01*
Y405304D01*
X1414515Y404854D01*
X1417733D01*
X1418856Y403731D01*
Y398503D01*
X1417460Y397107D01*
Y388813D01*
X1414575Y385928D01*
Y366343D01*
X1419150Y361768D01*
Y324788D01*
X1417205Y322843D01*
Y300700D01*
X1414742Y290959D01*
X1407379Y275010D01*
X1406387Y270028D01*
X1407307Y267166D01*
X1411588Y261110D01*
X1418030Y230776D01*
X1414112Y212335D01*
X1416122Y206441D01*
X1415678Y204222D01*
X1414733Y199494D01*
X1414949Y198415D01*
X1416683Y195430D01*
X1417295Y195267D01*
X1417908Y195624D01*
X1419445Y195215D01*
X1420377Y193611D01*
X1419967Y192075D01*
X1419355Y191719D01*
X1419192Y191106D01*
X1430004Y172487D01*
X1435163Y146310D01*
X1449040Y129217D01*
X1455845Y119006D01*
X1456672Y114869D01*
X1455791Y113548D01*
X1454951Y113380D01*
X1454598Y112852D01*
X1454775Y111968D01*
X1455304Y111615D01*
X1456144Y111783D01*
X1457465Y110901D01*
X1460606Y95196D01*
X1480798Y64902D01*
X1487196Y60637D01*
X1493794Y59233D01*
X1496665Y59844D01*
X1525071Y53809D01*
X1541420Y57281D01*
X1606640Y43418D01*
X1632220Y48849D01*
X1647806Y45731D01*
X1659116Y48136D01*
X1672466Y45295D01*
X1674226Y45654D01*
X1678032Y44880D01*
X1681421Y45572D01*
X1682897Y46549D01*
X1687802Y47546D01*
X1697603Y45553D01*
X1701515Y46342D01*
X1703404Y47589D01*
X1718430Y50649D01*
X1722854Y49754D01*
X1722866Y49750D01*
X1725273Y49265D01*
X1729919Y50216D01*
X1731243Y49341D01*
X1731498Y48096D01*
X1732028Y47746D01*
X1732912Y47927D01*
X1733262Y48457D01*
X1733007Y49702D01*
X1733883Y51027D01*
X1738189Y51908D01*
X1738427D01*
X1742667Y51063D01*
X1743197Y51417D01*
X1743587Y53358D01*
X1744909Y54240D01*
X1746726Y53874D01*
X1747608Y52553D01*
X1747218Y50611D01*
X1747570Y50082D01*
X1748457Y49904D01*
X1748985Y50256D01*
X1749375Y52197D01*
X1750697Y53079D01*
X1752514Y52713D01*
X1753396Y51392D01*
X1753006Y49450D01*
X1753358Y48922D01*
X1759250Y47739D01*
X1765145Y43497D01*
X1767863Y39039D01*
X1768752Y34977D01*
X1765943Y28159D01*
Y25136D01*
X1767069Y24010D01*
G01X1418241Y489523D02*
X1420017Y491299D01*
X1421289D01*
X1422966Y489622D01*
Y485650D01*
X1422316Y485000D01*
Y483650D01*
X1422966Y483000D01*
Y481650D01*
X1422316Y481000D01*
Y479650D01*
X1422966Y479000D01*
Y477650D01*
X1426298Y474318D01*
Y473399D01*
X1427252Y472445D01*
X1428171D01*
X1429126Y471490D01*
Y470571D01*
X1430080Y469617D01*
X1430999D01*
X1431954Y468662D01*
Y467743D01*
X1432908Y466789D01*
X1433827D01*
X1434782Y465834D01*
Y464915D01*
X1435736Y463961D01*
X1436655D01*
X1437686Y462930D01*
Y458729D01*
X1437036Y458079D01*
Y456729D01*
X1437686Y456079D01*
Y454729D01*
X1437036Y454079D01*
Y452729D01*
X1437686Y452079D01*
Y444741D01*
X1437036Y444091D01*
Y442741D01*
X1437686Y442091D01*
Y440741D01*
X1437036Y440091D01*
Y438741D01*
X1437686Y438091D01*
Y436741D01*
X1429304Y428359D01*
Y415369D01*
X1432066Y412607D01*
Y370827D01*
X1428750Y354405D01*
Y297036D01*
X1425520Y293806D01*
X1425519D01*
X1425518Y293805D01*
X1423164Y286283D01*
X1423163Y286281D01*
X1420197Y272313D01*
X1420930Y268649D01*
X1420174Y264874D01*
X1426546Y234868D01*
X1432732Y222186D01*
X1429213Y205603D01*
X1434191Y190998D01*
X1444510Y182449D01*
X1444861Y180700D01*
X1444978Y180114D01*
X1444083Y175637D01*
X1445655Y167774D01*
X1448947Y162837D01*
X1455641Y158374D01*
X1457023Y151479D01*
X1456594Y149335D01*
X1460603Y129283D01*
X1464237Y123839D01*
X1469501Y99079D01*
X1488167Y71071D01*
X1489753Y70014D01*
X1494097Y69092D01*
X1495454Y69380D01*
X1524532Y63205D01*
X1540378Y66570D01*
X1605694Y52688D01*
X1631859Y58244D01*
X1646804Y55252D01*
X1669861Y60147D01*
X1673435Y59430D01*
X1685118Y61762D01*
X1689469Y60889D01*
X1702450Y63531D01*
X1703254Y64063D01*
X1716966Y66854D01*
X1723347Y65557D01*
X1723813D01*
X1723814Y65558D01*
X1726226Y66070D01*
X1727929Y67206D01*
X1735571Y69243D01*
X1744200Y68069D01*
X1753552Y69937D01*
X1763043Y68025D01*
Y68026D01*
X1763044D01*
Y68025D01*
X1765510Y64713D01*
X1769163Y63747D01*
X1772560Y64658D01*
X1774424Y63981D01*
X1776680Y61719D01*
X1780192Y56200D01*
X1778330Y47450D01*
X1779095Y43853D01*
X1782667Y38518D01*
X1785281Y26223D01*
X1784381Y24872D01*
X1782432Y23571D01*
X1780187Y20205D01*
X1779348Y16194D01*
X1778090Y14308D01*
X1776475Y11886D01*
X1764265Y6534D01*
X1721082D01*
X1718629Y7055D01*
X1717300Y8693D01*
Y10759D01*
X1717721Y11180D01*
X1719297D01*
G01X1418441Y482523D02*
Y481271D01*
X1417820Y480650D01*
X1410724D01*
X1409050Y478976D01*
Y476024D01*
X1411778Y473296D01*
X1421723D01*
X1434425Y460594D01*
Y437036D01*
X1426804Y429415D01*
Y414169D01*
X1429516Y411457D01*
Y374005D01*
X1426250Y357883D01*
Y298249D01*
X1423378Y295377D01*
X1420583Y286442D01*
X1420582Y286440D01*
X1417527Y272058D01*
X1418290Y268246D01*
X1417581Y264708D01*
X1424078Y234119D01*
X1430062Y221849D01*
X1425875Y202144D01*
X1428617Y188444D01*
X1436053Y177364D01*
X1436796Y173660D01*
X1438702Y170802D01*
X1442020Y168591D01*
X1447564Y160277D01*
X1453113Y156577D01*
X1454189Y151538D01*
X1453781Y149496D01*
X1457959Y128605D01*
X1461759Y122910D01*
X1467042Y98065D01*
X1486367Y69072D01*
X1488731Y67497D01*
X1494077Y66360D01*
X1495689Y66703D01*
X1524403Y60607D01*
X1540396Y64005D01*
X1605868Y50089D01*
X1631923Y55619D01*
X1639812Y54042D01*
Y54041D01*
X1647025Y52599D01*
X1669415Y57346D01*
X1672577Y56711D01*
X1683346Y58789D01*
X1687690Y57919D01*
X1703467Y61113D01*
X1704233Y60605D01*
X1705556Y60873D01*
X1706064Y61639D01*
X1707387Y61907D01*
X1708153Y61399D01*
X1709476Y61667D01*
X1709984Y62433D01*
X1711307Y62701D01*
X1712073Y62193D01*
X1713396Y62461D01*
X1713904Y63227D01*
X1715227Y63495D01*
X1721467Y62225D01*
X1729091Y63760D01*
X1731465Y65342D01*
X1735486Y66299D01*
X1747852Y64339D01*
X1758882Y61610D01*
X1763764Y62586D01*
X1765069Y62241D01*
X1765532Y61447D01*
X1766837Y61102D01*
X1767631Y61565D01*
X1769648Y61032D01*
X1769649D01*
X1771982Y61743D01*
X1773323Y61256D01*
X1774608Y59963D01*
X1777471Y55667D01*
X1776317Y50241D01*
X1775546Y49741D01*
X1775265Y48420D01*
X1775766Y47649D01*
X1775485Y46329D01*
X1776669Y40409D01*
X1775741Y36041D01*
X1778035Y25236D01*
X1776132Y16271D01*
X1768186Y12608D01*
X1756578D01*
X1756577Y12609D01*
Y12608D01*
X1750727Y13848D01*
X1736886D01*
X1734451Y13198D01*
X1733000Y12229D01*
X1729921Y9150D01*
X1727478D01*
X1726768Y9860D01*
Y10968D01*
X1727181Y11381D01*
X1728678D01*
G01X1700200Y11317D02*
X1698771D01*
X1698072Y10618D01*
Y9028D01*
X1705825Y1275D01*
X1765174D01*
X1780100Y7822D01*
X1784631Y14629D01*
X1792401Y19808D01*
X1797088Y26835D01*
X1796908Y27736D01*
X1797657Y28859D01*
X1798558Y29040D01*
X1799776Y30865D01*
X1799596Y31767D01*
X1800345Y32890D01*
X1801246Y33070D01*
X1802174Y34461D01*
X1801880Y35929D01*
X1799691Y39213D01*
X1794191Y40313D01*
X1789876Y46787D01*
X1788975Y46967D01*
X1788226Y48090D01*
X1788407Y48992D01*
X1787658Y50115D01*
X1786505Y55875D01*
X1772065Y78574D01*
X1765679Y79852D01*
X1757657Y78238D01*
X1751465Y79500D01*
X1749625Y81339D01*
X1742756Y82736D01*
X1711272Y74356D01*
Y74357D01*
X1711271D01*
X1709699Y72008D01*
X1700826Y70230D01*
X1699008Y70600D01*
X1690426Y68855D01*
X1686779Y69585D01*
X1645644Y60917D01*
X1632386Y63805D01*
X1605481Y57937D01*
X1603271Y58408D01*
X1599934Y63450D01*
X1596596Y64131D01*
X1586044Y61986D01*
X1540225Y71725D01*
X1524242Y68515D01*
X1499167Y73841D01*
X1492656Y78393D01*
X1487981Y80659D01*
X1479719Y93048D01*
X1476452Y105482D01*
X1477884Y112225D01*
X1475208Y123648D01*
X1476855Y130841D01*
X1474624Y133948D01*
X1464543Y140667D01*
X1456790Y179466D01*
X1439520Y193780D01*
X1434875Y207386D01*
X1438173Y222981D01*
X1431288Y237098D01*
X1426522Y259530D01*
X1427419Y263752D01*
X1429724Y267212D01*
X1430016Y268665D01*
X1428311Y275150D01*
X1432083Y292911D01*
X1433750Y294577D01*
Y351910D01*
X1437891Y371295D01*
Y397792D01*
X1450900Y410801D01*
Y447483D01*
X1443700Y454683D01*
Y466041D01*
X1433150Y476591D01*
Y478779D01*
X1435097Y480726D01*
X1441252D01*
X1441842Y481316D01*
Y482924D01*
G01X1442041Y494423D02*
Y493143D01*
X1441398Y492500D01*
X1432485D01*
X1429530Y489545D01*
Y475660D01*
X1440241Y464949D01*
Y435747D01*
X1431804Y427310D01*
Y416569D01*
X1434666Y413707D01*
Y369678D01*
X1431250Y352827D01*
Y295777D01*
X1427855Y292382D01*
X1425265Y284133D01*
X1422852Y272777D01*
X1423635Y268876D01*
X1422802Y264711D01*
X1428886Y236064D01*
X1435455Y222595D01*
X1432005Y206337D01*
X1436619Y192819D01*
X1454393Y178091D01*
X1459721Y151471D01*
X1459313Y149432D01*
X1463029Y130857D01*
X1464568Y128547D01*
X1466858Y125114D01*
X1471830Y100252D01*
X1486388Y78451D01*
X1491586Y75932D01*
X1497924Y71497D01*
X1524722Y65809D01*
X1540363Y69134D01*
X1605549Y55277D01*
X1632431Y60974D01*
X1645715Y58169D01*
X1687236Y66879D01*
X1690369Y66213D01*
X1698036Y67772D01*
X1702748Y66811D01*
X1710900Y68469D01*
X1712807Y71854D01*
X1715170Y72406D01*
X1717753Y71888D01*
X1721251Y72589D01*
X1727873Y71265D01*
X1727874D01*
X1745487Y74849D01*
X1746254Y74341D01*
X1747577Y74610D01*
X1748084Y75377D01*
X1749407Y75646D01*
X1750174Y75138D01*
X1751497Y75407D01*
X1752004Y76174D01*
X1753327Y76443D01*
X1753329Y76444D01*
X1762064Y74691D01*
X1762573Y73925D01*
X1763897Y73660D01*
X1764662Y74169D01*
X1769864Y73125D01*
X1773548Y70668D01*
X1774273Y69529D01*
X1774073Y68632D01*
X1774798Y67493D01*
X1775695Y67293D01*
X1776962Y65303D01*
X1778527Y63737D01*
X1782893Y56876D01*
X1781089Y48390D01*
X1781793Y44859D01*
X1785246Y39678D01*
X1788304Y25294D01*
X1789215Y23927D01*
X1789545Y22272D01*
X1789255Y20821D01*
X1782680Y16436D01*
X1778252Y9794D01*
X1764584Y3802D01*
X1714998D01*
X1714348Y4452D01*
X1712998D01*
X1712348Y3802D01*
X1710998D01*
X1707798Y7002D01*
Y10738D01*
X1708321Y11261D01*
X1709771D01*
G01X1418341Y494423D02*
X1420315Y492449D01*
X1421766D01*
X1424116Y490099D01*
Y478127D01*
X1438836Y463407D01*
Y436264D01*
X1430454Y427882D01*
Y415846D01*
X1433216Y413084D01*
Y370712D01*
X1429900Y354290D01*
Y296559D01*
X1426532Y293191D01*
X1426530Y293185D01*
X1424278Y285991D01*
X1421372Y272307D01*
X1422103Y268649D01*
X1421349Y264881D01*
X1427642Y235245D01*
X1433940Y222335D01*
X1430404Y205674D01*
X1435176Y191677D01*
X1445558Y183075D01*
X1446034Y180700D01*
X1446151Y180114D01*
X1445256Y175637D01*
X1446740Y168220D01*
X1449777Y163667D01*
X1456675Y159067D01*
X1458196Y151479D01*
X1457767Y149335D01*
X1461686Y129732D01*
X1465316Y124294D01*
X1470580Y99534D01*
X1488997Y71901D01*
X1490208Y71094D01*
X1494097Y70268D01*
X1495454Y70556D01*
X1524530Y64382D01*
X1540378Y67746D01*
X1605694Y53864D01*
X1631852Y59419D01*
X1646797Y56427D01*
X1669854Y61322D01*
X1673436Y60603D01*
X1685118Y62935D01*
X1689467Y62063D01*
X1702001Y64614D01*
X1702805Y65146D01*
X1716966Y68028D01*
X1723463Y66707D01*
X1723684D01*
X1725771Y67150D01*
X1727449Y68269D01*
X1735498Y70414D01*
X1744164Y69235D01*
X1753553Y71110D01*
X1763704Y69066D01*
X1766193Y65723D01*
X1769161Y64938D01*
X1772598Y65860D01*
X1772601Y65867D01*
X1775058Y64975D01*
X1777584Y62443D01*
X1781415Y56421D01*
X1779506Y47450D01*
X1780174Y44309D01*
X1783746Y38974D01*
X1786507Y25988D01*
X1785211Y24043D01*
X1783262Y22741D01*
X1781268Y19751D01*
X1780429Y15741D01*
X1777246Y10967D01*
X1764506Y5384D01*
X1720961D01*
X1717992Y6014D01*
X1716150Y8285D01*
Y10609D01*
X1715579Y11180D01*
X1714297D01*
G01X1723678Y11381D02*
X1725219D01*
X1725618Y10982D01*
Y9383D01*
X1727001Y8000D01*
X1730398D01*
X1733733Y11335D01*
X1734932Y12135D01*
X1737037Y12698D01*
X1750606D01*
X1756456Y11458D01*
X1768439D01*
X1777138Y15467D01*
X1778090Y19953D01*
X1779211Y25236D01*
X1776917Y36041D01*
X1777844Y40402D01*
X1776660Y46322D01*
X1778697Y55902D01*
X1775503Y60694D01*
X1773958Y62250D01*
X1772014Y62955D01*
X1769626Y62228D01*
X1763800Y63766D01*
X1758909Y62789D01*
X1748081Y65468D01*
X1735441Y67471D01*
X1730998Y66414D01*
X1728642Y64843D01*
X1721468Y63399D01*
X1715228Y64669D01*
X1687689Y59093D01*
X1683350Y59961D01*
X1672581Y57884D01*
X1669409Y58521D01*
X1647020Y53774D01*
X1631916Y56794D01*
X1605868Y51265D01*
X1574306Y57974D01*
X1540396Y65181D01*
X1524403Y61783D01*
X1495689Y67879D01*
X1494077Y67536D01*
X1489186Y68576D01*
X1487197Y69902D01*
X1468121Y98520D01*
X1462838Y123365D01*
X1459042Y129054D01*
X1454954Y149496D01*
X1455364Y151546D01*
X1454141Y157275D01*
X1448394Y161107D01*
X1442977Y169229D01*
Y169230D01*
X1442849Y169421D01*
X1439532Y171632D01*
X1437879Y174109D01*
X1437136Y177815D01*
X1429700Y188894D01*
X1427050Y202137D01*
X1431270Y221997D01*
X1425174Y234496D01*
X1418756Y264715D01*
X1419463Y268246D01*
X1418702Y272051D01*
X1421697Y286150D01*
X1424392Y294763D01*
X1427400Y297772D01*
Y357767D01*
X1430666Y373889D01*
Y411934D01*
X1427954Y414646D01*
Y428938D01*
X1435575Y436559D01*
Y461071D01*
X1422200Y474446D01*
X1412255D01*
X1410200Y476501D01*
Y478499D01*
X1411201Y479500D01*
X1417982D01*
X1418341Y479141D01*
Y477323D01*
G01X1695200Y11317D02*
X1696223D01*
X1696922Y10618D01*
Y8551D01*
X1705348Y125D01*
X1765416D01*
X1780871Y6904D01*
X1785461Y13800D01*
X1793231Y18978D01*
X1803396Y34219D01*
X1802963Y36378D01*
X1800384Y40248D01*
X1794884Y41348D01*
X1788741Y50564D01*
X1787591Y56311D01*
X1772772Y79606D01*
X1765678Y81026D01*
X1757658Y79412D01*
X1752034Y80558D01*
X1750194Y82398D01*
X1742721Y83917D01*
X1710556Y75357D01*
X1709007Y73043D01*
X1700828Y71404D01*
X1699008Y71774D01*
X1690424Y70029D01*
X1686773Y70759D01*
X1645648Y62094D01*
X1632386Y64983D01*
X1605479Y59115D01*
X1603971Y59436D01*
X1600631Y64482D01*
X1596596Y65305D01*
X1586049Y63161D01*
X1540231Y72900D01*
X1526903Y70224D01*
X1524249Y69690D01*
X1499635Y74918D01*
X1493240Y79388D01*
X1488765Y81558D01*
X1480783Y93527D01*
X1477634Y105510D01*
X1479063Y112237D01*
X1476388Y123649D01*
X1478093Y131091D01*
X1475436Y134789D01*
X1465578Y141360D01*
X1457839Y180092D01*
X1457105Y180700D01*
X1440504Y194459D01*
X1436066Y207458D01*
X1439380Y223130D01*
X1432384Y237475D01*
X1427698Y259530D01*
X1428498Y263295D01*
X1430807Y266763D01*
X1431197Y268700D01*
X1429493Y275178D01*
X1433138Y292338D01*
X1434900Y294100D01*
Y351788D01*
X1439041Y371173D01*
Y397315D01*
X1452050Y410324D01*
Y447960D01*
X1444850Y455160D01*
Y466518D01*
X1434300Y477068D01*
Y478302D01*
X1435574Y479576D01*
X1441691D01*
X1442141Y479126D01*
Y477623D01*
G01X1442041Y489223D02*
Y490899D01*
X1441590Y491350D01*
X1432962D01*
X1430680Y489068D01*
Y476137D01*
X1441391Y465426D01*
Y435270D01*
X1432954Y426833D01*
Y417046D01*
X1435816Y414184D01*
Y369560D01*
X1432400Y352711D01*
Y295300D01*
X1428868Y291768D01*
X1426379Y283841D01*
X1424027Y272770D01*
X1424808Y268877D01*
X1423977Y264718D01*
X1429982Y236441D01*
X1436663Y222744D01*
X1433196Y206408D01*
X1437603Y193498D01*
X1455441Y178717D01*
X1460894Y151471D01*
X1460486Y149432D01*
X1464112Y131306D01*
X1465526Y129186D01*
X1467815Y125752D01*
Y125753D01*
X1467941Y125563D01*
X1472914Y100701D01*
X1487171Y79350D01*
X1492170Y76927D01*
X1498392Y72574D01*
X1524720Y66986D01*
X1540362Y70310D01*
X1605549Y56453D01*
X1632431Y62150D01*
X1645715Y59345D01*
X1687237Y68055D01*
X1687238D01*
X1690374Y67388D01*
X1698036Y68946D01*
X1702748Y67985D01*
X1710155Y69492D01*
X1712053Y72859D01*
X1715151Y73583D01*
X1717753Y73061D01*
X1721251Y73762D01*
X1727872Y72439D01*
X1753327Y77618D01*
X1770313Y74208D01*
X1774389Y71491D01*
X1777865Y66027D01*
X1778090Y65802D01*
X1779430Y64461D01*
X1784116Y57097D01*
X1782264Y48382D01*
X1782877Y45308D01*
X1786325Y40135D01*
Y40133D01*
X1789383Y25749D01*
X1790299Y24376D01*
X1790718Y22272D01*
X1790290Y20128D01*
X1783510Y15606D01*
X1779023Y8875D01*
X1764827Y2652D01*
X1710521D01*
X1706648Y6525D01*
Y10788D01*
X1706175Y11261D01*
X1704771D01*
G01X1522661Y491617D02*
Y507006D01*
G02X1523725Y509575I3633J0D01*
G01X1523789Y509639D01*
G03X1524903Y512332I-2701J2694D01*
G01Y513803D01*
G02X1525604Y515496I2395J0D01*
G01X1536234Y526131D01*
G02X1537366Y526600I1132J-1132D01*
G01X1565063D01*
G02X1585284Y518225I1J-28595D01*
G01X1587036Y516473D01*
G03X1589004Y515658I1968J1969D01*
G01X1601237D01*
G03X1611461Y525882I0J10224D01*
G01Y531492D01*
G02X1613636Y533667I2175J0D01*
G01X1620535D01*
G03Y535717I0J1025D01*
G01X1613636D01*
G02Y540067I0J2175D01*
G01X1620035D01*
G03Y542117I0J1025D01*
G01X1619602D01*
G02X1617139Y543135I-4J3478D01*
G01X1617138Y543136D01*
G02X1615125Y548001I4873J4865D01*
G01Y552472D01*
G03X1614110Y553487I-1015J0D01*
G01X1607856D01*
G02X1603900Y557443I0J3956D01*
G01Y569800D01*
G02X1604701Y571734I2734J1D01*
G01X1608050Y575083D01*
G03X1608513Y576201I-1118J1118D01*
G01Y576222D01*
G02X1611242Y578951I2729J0D01*
G01X1614106D01*
G03Y581001I0J1025D01*
G01X1611094D01*
G02X1608513Y583582I0J2581D01*
G01Y586261D01*
G02X1610868Y588616I2355J0D01*
G01X1611957D01*
G03X1612519Y589178I0J562D01*
G01Y590004D01*
G01X1519296Y499352D02*
Y508499D01*
G02X1520234Y510765I3206J0D01*
G01X1520235Y510766D01*
G03X1521597Y514051I-3284J3286D01*
G01Y515519D01*
G02X1522520Y517749I3155J0D01*
G01X1534511Y529740D01*
G02X1536228Y530450I1716J-1718D01*
G01X1563389D01*
G02X1587580Y520430I0J-34212D01*
G01X1588742Y519268D01*
G03X1589423Y518986I681J682D01*
G01X1601413D01*
G03X1608356Y525929I0J6943D01*
G01Y532553D01*
G03X1607118Y533790I-1237J0D01*
G01X1605940D01*
G02X1601956Y537774I0J3984D01*
G01Y545429D01*
G02X1606306I2175J-1D01*
G01Y539280D01*
G03X1608356I1025J0D01*
G01Y541341D01*
G02X1610531Y543516I2175J0D01*
G01X1611508D01*
G03Y545566I0J1025D01*
G01X1610531D01*
G02X1608356Y547741I0J2175D01*
G01Y548696D01*
G03X1606886Y550166I-1470J0D01*
G01X1604316D01*
G02X1602585Y550882I-1J2447D01*
G01X1594308Y559159D01*
G02X1593312Y561564I2406J2405D01*
G01Y571012D01*
G02X1594662Y574274I4615J1D01*
G01X1595352Y574964D01*
G03X1595904Y576294I-1330J1331D01*
G01Y580758D01*
G02X1596408Y581978I1725J1D01*
G01X1599876Y585446D01*
G02X1601009Y585914I1132J-1134D01*
G01X1603552D01*
G03X1604434Y586796I0J882D01*
G01Y589000D01*
G02X1604902Y590131I1601J0D01*
G01X1606563Y591791D01*
G03X1606695Y592109I-318J319D01*
G01Y598067D01*
G02X1607423Y599827I2488J1D01*
G01X1608801Y601205D01*
G02X1610300Y601825I1498J-1499D01*
G01X1611738D01*
G03X1612056Y601957I0J450D01*
G01X1613349Y603250D01*
G01X1603919Y596750D02*
X1602621Y595452D01*
G02X1602303Y595320I-318J318D01*
G01X1598987D01*
G03X1597856Y594852I0J-1601D01*
G01X1596473Y593469D01*
G03X1596476Y590144I1660J-1661D01*
G01X1597412Y589214D01*
G02X1595962Y587763I-725J-725D01*
G01X1594780Y588944D01*
G03X1592351I-1214J-1215D01*
G01X1592023Y588616D01*
G03X1591554Y587481I1135J-1134D01*
G01Y579900D01*
G02X1590931Y578399I-2123J2D01*
G03X1590145Y576500I1901J-1899D01*
G01Y573869D01*
G02X1589351Y573075I-794J0D01*
G03Y568975I0J-2050D01*
G01X1589873D01*
G02X1590145Y568703I0J-272D01*
G01Y567969D01*
G02X1589351Y567175I-794J0D01*
G03Y563075I0J-2050D01*
G01X1589605D01*
G02X1590145Y562535I0J-540D01*
G01Y560225D01*
G03X1591128Y557850I3359J-1D01*
G01X1597165Y551813D01*
G02X1598017Y549756I-2057J-2057D01*
G01Y536869D01*
G02X1595967I-1025J0D01*
G01Y548475D01*
G03X1594859Y551156I-3791J3D01*
G03X1594783Y551230I-2683J-2679D01*
G01X1594764Y551248D01*
X1591110Y554900D01*
G03X1587976I-1567J-1568D01*
G03X1587975Y551885I1506J-1508D01*
G01X1590836Y549024D01*
G02X1591617Y547138I-1887J-1886D01*
G01Y533050D01*
G02X1590744Y530858I-3194J2D01*
G02X1590681Y530793I-2324J2190D01*
G01X1590679Y530790D01*
X1588827Y528938D01*
G03Y526496I1221J-1221D01*
G01X1591376Y523947D01*
G02X1589928Y522499I-724J-724D01*
G01X1589091Y523336D01*
Y523337D01*
X1588445Y523983D01*
G03X1563692Y534236I-24753J-24753D01*
G01X1533899D01*
G03X1532767Y533767I0J-1600D01*
G01X1519417Y520417D01*
X1519418D01*
G03X1518450Y518078I2344J-2340D01*
G01Y514278D01*
X1518449Y514279D01*
G02X1517844Y512816I-2069J-1D01*
G01X1516890Y511862D01*
G03X1516166Y510112I1750J-1749D01*
G01Y498920D01*
G01X1508400Y489487D02*
Y493687D01*
G03X1508267Y494005I-450J-1D01*
G01X1505282Y496991D01*
G02X1504759Y498251I1260J1261D01*
G01Y502753D01*
G02X1505681Y504982I3152J1D01*
G01X1505847Y505148D01*
G02X1507785Y505951I1937J-1935D01*
G01X1511966D01*
G03X1513066Y507051I0J1100D01*
G01Y513896D01*
G02X1513758Y515566I2361J0D01*
G01X1514638Y516446D01*
G03X1515200Y517800I-1353J1355D01*
G01Y520266D01*
G02X1515668Y521397I1601J0D01*
G01X1531296Y537025D01*
G02X1532429Y537493I1132J-1134D01*
G01X1561263D01*
G03Y539543I0J1025D01*
G01X1545143D01*
G02Y543893I0J2175D01*
G01X1563815D01*
G02X1567881Y542210I1J-5750D01*
G01X1570845Y539246D01*
G03X1575768Y536206I8889J8889D01*
G02X1580438Y534183I-10761J-31243D01*
G03X1583514Y533400I3162J5988D01*
G03X1587063Y534870I0J5019D01*
G01X1587064Y534871D01*
G03X1588392Y538077I-3206J3206D01*
G01Y540864D01*
G03X1587457Y543119I-3190J-1D01*
G01Y543120D01*
X1585571Y545006D01*
G02X1584201Y548316I3310J3309D01*
G01Y589671D01*
G02X1584669Y590802I1601J0D01*
G01X1586986Y593119D01*
G02X1588117Y593587I1131J-1133D01*
G01X1589508D01*
G03X1589826Y593719I0J450D01*
G01X1592351Y596244D01*
G03X1592483Y596562I-317J318D01*
G01X1592484Y596561D01*
Y598791D01*
G02X1592952Y599922I1601J0D01*
G01X1599587Y606557D01*
G02X1600718Y607025I1131J-1133D01*
G01X1602258D01*
G03X1602576Y607157I0J449D01*
G01X1603869Y608450D01*
G01X1529600Y499300D02*
Y510164D01*
G02X1530485Y512301I3023J0D01*
G01X1532178Y513994D01*
G02X1532868Y514224I588J-614D01*
G03X1533557Y514454I101J844D01*
G01X1534512Y515409D01*
G03X1534742Y516098I-614J588D01*
G02X1534971Y516787I844J102D01*
G01X1535926Y517742D01*
G02X1536616Y517972I588J-614D01*
G03X1537305Y518202I101J844D01*
G01X1538260Y519157D01*
G03X1538490Y519846I-614J588D01*
G02X1538719Y520535I844J102D01*
G01X1539674Y521490D01*
G02X1539993Y521622I319J-319D01*
G01X1565010D01*
G02X1582099Y514543I0J-24166D01*
G01X1585223Y511419D01*
G03X1587133Y510628I1910J1912D01*
G01X1602086D01*
G03X1616704Y525246I0J14618D01*
G02X1620183Y528725I3479J0D01*
G01X1622433D01*
G03X1626468Y532760I0J4035D01*
G01Y543861D01*
G02X1627493Y544886I1025J0D01*
G01X1628548D01*
G03Y549236I0J2175D01*
G01X1627210D01*
G02X1626468Y549978I0J742D01*
G01Y550719D01*
G03X1622089I-2190J0D01*
G01Y547957D01*
G02X1619982I-1054J0D01*
G01Y554657D01*
G02X1620307Y555307I850J-19D01*
G03X1620632Y555957I-525J669D01*
G01Y557307D01*
G03X1620307Y557957I-850J-19D01*
G02X1619982Y558607I525J669D01*
G01Y559957D01*
G02X1620307Y560607I850J-19D01*
G03X1620632Y561257I-525J669D01*
G01Y562607D01*
G03X1620307Y563257I-850J-19D01*
G02X1619982Y563907I525J669D01*
G01Y582014D01*
X1619983Y582013D01*
G02X1622204Y587375I7582J0D01*
G01X1623664Y588835D01*
Y588836D01*
X1623666Y588838D01*
G02X1627075Y590250I3409J-3409D01*
G01X1647161D01*
G03X1648293Y590719I0J1600D01*
G01X1650054Y592480D01*
G03X1650523Y593611I-1131J1132D01*
G01Y594708D01*
G02X1651190Y595375I667J0D01*
G01X1652049D01*
G02X1652499Y594925I0J-450D01*
G01Y593950D01*
G01X1523811Y491617D02*
Y493222D01*
G02X1524136Y493872I850J-19D01*
G03X1524461Y494522I-525J669D01*
G01Y495872D01*
G03X1524136Y496522I-850J-19D01*
G02X1523811Y497172I525J669D01*
G01Y507007D01*
X1523812Y507006D01*
G02X1524539Y508761I2482J0D01*
G01X1524603Y508826D01*
G03X1526053Y512331I-3516J3507D01*
G01Y513803D01*
G02X1526418Y514682I1244J-1D01*
G01X1527372Y515637D01*
G02X1528062Y515867I588J-614D01*
G03X1528751Y516097I101J844D01*
G01X1529706Y517052D01*
G03X1529935Y517741I-615J587D01*
G02X1530165Y518431I844J102D01*
G01X1531119Y519386D01*
G02X1531809Y519616I588J-614D01*
G03X1532498Y519846I101J844D01*
G01X1533453Y520800D01*
G03X1533682Y521490I-615J587D01*
G02X1533912Y522179I844J101D01*
G01X1537048Y525317D01*
G02X1537366Y525450I319J-317D01*
G01X1565063D01*
G02X1584470Y517411I0J-27445D01*
G01X1586222Y515659D01*
G03X1589004Y514507I2782J2783D01*
G01X1601237D01*
G03X1612611Y525882I0J11374D01*
G01Y526192D01*
G02X1612936Y526842I850J-19D01*
G03X1613261Y527492I-525J669D01*
G01Y528842D01*
G03X1612936Y529492I-850J-19D01*
G02X1612611Y530142I525J669D01*
G01Y531492D01*
G02X1613636Y532517I1025J0D01*
G01X1620535D01*
G03Y536867I0J2175D01*
G01X1613636D01*
G02Y538917I0J1025D01*
G01X1620035D01*
G03Y543267I0J2175D01*
G01X1619601D01*
G02X1617953Y543949I-2J2328D01*
G01X1617952Y543950D01*
G02X1616275Y548002I4059J4053D01*
G01Y552472D01*
G03X1614110Y554637I-2165J0D01*
G01X1607856D01*
G02X1605050Y557443I0J2806D01*
G01Y569801D01*
X1605051Y569800D01*
G02X1605515Y570920I1583J0D01*
G01X1608864Y574269D01*
G03X1609663Y576201I-1933J1931D01*
G01Y576222D01*
G02X1611242Y577801I1579J0D01*
G01X1614106D01*
G03Y582151I0J2175D01*
G01X1611094D01*
G02X1609663Y583582I0J1431D01*
G01Y586261D01*
G02X1610868Y587466I1205J0D01*
G01X1612069D01*
G02X1612519Y587016I0J-450D01*
G01Y586004D01*
G01X1520446Y499352D02*
Y508500D01*
X1520447Y508499D01*
G02X1521048Y509951I2055J0D01*
G01X1521049Y509952D01*
G03X1522747Y514051I-4099J4099D01*
G01Y515518D01*
G02X1523334Y516935I2004J0D01*
G01X1524289Y517890D01*
G02X1524978Y518119I587J-615D01*
G03X1525667Y518349I101J844D01*
G01X1526622Y519304D01*
G03X1526852Y519993I-614J588D01*
G02X1527082Y520683I844J102D01*
G01X1528037Y521638D01*
G02X1528726Y521867I587J-615D01*
G03X1529415Y522097I101J844D01*
G01X1530370Y523052D01*
G03X1530600Y523741I-614J588D01*
G02X1530830Y524431I844J102D01*
G01X1531785Y525386D01*
G02X1532474Y525615I587J-615D01*
G03X1533163Y525845I101J844D01*
G01X1534118Y526800D01*
G03X1534348Y527489I-614J588D01*
G02X1534578Y528179I844J102D01*
G01X1535324Y528926D01*
G02X1536227Y529300I903J-904D01*
G01X1563389D01*
G02X1586766Y519616I-1J-33061D01*
G01X1587928Y518454D01*
G03X1589422Y517836I1494J1496D01*
G01X1601414D01*
G03X1609506Y525929I-1J8093D01*
G01Y532553D01*
G03X1607119Y534940I-2387J0D01*
G01X1605940D01*
G02X1603106Y537774I0J2834D01*
G01Y545428D01*
G02X1605156I1025J0D01*
G01Y539280D01*
G03X1609506I2175J0D01*
G01Y541341D01*
G02X1610531Y542366I1025J0D01*
G01X1611508D01*
G03Y546716I0J2175D01*
G01X1610531D01*
G02X1609506Y547741I0J1025D01*
G01Y548696D01*
G03X1606886Y551316I-2620J0D01*
G01X1604316D01*
G02X1603399Y551696I0J1296D01*
G01X1602618Y552477D01*
G02X1602388Y553167I614J588D01*
G03X1602158Y553856I-844J101D01*
G01X1601203Y554811D01*
G03X1600514Y555041I-588J-614D01*
G02X1599825Y555270I-102J844D01*
G01X1595122Y559973D01*
G02X1594462Y561565I1592J1593D01*
G01Y571011D01*
G02X1595476Y573460I3464J0D01*
G01X1596166Y574150D01*
G03X1597054Y576294I-2144J2144D01*
G01Y580758D01*
G02X1597222Y581164I575J0D01*
G01X1600690Y584632D01*
G02X1601009Y584764I319J-319D01*
G01X1603552D01*
G03X1605584Y586796I0J2032D01*
G01Y588999D01*
G02X1605716Y589317I450J0D01*
G01X1607377Y590978D01*
G03X1607845Y592109I-1133J1131D01*
G01Y598067D01*
G02X1608237Y599013I1337J0D01*
G01X1609615Y600391D01*
G02X1610300Y600675I685J-684D01*
G01X1611738D01*
G02X1612056Y600543I0J-450D01*
G01X1613349Y599250D01*
G01X1603919Y592750D02*
X1602631Y594038D01*
G03X1602313Y594170I-318J-318D01*
G01X1598988D01*
G03X1598670Y594038I0J-450D01*
G01X1597287Y592655D01*
G03X1597288Y590960I846J-847D01*
G01X1598225Y590028D01*
G02X1595149Y586949I-1538J-1540D01*
G01X1593967Y588130D01*
G03X1593165I-401J-401D01*
G01X1592837Y587802D01*
G03X1592704Y587481I321J-321D01*
G01Y586131D01*
G03X1593029Y585481I850J19D01*
G02X1593354Y584831I-525J-669D01*
G01Y583481D01*
G02X1593029Y582831I-850J19D01*
G03X1592704Y582181I525J-669D01*
G01Y579900D01*
G02X1591745Y577585I-3274J0D01*
G03X1591295Y576499I1086J-1086D01*
G01Y573869D01*
G02X1589351Y571925I-1944J0D01*
G03Y570125I0J-900D01*
G01X1589873D01*
G02X1591295Y568703I0J-1422D01*
G01Y567969D01*
G02X1589351Y566025I-1944J0D01*
G03Y564225I0J-900D01*
G01X1589605D01*
G02X1591295Y562535I0J-1690D01*
G01Y560224D01*
X1591296Y560225D01*
G03X1591942Y558664I2208J0D01*
G01X1597979Y552627D01*
G02X1599167Y549756I-2872J-2870D01*
G01Y536869D01*
G02X1594817I-2175J0D01*
G01Y548476D01*
G03X1594044Y550343I-2641J0D01*
G01X1594042D01*
X1590297Y554086D01*
G03X1588789I-754J-754D01*
G03Y552699I694J-693D01*
G01X1591650Y549838D01*
G02X1592767Y547138I-2701J-2699D01*
G01Y533050D01*
G02X1591580Y530068I-4344J2D01*
G01X1591573Y530057D01*
Y530056D01*
X1589641Y528124D01*
G03Y527310I407J-407D01*
G01X1592190Y524761D01*
G02X1589115Y521685I-1538J-1538D01*
G01X1587941Y522859D01*
Y522860D01*
X1587631Y523169D01*
G03X1563692Y533086I-23940J-23939D01*
G01X1533898D01*
G03X1533581Y532953I2J-450D01*
G01X1531476Y530848D01*
G03X1531246Y530158I614J-588D01*
G02X1531016Y529469I-844J-101D01*
G01X1530061Y528514D01*
G02X1529372Y528284I-588J614D01*
G03X1528683Y528055I-102J-844D01*
G01X1527728Y527100D01*
G03X1527498Y526410I614J-588D01*
G02X1527268Y525721I-844J-101D01*
G01X1526313Y524766D01*
G02X1525624Y524536I-588J614D01*
G03X1524935Y524307I-102J-844D01*
G01X1523980Y523352D01*
G03X1523750Y522662I614J-588D01*
G02X1523520Y521973I-844J-101D01*
G01X1522565Y521018D01*
G02X1521876Y520788I-588J614D01*
G03X1521187Y520559I-102J-844D01*
G01X1520232Y519604D01*
G03X1519600Y518077I1530J-1527D01*
G01Y514279D01*
G02X1518658Y512002I-3220J-1D01*
G01X1517704Y511048D01*
G03X1517316Y510112I935J-936D01*
G01Y498920D01*
G01X1603869Y604450D02*
X1602576Y605743D01*
G03X1602258Y605875I-318J-317D01*
G01X1600719D01*
G03X1600401Y605743I0J-450D01*
G01X1599446Y604788D01*
G03X1599217Y604099I615J-587D01*
G02X1598987Y603410I-844J-101D01*
G01X1598032Y602455D01*
G02X1597343Y602225I-588J614D01*
G03X1596653Y601995I-102J-844D01*
G01X1593766Y599108D01*
G03X1593634Y598790I318J-318D01*
G01Y596562D01*
G02X1593165Y595430I-1600J0D01*
G01X1590640Y592905D01*
G02X1589509Y592437I-1131J1133D01*
G01X1588118D01*
G03X1587800Y592305I0J-450D01*
G01X1585483Y589988D01*
G03X1585351Y589670I318J-318D01*
G01Y588320D01*
G03X1585676Y587670I850J19D01*
G02X1586001Y587020I-525J-669D01*
G01Y585670D01*
G02X1585676Y585020I-850J19D01*
G03X1585351Y584370I525J-669D01*
G01Y578866D01*
G03X1585676Y578216I850J19D01*
G02X1586001Y577566I-525J-669D01*
G01Y576216D01*
G02X1585676Y575566I-850J19D01*
G03X1585351Y574916I525J-669D01*
G01Y563928D01*
G03X1585676Y563278I850J19D01*
G02X1586001Y562628I-525J-669D01*
G01Y561278D01*
G02X1585676Y560628I-850J19D01*
G03X1585351Y559978I525J-669D01*
G01Y548316D01*
G03X1586385Y545820I3530J0D01*
G01X1588271Y543933D01*
G02X1589542Y540864I-3070J-3069D01*
G01Y538077D01*
G02X1587878Y534057I-5684J-1D01*
G01X1587877Y534056D01*
G02X1583514Y532250I-4362J4364D01*
G02X1580005Y533110I-65J7322D01*
G03X1575406Y535114I-15000J-28145D01*
G02X1570031Y538432I4327J13022D01*
G01X1567067Y541396D01*
G03X1563815Y542743I-3252J-3252D01*
G01X1545143D01*
G03Y540693I0J-1025D01*
G01X1561263D01*
G02Y536343I0J-2175D01*
G01X1532429D01*
G03X1532110Y536211I0J-451D01*
G01X1516482Y520583D01*
G03X1516350Y520265I318J-318D01*
G01Y517799D01*
G02X1515452Y515632I-3066J1D01*
G01X1514572Y514752D01*
G03X1514216Y513896I855J-857D01*
G01Y507051D01*
G02X1511966Y504801I-2250J0D01*
G01X1507785D01*
G03X1506662Y504336I0J-1588D01*
G01X1506495Y504168D01*
G03X1505910Y502753I1416J-1414D01*
G01X1505909Y502754D01*
Y498252D01*
G03X1506095Y497805I632J1D01*
G01X1509081Y494819D01*
G02X1509550Y493687I-1132J-1132D01*
G01Y489487D01*
G01X1846517Y253500D02*
X1847421D01*
X1847850Y253071D01*
Y251745D01*
X1847089Y250984D01*
X1837851D01*
X1831520Y257315D01*
X1679215D01*
X1667830Y268700D01*
Y301234D01*
X1670398Y309386D01*
X1667971Y319646D01*
X1670624Y328064D01*
X1668668Y336334D01*
X1671333Y344791D01*
X1669343Y353200D01*
X1672691Y363824D01*
X1668697Y380705D01*
X1666310Y382265D01*
X1658980D01*
X1647219Y389729D01*
X1644458Y401382D01*
X1645356Y404232D01*
X1644437Y408114D01*
X1654390Y439708D01*
X1652867Y444517D01*
X1654163Y448716D01*
X1652399Y454317D01*
X1647762Y461723D01*
Y461724D01*
X1637873Y464676D01*
X1633223Y463143D01*
X1628223Y466120D01*
X1626741Y470312D01*
X1627337Y472264D01*
X1625381Y478068D01*
X1619989Y479939D01*
X1615943Y478948D01*
X1613257Y479661D01*
X1611297Y479013D01*
X1610475Y479427D01*
X1609194Y479003D01*
X1608780Y478182D01*
X1607498Y477759D01*
X1606677Y478172D01*
X1605396Y477748D01*
X1604982Y476927D01*
X1603700Y476504D01*
X1602879Y476917D01*
X1601597Y476493D01*
X1601184Y475672D01*
X1599146Y474999D01*
X1595344Y476329D01*
X1592504Y475651D01*
X1589318Y476607D01*
X1584544Y475504D01*
X1581414Y473547D01*
G01X1850220Y253500D02*
X1849426D01*
X1849000Y253074D01*
Y251268D01*
X1847566Y249834D01*
X1837374D01*
X1831043Y256165D01*
X1678738D01*
X1666680Y268223D01*
Y301411D01*
X1669205Y309429D01*
X1669204D01*
X1669205Y309430D01*
X1666778Y319690D01*
X1669431Y328108D01*
X1667475Y336378D01*
X1670140Y344835D01*
X1669679Y346784D01*
X1669448Y347758D01*
X1669218Y348732D01*
X1669216D01*
X1668150Y353244D01*
X1671498Y363868D01*
X1667683Y379993D01*
X1665967Y381115D01*
X1658645D01*
X1646207Y389008D01*
X1643265Y401425D01*
X1643626Y402570D01*
Y402571D01*
X1643714Y402850D01*
X1643715Y402851D01*
X1643803Y403132D01*
X1643892Y403413D01*
X1644163Y404275D01*
X1643244Y408157D01*
X1653183Y439707D01*
X1651661Y444513D01*
X1652958Y448713D01*
X1651346Y453831D01*
X1647017Y460745D01*
X1637890Y463470D01*
X1633085Y461886D01*
X1627277Y465344D01*
X1625530Y470286D01*
X1626129Y472247D01*
X1624471Y477166D01*
X1619933Y478741D01*
X1615932Y477761D01*
X1613293Y478461D01*
X1599135Y473784D01*
X1595283Y475132D01*
X1592470Y474460D01*
X1589280Y475417D01*
X1584991Y474426D01*
X1582024Y472572D01*
G01X1660680Y590750D02*
X1662065Y589365D01*
G03X1662383Y589233I318J318D01*
G01X1663264D01*
G02X1665100Y587397I0J-1836D01*
G01Y581886D01*
G03X1666150Y579351I3585J0D01*
G01X1669550Y575951D01*
G03X1673172Y574450I3624J3625D01*
G01X1689764D01*
G02X1694056Y572672I0J-6070D01*
G01X1696197Y570531D01*
G02X1697450Y567504I-3030J-3027D01*
G01Y564413D01*
G02X1693687Y560650I-3763J0D01*
G01X1667891D01*
G03X1665751Y559764I-1J-3025D01*
G01X1663261Y557274D01*
G02X1660070Y555953I-3191J3194D01*
G01X1658234D01*
G03X1655381Y554771I0J-4034D01*
G01X1643596Y542986D01*
G03X1642083Y539334I3651J-3652D01*
G01Y526099D01*
G02X1640673Y522695I-4816J1D01*
G01X1634771Y516793D01*
G03X1633075Y512698I4093J-4094D01*
G01X1633074Y512699D01*
Y505278D01*
G02X1628238Y500442I-4836J0D01*
G01X1584291D01*
G02X1581695Y501517I0J3673D01*
G01X1575791Y507421D01*
G03X1566550Y511250I-9242J-9239D01*
G01X1566143D01*
G03X1563001Y509949I-1J-4442D01*
G01X1559913Y506860D01*
X1558884Y505830D01*
G03X1558400Y504661I1171J-1169D01*
G01Y497438D01*
G02X1557932Y496307I-1601J0D01*
G01X1557600Y495975D01*
G01X1658369Y606250D02*
X1657076Y604957D01*
G02X1656758Y604825I-318J318D01*
G01X1656308D01*
G03X1654708Y603225I0J-1600D01*
G01Y590011D01*
G02X1653683Y588986I-1025J0D01*
G01X1652162D01*
G03Y584636I0J-2175D01*
G01X1653683D01*
G02X1654708Y583611I0J-1025D01*
G01Y576099D01*
X1654707Y576100D01*
G02X1653896Y574150I-2750J0D01*
G01X1653858Y574112D01*
Y574113D01*
X1651372Y571627D01*
G03X1650257Y568931I2696J-2693D01*
G01Y562245D01*
X1650256Y562246D01*
G02X1649502Y560424I-2579J0D01*
G01X1649050Y559972D01*
G02X1647600I-725J725D01*
G01X1644147Y563425D01*
G03X1641071I-1538J-1538D01*
G01X1641068Y563422D01*
G03Y560346I1538J-1538D01*
G01X1643486Y557928D01*
G02Y555940I-994J-994D01*
G01X1629486Y541940D01*
G03X1628655Y539931I2010J-2008D01*
G01Y527605D01*
G03X1629225Y526112I2236J-2D01*
G01X1629367Y525954D01*
G02X1629590Y525365I-654J-584D01*
G01Y525364D01*
X1629588Y524502D01*
Y524463D01*
G02Y524431I-743J-16D01*
G02X1629341Y523870I-844J37D01*
G01X1628734Y523261D01*
G02X1628346Y523100I-388J387D01*
G01X1627143D01*
G03X1624634Y522061I0J-3550D01*
G01X1619262Y516689D01*
G03X1618438Y514700I1989J-1989D01*
G01Y510056D01*
G02X1618306Y509737I-451J0D01*
G01X1617313Y508744D01*
G02X1616603Y508450I-710J710D01*
G01X1585587D01*
G02X1585268Y508582I0J451D01*
G01X1581233Y512617D01*
G03X1564306Y519628I-16926J-16925D01*
G01X1544839D01*
G03X1542599Y518700I0J-3168D01*
G01X1538662Y514763D01*
G03X1538000Y513165I1598J-1598D01*
G01Y503600D01*
G01X1528450Y499300D02*
Y510164D01*
G02X1529671Y513115I4173J1D01*
G01X1538860Y522304D01*
G02X1539993Y522772I1132J-1134D01*
G01X1565010D01*
G02X1582913Y515357I1J-25317D01*
G01X1586037Y512233D01*
G03X1587134Y511778I1098J1097D01*
G01X1602086D01*
G03X1615554Y525246I0J13468D01*
G02X1620183Y529875I4629J0D01*
G01X1622433D01*
G03X1625318Y532760I0J2885D01*
G01Y543861D01*
G02X1627493Y546036I2175J0D01*
G01X1628548D01*
G03Y548086I0J1025D01*
G01X1627210D01*
G02X1625318Y549978I0J1892D01*
G01Y550719D01*
G03X1623239I-1039J0D01*
G01Y547957D01*
G02X1618832I-2203J0D01*
G01Y582013D01*
G02X1621390Y588189I8733J1D01*
G01X1622850Y589649D01*
Y589650D01*
G02X1627075Y591400I4225J-4225D01*
G01X1647162D01*
G03X1647479Y591533I-2J449D01*
G01X1649240Y593294D01*
G03X1649372Y593612I-317J318D01*
G01X1649373Y593611D01*
Y594708D01*
G02X1651190Y596525I1817J0D01*
G01X1652049D01*
G03X1652499Y596975I0J450D01*
G01Y597950D01*
G01X1650869Y614200D02*
Y612775D01*
G03X1651319Y612325I450J0D01*
G01X1659804D01*
G02X1662998Y611002I0J-4517D01*
G01X1663700Y610300D01*
G02X1664273Y608915I-1387J-1385D01*
G01Y600482D01*
G02X1663805Y599349I-1602J-1D01*
G01X1659518Y595062D01*
G03X1658958Y593710I1352J-1352D01*
G01Y582137D01*
G03X1660583Y578218I5540J1D01*
G01X1665125Y573676D01*
G02X1666150Y571202I-2476J-2475D01*
G01Y566123D01*
G02X1665249Y563949I-3075J1D01*
G01X1665248D01*
X1661546Y560247D01*
G02X1659714Y559487I-1833J1831D01*
G01X1656948D01*
G03X1654705Y558558I0J-3172D01*
G01X1634478Y538336D01*
G03X1634346Y538017I319J-319D01*
G01Y531914D01*
G03X1634460Y531614I452J0D01*
G02X1635300Y529401I-2495J-2213D01*
G01Y525027D01*
G02X1632964Y519387I-7979J1D01*
G01X1630750Y517173D01*
G02X1627493Y515825I-3256J3257D01*
G03X1625349Y513680I0J-2144D01*
G01X1625353Y508693D01*
G02X1624559Y506779I-2697J-3D01*
G01X1622643Y504872D01*
G02X1621018Y504200I-1625J1628D01*
G01X1584169D01*
G02X1582893Y504728I1J1807D01*
G01X1578165Y509456D01*
G03X1564110Y515279I-14056J-14053D01*
G01X1554090D01*
G03X1553773Y515146I2J-450D01*
G01X1551635Y513008D01*
G03X1551503Y512690I317J-318D01*
G01X1551502Y512691D01*
Y501192D01*
G01X1660680Y586750D02*
X1661881Y587951D01*
G02X1662199Y588083I318J-318D01*
G01X1663264D01*
G02X1663950Y587397I0J-686D01*
G01Y581887D01*
G03X1665336Y578537I4735J-3D01*
G01X1668736Y575137D01*
G03X1673173Y573300I4437J4439D01*
G01X1689763D01*
G02X1693242Y571858I-1J-4920D01*
G01X1695383Y569717D01*
G02X1696300Y567503I-2215J-2214D01*
G01Y564413D01*
G02X1693687Y561800I-2613J0D01*
G01X1667891D01*
G03X1664937Y560577I-2J-4175D01*
G01X1662447Y558088D01*
G02X1660069Y557103I-2379J2380D01*
G01X1658234D01*
G03X1654567Y555585I-1J-5185D01*
G01X1642782Y543800D01*
G03X1640933Y539334I4466J-4465D01*
G01Y526100D01*
G02X1639859Y523509I-3665J1D01*
G01X1633957Y517607D01*
G03X1631924Y512698I4907J-4908D01*
G01Y505278D01*
G02X1628238Y501592I-3686J0D01*
G01X1625591D01*
G02X1624941Y501917I19J850D01*
G03X1624291Y502242I-669J-525D01*
G01X1622941D01*
G03X1622291Y501917I19J-850D01*
G02X1621641Y501592I-669J525D01*
G01X1620291D01*
G02X1619641Y501917I19J850D01*
G03X1618991Y502242I-669J-525D01*
G01X1617641D01*
G03X1616991Y501917I19J-850D01*
G02X1616341Y501592I-669J525D01*
G01X1614991D01*
G02X1614341Y501917I19J850D01*
G03X1613691Y502242I-669J-525D01*
G01X1612341D01*
G03X1611691Y501917I19J-850D01*
G02X1611041Y501592I-669J525D01*
G01X1609691D01*
G02X1609041Y501917I19J850D01*
G03X1608391Y502242I-669J-525D01*
G01X1607041D01*
G03X1606391Y501917I19J-850D01*
G02X1605741Y501592I-669J525D01*
G01X1600193D01*
G02X1599543Y501917I19J850D01*
G03X1598893Y502242I-669J-525D01*
G01X1597543D01*
G03X1596893Y501917I19J-850D01*
G02X1596243Y501592I-669J525D01*
G01X1594893D01*
G02X1594243Y501917I19J850D01*
G03X1593593Y502242I-669J-525D01*
G01X1592243D01*
G03X1591593Y501917I19J-850D01*
G02X1590943Y501592I-669J525D01*
G01X1589593D01*
G02X1588943Y501917I19J850D01*
G03X1588293Y502242I-669J-525D01*
G01X1586943D01*
G03X1586293Y501917I19J-850D01*
G02X1585643Y501592I-669J525D01*
G01X1584292D01*
G02X1582509Y502331I1J2522D01*
G01X1576605Y508235D01*
G03X1566549Y512400I-10055J-10054D01*
G01X1566143D01*
G03X1562187Y510763I-2J-5593D01*
G01X1558070Y506644D01*
G03X1557250Y504662I1985J-1982D01*
G01Y497439D01*
G02X1557118Y497121I-450J0D01*
G01X1556786Y496789D01*
G01X1658369Y602250D02*
X1657076Y603543D01*
G03X1656758Y603675I-318J-318D01*
G01X1656308D01*
G03X1655858Y603225I0J-450D01*
G01Y590011D01*
G02X1653683Y587836I-2175J0D01*
G01X1652162D01*
G03Y585786I0J-1025D01*
G01X1653683D01*
G02X1655858Y583611I0J-2175D01*
G01Y576100D01*
G02X1654708Y573334I-3901J0D01*
G01X1654690Y573316D01*
X1654672Y573299D01*
X1652186Y570813D01*
G03X1651407Y568932I1881J-1881D01*
G01Y562246D01*
G02X1650316Y559610I-3730J0D01*
G01X1649864Y559158D01*
G02X1646786I-1539J1539D01*
G01X1643333Y562611D01*
G03X1641885I-724J-724D01*
G01X1641882Y562608D01*
G03Y561160I724J-724D01*
G01X1644300Y558742D01*
G02Y555126I-1808J-1808D01*
G01X1630300Y541126D01*
G03X1629805Y539931I1195J-1195D01*
G01Y538206D01*
G03X1630130Y537556I850J19D01*
G02X1630455Y536906I-525J-669D01*
G01Y535556D01*
G02X1630130Y534906I-850J19D01*
G03X1629805Y534256I525J-669D01*
G01Y532906D01*
G03X1630130Y532256I850J19D01*
G02X1630455Y531606I-525J-669D01*
G01Y530256D01*
G02X1630130Y529606I-850J19D01*
G03X1629805Y528956I525J-669D01*
G01Y527606D01*
G03X1630083Y526881I1085J0D01*
G01X1630082Y526879D01*
X1630223Y526722D01*
G02X1630740Y525360I-1510J-1352D01*
G01X1630738Y524500D01*
Y524462D01*
G02Y524404I-1893J-29D01*
G02X1630156Y523057I-1994J62D01*
G01X1629548Y522448D01*
G02X1628345Y521950I-1201J1200D01*
G01X1627144D01*
G03X1625448Y521247I1J-2399D01*
G01X1623824Y519623D01*
G03X1623594Y518933I614J-588D01*
G02X1623364Y518244I-844J-101D01*
G01X1622409Y517289D01*
G02X1621720Y517059I-588J614D01*
G03X1621031Y516830I-102J-844D01*
G01X1620076Y515875D01*
G03X1619588Y514700I1174J-1176D01*
G01Y510056D01*
G02X1619120Y508923I-1602J-1D01*
G01X1618127Y507930D01*
G02X1616603Y507300I-1523J1525D01*
G01X1585587D01*
G02X1584454Y507768I-1J1602D01*
G01X1580419Y511803D01*
G03X1564306Y518478I-16113J-16110D01*
G01X1550140D01*
G03X1549490Y518153I19J-850D01*
G02X1548840Y517828I-669J525D01*
G01X1547490D01*
G02X1546840Y518153I19J850D01*
G03X1546190Y518478I-669J-525D01*
G01X1544840D01*
G03X1543413Y517886I1J-2018D01*
G01X1539476Y513949D01*
G03X1539150Y513165I783J-785D01*
G01Y503600D01*
G01X1650869Y609200D02*
Y610725D01*
G02X1651319Y611175I450J0D01*
G01X1659804D01*
G02X1662184Y610188I-1J-3366D01*
G01X1662886Y609486D01*
G02X1663123Y608914I-572J-572D01*
G01Y600481D01*
G02X1662991Y600162I-452J0D01*
G01X1658704Y595876D01*
G03X1657808Y593710I2167J-2165D01*
G01Y582136D01*
G03X1659769Y577404I6691J0D01*
G01X1664311Y572862D01*
G02X1665000Y571201I-1662J-1663D01*
G01Y566124D01*
G02X1664435Y564763I-1924J1D01*
G01X1660732Y561060D01*
G02X1659713Y560637I-1020J1017D01*
G01X1656947D01*
G03X1653891Y559372I0J-4323D01*
G01X1648656Y554138D01*
G02X1647967Y553909I-587J615D01*
G03X1647277Y553679I-102J-844D01*
G01X1646322Y552724D01*
G03X1646093Y552035I615J-587D01*
G02X1645863Y551345I-844J-102D01*
G01X1644908Y550391D01*
G02X1644219Y550161I-588J614D01*
G03X1643529Y549932I-103J-844D01*
G01X1642574Y548977D01*
G03X1642345Y548288I615J-587D01*
G02X1642115Y547598I-844J-102D01*
G01X1641160Y546644D01*
G02X1640471Y546414I-588J614D01*
G03X1639781Y546185I-103J-844D01*
G01X1638826Y545230D01*
G03X1638597Y544541I615J-587D01*
G02X1638367Y543851I-844J-102D01*
G01X1637412Y542897D01*
G02X1636723Y542667I-588J614D01*
G03X1636033Y542438I-103J-844D01*
G01X1635078Y541483D01*
G03X1634849Y540794I615J-587D01*
G02X1634619Y540104I-844J-102D01*
G01X1633664Y539150D01*
G03X1633196Y538017I1134J-1132D01*
G01Y531915D01*
G03X1633599Y530850I1602J-2D01*
G02X1634150Y529401I-1634J-1450D01*
G01Y525028D01*
G02X1632150Y520201I-6828J1D01*
G01X1629936Y517987D01*
G02X1627493Y516975I-2443J2443D01*
G03X1624198Y513680I0J-3295D01*
G01X1624203Y508692D01*
G02X1623747Y507595I-1547J0D01*
G01X1621831Y505687D01*
X1621830D01*
G02X1621018Y505350I-813J812D01*
G01X1584170D01*
G02X1583707Y505542I1J657D01*
G01X1578979Y510270D01*
G03X1564109Y516429I-14869J-14868D01*
G01X1554091D01*
G03X1552959Y515960I0J-1600D01*
G01X1550821Y513822D01*
G03X1550352Y512690I1131J-1132D01*
G01Y501192D01*
G01X1854720Y253700D02*
X1855770D01*
X1856020Y253950D01*
Y255730D01*
X1851885Y259865D01*
X1680272D01*
X1670380Y269757D01*
Y299997D01*
X1673158Y308804D01*
X1671627Y315275D01*
Y315277D01*
X1670668Y319327D01*
X1673434Y328097D01*
X1671423Y336592D01*
X1673977Y344694D01*
X1672019Y352967D01*
X1675431Y363789D01*
X1671002Y382499D01*
X1667450Y384823D01*
X1660040D01*
X1649580Y391461D01*
X1647189Y401562D01*
X1648111Y404488D01*
X1647192Y408370D01*
X1657085Y439768D01*
X1655756Y443954D01*
X1657154Y448479D01*
X1654946Y455492D01*
X1652215Y459852D01*
X1652214D01*
X1649485Y464210D01*
X1637586Y467606D01*
X1633422Y466218D01*
X1630358Y467924D01*
X1629480Y470375D01*
X1630037Y472238D01*
X1624277Y489337D01*
X1616130Y492957D01*
X1607879Y490620D01*
X1602060Y492200D01*
X1595744Y490601D01*
X1586923Y492432D01*
X1583488Y491264D01*
X1567745Y496682D01*
X1565615Y496170D01*
X1565192Y496389D01*
X1562246Y497916D01*
X1561596Y501016D01*
X1561601Y503438D01*
X1561600D01*
X1561601Y503600D01*
Y503645D01*
X1561963Y504615D01*
X1563069Y505404D01*
X1564075D01*
X1565000Y506329D01*
G01X1858420Y253700D02*
X1857620D01*
X1857170Y254150D01*
Y256207D01*
X1852362Y261015D01*
X1680749D01*
X1671530Y270234D01*
Y299819D01*
X1674351Y308760D01*
X1672777Y315410D01*
Y315412D01*
X1671861Y319283D01*
X1674627Y328053D01*
X1672616Y336548D01*
X1675170Y344650D01*
X1673212Y352923D01*
X1676624Y363745D01*
X1672016Y383211D01*
X1667793Y385973D01*
X1660375D01*
X1650592Y392182D01*
X1648382Y401519D01*
X1649304Y404445D01*
X1648385Y408327D01*
X1658292Y439769D01*
X1656962Y443959D01*
X1658359Y448482D01*
X1655999Y455978D01*
X1650225Y465195D01*
X1637559Y468810D01*
X1633539Y467470D01*
X1631295Y468719D01*
X1630690Y470407D01*
X1631244Y472259D01*
X1628133Y481497D01*
X1628541Y482321D01*
X1628110Y483600D01*
X1627287Y484009D01*
X1626856Y485288D01*
X1627264Y486111D01*
X1626833Y487391D01*
X1626010Y487799D01*
X1625207Y490183D01*
X1616217Y494177D01*
X1607873Y491814D01*
X1602070Y493389D01*
X1595718Y491781D01*
X1586850Y493622D01*
X1583490Y492480D01*
X1576753Y494798D01*
X1576350Y495625D01*
X1575074Y496064D01*
X1574248Y495661D01*
X1572971Y496100D01*
X1572568Y496926D01*
X1571291Y497366D01*
X1570465Y496962D01*
X1567802Y497879D01*
X1565763Y497389D01*
X1563260Y498686D01*
X1562747Y501134D01*
X1562751Y503437D01*
X1562918Y503883D01*
X1563438Y504254D01*
X1564075D01*
X1565000Y503329D01*
G54D27*
G01X41000Y265350D02*
Y262711D01*
X49250Y254461D01*
X57139D01*
X57500Y254100D01*
G01X44310Y268160D02*
X43690Y267540D01*
Y263557D01*
X50286Y256961D01*
X56949D01*
X57444Y257456D01*
G01X37000Y265350D02*
Y262515D01*
X29357Y254872D01*
X20614D01*
X19904Y254162D01*
G01X33490Y267900D02*
X34170Y267220D01*
Y263221D01*
X28321Y257372D01*
X20328D01*
X19800Y257900D01*
G54D18*
X72074Y243282D03*
X65180Y243368D03*
X61800Y243400D03*
X68498Y243368D03*
X49560Y649770D03*
Y644670D03*
X54360D03*
X49560Y649570D03*
Y644670D03*
X54360D03*
X49560Y654670D03*
X54360D03*
X49560D03*
X54360D03*
X214820Y649570D03*
Y644670D03*
X210020D03*
X214820Y649770D03*
Y644670D03*
X210020D03*
X214820Y654670D03*
X210020D03*
X214820D03*
X210020D03*
X238282Y649670D03*
Y644770D03*
X243082D03*
X238282Y649870D03*
Y644770D03*
X243082D03*
X238282Y654770D03*
X243082D03*
X238282D03*
X243082D03*
X402404Y649650D03*
Y644550D03*
X397604D03*
X402404Y649450D03*
Y644550D03*
X397604D03*
X402404Y654550D03*
X397604D03*
X402404D03*
X397604D03*
X425750Y649400D03*
Y644500D03*
Y649600D03*
Y644500D03*
Y654500D03*
D03*
X589871Y649379D03*
Y644279D03*
X589872Y649180D03*
Y644280D03*
X589871Y654279D03*
X589872Y654280D03*
X613298Y649331D03*
Y644231D03*
X618098D03*
X613298Y649131D03*
Y644231D03*
X618098D03*
X613298Y654231D03*
X618098D03*
X613298D03*
X618098D03*
X905515Y649159D03*
Y644259D03*
X900715D03*
X905515Y649359D03*
Y644259D03*
X900715D03*
X905515Y654259D03*
X900715D03*
X905515D03*
X900715D03*
X928952Y649120D03*
Y644220D03*
X933752D03*
X928952Y649320D03*
Y644220D03*
X933752D03*
X928952Y654220D03*
X933752D03*
X928952D03*
X933752D03*
X1219041Y649348D03*
Y644248D03*
X1214241D03*
X1219041Y649148D03*
Y644248D03*
X1214241D03*
X1219041Y654248D03*
X1214241D03*
X1219041D03*
X1214241D03*
X1242450Y649150D03*
Y644250D03*
Y649350D03*
Y644250D03*
Y654250D03*
D03*
X1532539Y649378D03*
Y644278D03*
Y649178D03*
Y644278D03*
Y654278D03*
D03*
G54D37*
G01X17716Y380984D02*
Y380983D01*
X14683Y377950D01*
X-16699D01*
X-20038Y381289D01*
Y459674D01*
X-7309Y472403D01*
X29893D01*
X31130Y473640D01*
X65848D01*
X69083Y476875D01*
Y481417D01*
X64788Y485712D01*
Y506995D01*
X66217Y508424D01*
X66236D01*
X72847Y515035D01*
Y525327D01*
X85552Y538032D01*
Y591000D01*
X85553D01*
Y592617D01*
X90688Y597752D01*
X105252D01*
X115500Y608000D01*
Y611500D01*
X119500Y615500D01*
X390499D01*
X391499Y614500D01*
X619280D01*
X632234Y601546D01*
X650445D01*
X660739Y591252D01*
X696515D01*
X708952Y603689D01*
Y607355D01*
X717421Y615824D01*
X733119D01*
X739010Y621715D01*
X1040785D01*
X1041948Y620552D01*
X1101040D01*
X1103132Y622644D01*
X1299356D01*
X1305500Y616500D01*
X1327000D01*
X1330900Y612600D01*
Y551175D01*
X1333423Y548652D01*
X1347638D01*
X1356309Y557323D01*
X1371460D01*
X1374574Y554209D01*
X1378749D01*
X1379586Y555046D01*
X1384928D01*
X1398018Y568136D01*
X1436364D01*
X1441409Y563091D01*
Y561117D01*
G01X-4725Y373110D02*
X-5810D01*
X-9420Y376720D01*
X-17954D01*
X-20790Y379556D01*
Y475750D01*
X-19802Y476738D01*
G01X-10236Y373110D02*
Y373111D01*
X-12525Y375400D01*
X-18290D01*
X-21542Y378652D01*
Y476062D01*
X-21378Y476226D01*
Y479691D01*
X-19783Y481286D01*
G01X-14488Y434094D02*
X-18886Y438492D01*
Y456638D01*
X-9280Y466244D01*
Y468802D01*
X-6831Y471251D01*
X30551D01*
X31570Y472270D01*
X67220D01*
X70260Y475310D01*
Y477880D01*
X71050Y478670D01*
G01X-19802Y476738D02*
X-18690Y477850D01*
X-12500D01*
X-7990Y473340D01*
X4349D01*
X8686Y477677D01*
X20013D01*
X21610Y476080D01*
X59120D01*
X60190Y477150D01*
X64920D01*
X65450Y476620D01*
Y475610D01*
G01X67477Y477940D02*
X67340Y478077D01*
X59806D01*
X58736Y477007D01*
X22175D01*
X20355Y478827D01*
X8318D01*
X3758Y474267D01*
X-7606D01*
X-12149Y478810D01*
X-14960D01*
X-16980Y480830D01*
X-19327D01*
X-19783Y481286D01*
G01X-9600Y526100D02*
X-8501D01*
X-4744Y529857D01*
Y538574D01*
X-5670Y539500D01*
X-8559D01*
X-18372Y549313D01*
Y558826D01*
X-11378Y565820D01*
X-1921D01*
X-265Y564164D01*
X50184D01*
X56000Y569980D01*
Y610000D01*
X69750Y623750D01*
X96750D01*
X103239Y617261D01*
X114241D01*
X116488Y619508D01*
X393011D01*
X394011Y618508D01*
X645890D01*
X650298Y614100D01*
X655100D01*
G01X34000Y93350D02*
Y90571D01*
X36262Y88309D01*
Y83638D01*
X39200Y80700D01*
Y28398D01*
X54374Y13224D01*
Y835D01*
X64217Y-9008D01*
X81264D01*
X91165Y893D01*
X104907D01*
X107200Y-1400D01*
Y-8967D01*
X113821Y-15588D01*
X402411D01*
X405287Y-12712D01*
X621344D01*
X635870Y1814D01*
X637247D01*
X645405Y9972D01*
Y21161D01*
X646989Y22745D01*
X651156D01*
X658253Y15648D01*
X671147D01*
X676351Y20852D01*
X681687D01*
X685463Y17076D01*
X693625D01*
X694201Y16500D01*
X721190D01*
X722240Y15450D01*
Y12589D01*
X726796Y8033D01*
Y4460D01*
X731267Y-11D01*
X732484D01*
X735151Y2656D01*
X758211D01*
X760332Y535D01*
X762373D01*
X762380Y528D01*
X1021269D01*
X1024263Y-2466D01*
X1027734D01*
X1033477Y3277D01*
X1272609D01*
X1277452Y8120D01*
Y16003D01*
X1283863Y22414D01*
X1291143D01*
X1303857Y35128D01*
X1306615D01*
X1308682Y37195D01*
X1327774D01*
X1333586Y43007D01*
Y75785D01*
X1339279Y81478D01*
Y88768D01*
X1342031Y91520D01*
X1372346D01*
X1374629Y93803D01*
X1396538D01*
X1406558Y103823D01*
Y114611D01*
X1404200Y116969D01*
Y119200D01*
G01X35650Y91150D02*
X37214Y89586D01*
Y84300D01*
X40200Y81314D01*
Y28745D01*
X55460Y13485D01*
Y1472D01*
X64953Y-8021D01*
X80826D01*
X90692Y1845D01*
X105302D01*
X108153Y-1006D01*
Y-1794D01*
X108152Y-1795D01*
Y-8572D01*
X114216Y-14636D01*
X402016D01*
X404892Y-11760D01*
X620949D01*
X635475Y2766D01*
X636852D01*
X644453Y10367D01*
Y21556D01*
X648163Y25266D01*
X656234D01*
X658100Y23400D01*
Y21000D01*
X662500Y16600D01*
X670741D01*
X674641Y20500D01*
X674652D01*
X676293Y22141D01*
X681745D01*
X685858Y18028D01*
X694272D01*
X694770Y17530D01*
X724056D01*
X727748Y13838D01*
X729454D01*
X739260Y4032D01*
X760223D01*
X762775Y1480D01*
X1022879D01*
X1025259Y-900D01*
X1027910D01*
X1033039Y4229D01*
X1272214D01*
X1276500Y8515D01*
Y16398D01*
X1283468Y23366D01*
X1290748D01*
X1303463Y36081D01*
X1305207D01*
X1305208Y36080D01*
X1306220D01*
X1308287Y38147D01*
X1327379D01*
X1332634Y43402D01*
Y79779D01*
X1335055Y82200D01*
Y90680D01*
X1336096Y91721D01*
X1340885D01*
X1341636Y92472D01*
X1371837D01*
X1374120Y94755D01*
X1396143D01*
X1405606Y104218D01*
Y113194D01*
X1402500Y116300D01*
G01X3806Y302347D02*
X5092Y303633D01*
Y307773D01*
X6954Y309635D01*
Y341209D01*
X13035Y347290D01*
X33904D01*
X40674Y354060D01*
Y370221D01*
X44578Y374125D01*
Y404480D01*
X54810Y414712D01*
X57465D01*
X66140Y423387D01*
Y432487D01*
X83501Y449848D01*
Y480870D01*
X93265Y490634D01*
X97484D01*
X110323Y503473D01*
X338283D01*
X350419Y491337D01*
X475493D01*
X486212Y502056D01*
X589895D01*
X596303Y508464D01*
X618090D01*
X625300Y515674D01*
Y556680D01*
X631620Y563000D01*
X642000D01*
X644256Y565256D01*
X726135D01*
X740630Y579751D01*
X758878D01*
X760038Y580911D01*
X1020486D01*
X1025545Y575852D01*
X1030302D01*
X1035076Y580626D01*
X1265822D01*
X1271456Y586260D01*
X1274391D01*
X1281689Y578962D01*
X1290292D01*
G01X6806Y302347D02*
X5995Y303158D01*
Y307060D01*
X8238Y309303D01*
Y340225D01*
X14077Y346064D01*
X34254D01*
X41626Y353436D01*
Y369826D01*
X45530Y373730D01*
Y404085D01*
X55205Y413760D01*
X57860D01*
X67092Y422992D01*
Y432092D01*
X84453Y449453D01*
Y480475D01*
X93660Y489682D01*
X97879D01*
X110718Y502521D01*
X337605D01*
X349941Y490185D01*
X475971D01*
X486690Y500904D01*
X590373D01*
X596781Y507312D01*
X618568D01*
X626500Y515244D01*
Y556230D01*
X631994Y561724D01*
X654453D01*
X656833Y564104D01*
X726613D01*
X741108Y578599D01*
X759356D01*
X760516Y579759D01*
X1019971D01*
X1025031Y574699D01*
X1030841D01*
X1035616Y579474D01*
X1266300D01*
X1271868Y585042D01*
X1274217D01*
X1281714Y577545D01*
X1289270D01*
X1289863Y576952D01*
X1292190D01*
G01X1344761Y498282D02*
Y500839D01*
X1324993Y520607D01*
X1317361D01*
X1306199Y531769D01*
Y534609D01*
X1297880Y542928D01*
X1284400D01*
X1282472Y541000D01*
X1280000D01*
X1274700Y546300D01*
X1143423D01*
X1136900Y552823D01*
Y553588D01*
X1130612Y559876D01*
X1031975D01*
X1018421Y546322D01*
X925881D01*
X919500Y552703D01*
Y553468D01*
X915431Y557537D01*
X759225D01*
X756743Y560019D01*
X744444D01*
X743415Y561048D01*
X658101D01*
X655721Y558668D01*
X634976D01*
X629652Y553344D01*
Y514696D01*
X629653Y514695D01*
Y514073D01*
X620604Y505024D01*
X598858D01*
X580860Y487026D01*
X94762D01*
X87545Y479809D01*
Y446855D01*
X71032Y430342D01*
Y403133D01*
X68319Y400420D01*
X62627D01*
X48986Y386779D01*
Y370656D01*
X45642Y367312D01*
Y355000D01*
X47200Y353442D01*
Y352764D01*
X47300Y352664D01*
Y343301D01*
X48375Y342226D01*
X49974D01*
X50800Y341400D01*
Y336450D01*
X51670Y335580D01*
X54220D01*
X58408Y331392D01*
Y326049D01*
X64033Y320424D01*
X70724D01*
X72100Y321800D01*
G01X48550Y301650D02*
X48677Y301777D01*
Y314777D01*
X57330Y323430D01*
Y328670D01*
X54560Y331440D01*
X50908D01*
X47600Y334748D01*
Y341937D01*
X46548Y342989D01*
Y352352D01*
X44000Y354900D01*
Y367300D01*
X47834Y371134D01*
Y394695D01*
X70280Y417141D01*
Y431220D01*
X86793Y447733D01*
Y480121D01*
X94450Y487778D01*
X579982D01*
X597980Y505776D01*
X620292D01*
X628900Y514384D01*
Y553656D01*
X634664Y559420D01*
X655409D01*
X657789Y561800D01*
X745834D01*
X761489Y577455D01*
X1018895D01*
X1032198Y564152D01*
X1036043D01*
X1036066Y564129D01*
X1041128D01*
X1042500Y565501D01*
Y575053D01*
X1044354Y576907D01*
X1267907D01*
X1273200Y582200D01*
G01X-9843Y380984D02*
X-5927Y384900D01*
X-3101D01*
X-1660Y386341D01*
Y389880D01*
X660Y392200D01*
X34400D01*
X37500Y395300D01*
Y407671D01*
X46100Y416271D01*
G01X6693Y380984D02*
Y382993D01*
X8100Y384400D01*
X35300D01*
X39900Y389000D01*
Y401716D01*
X54662Y416478D01*
G01X1181Y380984D02*
X5797Y385600D01*
X34618D01*
X38700Y389682D01*
Y402146D01*
X51645Y415091D01*
Y416281D01*
G01X90831Y184982D02*
Y201811D01*
X79505Y213137D01*
Y267865D01*
X74157Y273213D01*
X61905D01*
X55018Y280100D01*
X49052D01*
X48700Y280452D01*
Y280471D01*
X46752Y282419D01*
Y313916D01*
X56578Y323742D01*
Y328358D01*
X54346Y330590D01*
X50694D01*
X46848Y334436D01*
Y341625D01*
X45796Y342677D01*
Y351052D01*
X42848Y354000D01*
Y368248D01*
X46682Y372082D01*
Y403411D01*
X55831Y412560D01*
X64069D01*
X69344Y417835D01*
Y431914D01*
X86041Y448611D01*
Y480433D01*
X94138Y488530D01*
X98423D01*
X110385Y500492D01*
Y500530D01*
X111308Y501453D01*
X112614D01*
X112698Y501369D01*
X336659D01*
X348995Y489033D01*
X579607D01*
X597134Y506560D01*
X618880D01*
X627700Y515380D01*
Y554086D01*
X634186Y560572D01*
X654931D01*
X657311Y562952D01*
X727091D01*
X741586Y577447D01*
X759834D01*
X760994Y578607D01*
X1019392D01*
X1024452Y573547D01*
X1031319D01*
X1036094Y578322D01*
X1266778D01*
X1272232Y583776D01*
X1273853D01*
X1280000Y577629D01*
Y566500D01*
X1282371Y564129D01*
X1289371D01*
X1290200Y563300D01*
X1290900D01*
G01X-4725Y388858D02*
X-273Y393310D01*
X29060D01*
X36430Y400680D01*
Y408725D01*
X30641Y414514D01*
Y426698D01*
X74430Y470487D01*
Y479670D01*
X65540Y488560D01*
Y506407D01*
X73599Y514466D01*
Y525015D01*
X86305Y537721D01*
Y590672D01*
X92633Y597000D01*
X108546D01*
X113200Y601654D01*
X625860D01*
X628548Y598966D01*
X647875D01*
X660341Y586500D01*
X695634D01*
X702702Y593568D01*
X712427D01*
X715573Y596714D01*
Y598744D01*
X725829Y609000D01*
X734878D01*
X742176Y616298D01*
X1038702D01*
X1040299Y614701D01*
X1282919D01*
X1283399Y615181D01*
X1291619D01*
X1294800Y612000D01*
X1324529D01*
X1326126Y610403D01*
Y550427D01*
X1322931Y547232D01*
Y544756D01*
X1326008Y541679D01*
X1329604D01*
X1330305Y542380D01*
X1350096D01*
X1354043Y546327D01*
X1367358D01*
X1369124Y548093D01*
X1381553D01*
X1382450Y548990D01*
X1387439D01*
X1389975Y551526D01*
X1400602D01*
X1409427Y542701D01*
X1419599D01*
X1424900Y537400D01*
X1430524D01*
X1463770Y504154D01*
Y496185D01*
X1466851Y493104D01*
Y486767D01*
X1474248Y479370D01*
X1482851D01*
X1484000Y478221D01*
Y471000D01*
X1485100Y469900D01*
G01X1458060Y495020D02*
Y499841D01*
X1453500Y504401D01*
X1450321D01*
X1442600Y512122D01*
X1415204D01*
X1410971Y516355D01*
X1404451D01*
X1397216Y523590D01*
X1394994D01*
X1390207Y528377D01*
X1336477D01*
X1330250Y522150D01*
X1317946D01*
X1307703Y532393D01*
Y535233D01*
X1294771Y548165D01*
Y562668D01*
X1296600Y564497D01*
Y578671D01*
X1296676Y578747D01*
Y580053D01*
X1296600Y580129D01*
Y588207D01*
X1295772Y589035D01*
Y594310D01*
X1292482Y597600D01*
X740819D01*
X727567Y584348D01*
X715442D01*
X710258Y579164D01*
X701250D01*
X693415Y571329D01*
X680535D01*
X669290Y582574D01*
X635525D01*
X620443Y597656D01*
X117096D01*
X108100Y588660D01*
Y541628D01*
X104606Y538134D01*
Y533101D01*
X97605Y526100D01*
X93502D01*
X93054Y525652D01*
X88404D01*
X78452Y515700D01*
Y514012D01*
X70231Y505791D01*
Y491835D01*
X78270Y483796D01*
Y462473D01*
X72240Y456443D01*
Y453020D01*
X45637Y426417D01*
Y416734D01*
X46100Y416271D01*
G01Y413520D02*
X47676Y415096D01*
Y417082D01*
X46789Y417969D01*
Y425354D01*
X73470Y452035D01*
Y456043D01*
X79422Y461995D01*
Y484274D01*
X70983Y492713D01*
Y505479D01*
X79204Y513700D01*
Y515388D01*
X88716Y524900D01*
X98035D01*
X109252Y536117D01*
Y588182D01*
X117574Y596504D01*
X619965D01*
X635047Y581422D01*
X668812D01*
X680058Y570176D01*
X693892D01*
X701728Y578012D01*
X710736D01*
X715920Y583196D01*
X728045D01*
X741154Y596305D01*
X1291945D01*
X1294029Y594221D01*
Y586000D01*
X1290900Y582871D01*
Y581100D01*
X1294029Y577971D01*
Y563729D01*
X1293600Y563300D01*
Y560300D01*
X1292000Y558700D01*
X1284852D01*
X1280777Y554625D01*
Y549133D01*
X1284831Y545079D01*
X1296793D01*
X1306951Y534921D01*
Y532081D01*
X1317634Y521398D01*
X1330562D01*
X1336789Y527625D01*
X1389777D01*
X1394713Y522689D01*
X1396874D01*
X1403960Y515603D01*
X1410659D01*
X1415362Y510900D01*
X1441717D01*
X1456484Y496133D01*
Y494367D01*
X1461061Y489790D01*
X1461267D01*
G01X629977Y613024D02*
X626397Y616604D01*
X392395D01*
X391395Y617604D01*
X118256D01*
X113396Y612744D01*
Y609243D01*
X104605Y600452D01*
X90411D01*
X83448Y593489D01*
Y539295D01*
X81005Y536852D01*
X74615D01*
X69541Y531778D01*
X46090D01*
X42457Y528145D01*
X16766D01*
X14073Y530838D01*
X7988D01*
X1965Y524815D01*
Y520162D01*
X3354Y518773D01*
Y517143D01*
G01X627705Y611973D02*
Y614069D01*
X626122Y615652D01*
X392000D01*
X391000Y616652D01*
X118651D01*
X114348Y612349D01*
Y608848D01*
X105000Y599500D01*
X90806D01*
X84400Y593094D01*
Y538900D01*
X81400Y535900D01*
X75010D01*
X69936Y530826D01*
X46485D01*
X42894Y527235D01*
X16612D01*
X13961Y529886D01*
X8383D01*
X2887Y524390D01*
Y520882D01*
X6748Y517021D01*
G01X148901Y-50496D02*
X445509D01*
G02Y-53848I0J-1676D01*
G01X147382D01*
X145030Y-56200D01*
X104450D01*
X100500Y-52250D01*
G01X662700Y-17900D02*
Y-18800D01*
X662000Y-19500D01*
X658500D01*
X657500Y-18500D01*
X652000D01*
X650500Y-20000D01*
X648500D01*
X648000Y-20500D01*
X457112D01*
X454988Y-18376D01*
X409425D01*
X406549Y-21252D01*
X98116D01*
X94864Y-18000D01*
X93500D01*
G01X1605004Y-17346D02*
X1603358Y-15700D01*
X1588776D01*
X1587600Y-14524D01*
X1579930D01*
X1574558Y-9152D01*
X1548410D01*
X1546758Y-10804D01*
X1524290D01*
X1524288Y-10806D01*
X1523666D01*
X1523665Y-10805D01*
X1523335D01*
X1523334Y-10806D01*
X1500058D01*
X1499682Y-10430D01*
Y-6882D01*
X1491193Y1607D01*
X1488434D01*
X1486992Y3049D01*
Y7007D01*
X1484257Y9742D01*
X1477454D01*
X1469381Y17815D01*
X1441621D01*
X1430055Y29381D01*
Y37169D01*
X1426224Y41000D01*
X1421600D01*
X1418500Y44100D01*
Y52200D01*
X1419966Y53666D01*
Y73078D01*
X1416861Y76183D01*
Y82301D01*
X1412248Y86914D01*
X1402396D01*
X1401878Y87432D01*
X1399264D01*
X1397897Y88799D01*
X1386325D01*
X1382927Y85401D01*
X1377906D01*
X1372700Y80195D01*
Y73812D01*
X1368212Y69324D01*
Y56841D01*
X1363601Y52230D01*
X1350827D01*
X1330695Y32098D01*
X1325652D01*
X1319374Y25820D01*
X1303019D01*
X1295703Y18504D01*
Y9669D01*
X1290793Y4759D01*
X1283331D01*
X1269209Y-9363D01*
Y-11384D01*
X1265361Y-15232D01*
X735973D01*
X727302Y-6561D01*
Y-5939D01*
X727303Y-5938D01*
Y-1435D01*
X722988Y2880D01*
Y4232D01*
X715419Y11801D01*
X704382D01*
X703033Y10452D01*
X676266D01*
X675023Y11695D01*
X662766D01*
X655160Y4089D01*
Y-11557D01*
X649845Y-16872D01*
X408235D01*
X405359Y-19748D01*
X99252D01*
X95124Y-15620D01*
X92220D01*
X88092Y-19748D01*
X80585D01*
X79495Y-20838D01*
X70374D01*
X68606Y-19070D01*
X65550D01*
X65164Y-19456D01*
G01X87091Y-16391D02*
X90178Y-13304D01*
X96000D01*
X100188Y-17492D01*
X403857D01*
X406733Y-14616D01*
X647777D01*
X652142Y-10251D01*
Y4263D01*
X662279Y14400D01*
X671529D01*
X672681Y15552D01*
X683319D01*
X685147Y13724D01*
X702644D01*
X702977Y14057D01*
X716355D01*
X725644Y4768D01*
Y3982D01*
X730191Y-565D01*
Y-6258D01*
X736502Y-12569D01*
X1019261D01*
X1033955Y2125D01*
X1273087D01*
X1278646Y7684D01*
Y15492D01*
X1284416Y21262D01*
X1291621D01*
X1304335Y33976D01*
X1307237D01*
X1309304Y36043D01*
X1328252D01*
X1334738Y42529D01*
Y71839D01*
X1340431Y77532D01*
Y88290D01*
X1342509Y90368D01*
X1381612D01*
X1383895Y92651D01*
X1397131D01*
X1408082Y103602D01*
Y114717D01*
X1406199Y116600D01*
Y118830D01*
X1405776Y119253D01*
Y119853D01*
X1404853Y120776D01*
X1404253D01*
X1401200Y123829D01*
Y124300D01*
G01X66061Y-13689D02*
X66972Y-12778D01*
X71844D01*
X78062Y-18996D01*
X87780D01*
X91968Y-14808D01*
X95376D01*
X99564Y-18996D01*
X405047D01*
X407923Y-16120D01*
X649533D01*
X654267Y-11386D01*
Y4260D01*
X662455Y12448D01*
X676052D01*
X677296Y11204D01*
X702721D01*
X704070Y12553D01*
X715731D01*
X723740Y4544D01*
Y3192D01*
X728055Y-1123D01*
Y-6250D01*
X736062Y-14257D01*
X1265031D01*
X1265032Y-14258D01*
X1268117Y-11173D01*
Y-5167D01*
X1270003Y-3281D01*
X1273088D01*
X1281880Y5511D01*
X1290481D01*
X1294951Y9981D01*
Y19920D01*
X1301603Y26572D01*
X1319062D01*
X1325340Y32850D01*
X1330383D01*
X1346554Y49021D01*
Y68052D01*
X1348437Y69935D01*
X1367179D01*
X1371740Y74496D01*
Y80511D01*
X1377382Y86153D01*
X1382615D01*
X1386013Y89551D01*
X1398209D01*
X1399576Y88184D01*
X1401605D01*
X1401606Y88183D01*
X1402190D01*
X1402701Y87672D01*
X1412554D01*
X1417613Y82613D01*
Y76495D01*
X1420718Y73390D01*
Y47570D01*
X1430819Y37469D01*
Y29681D01*
X1441933Y18567D01*
X1485539D01*
X1495583Y8523D01*
Y-1383D01*
X1501900Y-7700D01*
Y-9124D01*
G01X1607504Y-17346D02*
X1605058Y-14900D01*
X1589100D01*
X1587800Y-13600D01*
X1580100D01*
X1574900Y-8400D01*
X1548000D01*
X1547600Y-8800D01*
Y-8898D01*
X1546446Y-10052D01*
X1523978D01*
X1523977Y-10053D01*
X1523023D01*
X1523022Y-10052D01*
X1505451D01*
X1496532Y-1133D01*
Y8638D01*
X1485851Y19319D01*
X1442681D01*
X1434294Y27706D01*
Y37624D01*
X1426408Y45510D01*
X1423878D01*
X1421470Y47918D01*
Y73702D01*
X1418365Y76807D01*
Y82301D01*
X1418366Y82302D01*
Y82924D01*
X1412866Y88424D01*
X1403013D01*
X1402501Y88936D01*
X1399888D01*
X1398521Y90303D01*
X1385701D01*
X1382303Y86905D01*
X1376924D01*
X1370879Y80860D01*
Y74907D01*
X1367710Y71738D01*
X1348225D01*
X1345352Y68865D01*
Y53226D01*
X1337775Y45649D01*
Y42306D01*
X1329208Y33739D01*
X1310312D01*
X1305093Y28520D01*
X1302487D01*
X1294199Y20232D01*
Y10293D01*
X1290169Y6263D01*
X1281172D01*
X1272504Y-2405D01*
X1269365D01*
X1267153Y-4617D01*
Y-11072D01*
X1265051Y-13174D01*
X1019720D01*
X1019573Y-13321D01*
X736190D01*
X728807Y-5938D01*
Y-811D01*
X724492Y3504D01*
Y4856D01*
X716043Y13305D01*
X703351D01*
X702361Y12315D01*
X684485D01*
X682000Y14800D01*
X676000D01*
X674400Y13200D01*
X662143D01*
X653294Y4351D01*
Y-11295D01*
X649221Y-15368D01*
X407611D01*
X404735Y-18244D01*
X99876D01*
X95688Y-14056D01*
X91656D01*
X87468Y-18244D01*
X78374D01*
X71348Y-11218D01*
X65331D01*
X63683Y-12866D01*
G01X64159Y11303D02*
X71375D01*
X79776Y19704D01*
X97429D01*
X97656Y19477D01*
X369059D01*
X373245Y15291D01*
X382043D01*
X386456Y19704D01*
X389918D01*
X390545Y19077D01*
X623622D01*
X630372Y25827D01*
Y34895D01*
X634226Y38749D01*
X646417D01*
X654016Y31150D01*
G01X67564Y-20745D02*
X68452Y-21633D01*
X79891D01*
X81024Y-20500D01*
X88404D01*
X92502Y-16402D01*
X94842D01*
X98940Y-20500D01*
X406237D01*
X409113Y-17624D01*
X650723D01*
X659000Y-9347D01*
Y2199D01*
X663093Y6292D01*
X675267D01*
X678675Y9700D01*
X703345D01*
X704694Y11049D01*
X714664D01*
X721300Y4413D01*
Y2938D01*
X726151Y-1913D01*
Y-6381D01*
X726549Y-6779D01*
Y-6872D01*
X735661Y-15984D01*
X1265673D01*
X1269961Y-11696D01*
Y-9675D01*
X1283643Y4007D01*
X1290481D01*
X1290482Y4006D01*
X1291104D01*
X1296455Y9357D01*
Y17533D01*
X1303990Y25068D01*
X1319686D01*
X1325964Y31346D01*
X1331007D01*
X1351139Y51478D01*
X1364122D01*
X1369260Y56616D01*
Y68731D01*
X1373870Y73341D01*
Y80223D01*
X1378296Y84649D01*
X1383239D01*
X1386637Y88047D01*
X1397585D01*
X1398952Y86680D01*
X1401425D01*
X1402082Y86023D01*
X1411727D01*
X1416059Y81691D01*
Y75581D01*
X1419029Y72611D01*
Y54037D01*
X1415200Y50208D01*
Y44300D01*
X1419392Y40108D01*
X1426052D01*
X1428898Y37262D01*
Y36096D01*
X1428897Y36095D01*
Y29195D01*
X1436683Y21409D01*
X1436963D01*
X1441309Y17063D01*
X1468399D01*
X1469019Y16443D01*
X1469077D01*
X1476530Y8990D01*
X1480841D01*
X1485242Y4589D01*
G01X107700Y211040D02*
X107850D01*
X109810Y213000D01*
Y218286D01*
X111400Y219876D01*
Y233654D01*
X110450Y234604D01*
Y243356D01*
X112705Y245611D01*
Y262246D01*
X107706Y267245D01*
Y290403D01*
X106150Y291959D01*
Y305850D01*
X103500Y308500D01*
G01X102322Y295478D02*
Y294378D01*
X106710Y289990D01*
Y266832D01*
X111953Y261589D01*
Y246175D01*
X109590Y243812D01*
Y234148D01*
X110470Y233268D01*
Y220262D01*
X108880Y218672D01*
Y214780D01*
X105147Y211047D01*
X102507D01*
G01X1414107Y447267D02*
X1409687D01*
X1405965Y450989D01*
X1401845D01*
X1400000Y452834D01*
Y459100D01*
X1399420Y459680D01*
X1391470D01*
X1385630Y465520D01*
X1371442D01*
X1367860Y469102D01*
X1341547D01*
X1327385Y483264D01*
X1295263D01*
X1292673Y485854D01*
X1279945D01*
X1273666Y492133D01*
X1265846D01*
X1259921Y498058D01*
X1220958D01*
X1206576Y483676D01*
X1042220D01*
X1038548Y487348D01*
X963070D01*
X960196Y484474D01*
X881646D01*
X875908Y490212D01*
X737976D01*
X733988Y494200D01*
X713783D01*
X707964Y488381D01*
X688494D01*
X679227Y497648D01*
X657077D01*
X654417Y494988D01*
X653774D01*
X653338Y494552D01*
X642854D01*
X635390Y502016D01*
X600672D01*
X580674Y482018D01*
X133416D01*
X102790Y451392D01*
X95588D01*
X72536Y428340D01*
Y394597D01*
X66506Y388567D01*
X61078D01*
X51836Y379325D01*
Y361723D01*
X54561Y358998D01*
Y342368D01*
X56300Y340629D01*
Y338500D01*
G01X1345700Y285300D02*
Y286000D01*
X1337855Y293845D01*
X1333701D01*
X1326837Y300709D01*
Y337432D01*
X1327668Y338263D01*
Y338770D01*
X1328198Y339300D01*
Y340291D01*
X1328000Y340489D01*
Y347000D01*
X1329300Y348300D01*
X1333400D01*
X1334900Y349800D01*
Y360378D01*
X1340156Y365634D01*
Y369011D01*
X1342325Y371180D01*
Y392376D01*
X1340185Y394516D01*
Y411189D01*
X1352820Y423824D01*
Y463698D01*
X1348940Y467578D01*
X1340943D01*
X1326761Y481760D01*
X1294639D01*
X1292049Y484350D01*
X1279321D01*
X1273057Y490614D01*
X1264885D01*
X1258945Y496554D01*
X1222794D01*
X1208334Y482094D01*
X1040222D01*
X1036929Y485387D01*
X964170D01*
X961753Y482970D01*
X877580D01*
X871842Y488708D01*
X736856D01*
X732880Y492684D01*
X715538D01*
X709621Y486767D01*
X686837D01*
X678260Y495344D01*
X658033D01*
X655373Y492684D01*
X654730D01*
X652118Y490072D01*
X645206D01*
X634766Y500512D01*
X601296D01*
X580898Y480114D01*
X580870D01*
X580470Y479714D01*
X134372D01*
X103746Y449088D01*
X96544D01*
X74040Y426584D01*
Y392841D01*
X67462Y386263D01*
X62034D01*
X53900Y378129D01*
Y362919D01*
X57089Y359730D01*
Y349882D01*
X63322Y343649D01*
X77021D01*
X82366Y338304D01*
X86296D01*
X87400Y337200D01*
G01X124340Y197750D02*
Y199020D01*
X110740Y212620D01*
Y217900D01*
X112330Y219490D01*
Y234040D01*
X111280Y235090D01*
Y242870D01*
X113510Y245100D01*
Y262580D01*
X108511Y267579D01*
Y290737D01*
X107043Y292205D01*
Y326347D01*
X103200Y330190D01*
G01X68418Y336150D02*
X67400Y337168D01*
Y339529D01*
X65529Y341400D01*
X63941D01*
X55873Y349468D01*
Y359316D01*
X52988Y362201D01*
Y378847D01*
X61556Y387415D01*
X66984D01*
X73288Y393719D01*
Y427462D01*
X96066Y450240D01*
X103268D01*
X133894Y480866D01*
X580586D01*
X600984Y501264D01*
X635078D01*
X645518Y490824D01*
X651240D01*
X654252Y493836D01*
X654895D01*
X657555Y496496D01*
X678749D01*
X687726Y487519D01*
X708732D01*
X714649Y493436D01*
X733650D01*
X737626Y489460D01*
X875596D01*
X881334Y483722D01*
X960508D01*
X963325Y486539D01*
X1037407D01*
X1041046Y482900D01*
X1207510D01*
X1221916Y497306D01*
X1259609D01*
X1265534Y491381D01*
X1273354D01*
X1279633Y485102D01*
X1292361D01*
X1294951Y482512D01*
X1327073D01*
X1341255Y468330D01*
X1357708D01*
X1362560Y463478D01*
G01X1299450Y484950D02*
X1294641D01*
X1292985Y486606D01*
X1280465D01*
X1274119Y492952D01*
X1266569D01*
X1264466Y495055D01*
Y498315D01*
X1262148Y500633D01*
X1220250D01*
X1205720Y486103D01*
X1043177D01*
X1039628Y489652D01*
X961362D01*
X959220Y487510D01*
X883290D01*
X876412Y494388D01*
X755072D01*
X752956Y496504D01*
X711420D01*
X710100Y497824D01*
X700126D01*
X698925Y499025D01*
X695725D01*
X691700Y495000D01*
Y490500D01*
X690733Y489533D01*
X688972D01*
X679705Y498800D01*
X652591D01*
X649495Y495704D01*
X642766D01*
X635702Y502768D01*
X600360D01*
X580762Y483170D01*
X133129D01*
X102650Y452691D01*
X95011D01*
X71784Y429464D01*
Y402255D01*
X68650Y399121D01*
X62392D01*
X50138Y386867D01*
Y370178D01*
X46394Y366434D01*
Y356458D01*
X48352Y354500D01*
X49100D01*
G01X85609Y385234D02*
Y390243D01*
X91836Y396470D01*
Y429765D01*
X98787Y436716D01*
X114756D01*
X156240Y478200D01*
X581126D01*
X599902Y496976D01*
X613407D01*
X615420Y498989D01*
X634297D01*
X644622Y488664D01*
X652702D01*
X655314Y491276D01*
X656177D01*
X658837Y493936D01*
X677676D01*
X686253Y485359D01*
X710205D01*
X716122Y491276D01*
X732254D01*
X736230Y487300D01*
X871258D01*
X876997Y481561D01*
X878163D01*
X878164Y481562D01*
X962337D01*
X964754Y483979D01*
X1036345D01*
X1039664Y480660D01*
X1208892D01*
X1223232Y495000D01*
X1258507D01*
X1264345Y489162D01*
X1272517D01*
X1285451Y476228D01*
X1301240D01*
G01X54662Y416478D02*
X55400Y417216D01*
Y427699D01*
X78397Y450696D01*
Y454633D01*
X82228Y458464D01*
Y498260D01*
X84140Y500172D01*
Y507730D01*
X82228Y509642D01*
Y514128D01*
X88700Y520600D01*
X90250D01*
X91650Y522000D01*
G01X51645Y416281D02*
X54448Y419084D01*
Y428094D01*
X77252Y450898D01*
Y454939D01*
X81276Y458963D01*
Y498655D01*
X83188Y500567D01*
Y507335D01*
X81276Y509247D01*
Y514780D01*
X88855Y522359D01*
G01X702100Y568800D02*
X701200Y569700D01*
X697900D01*
X694608Y566408D01*
X656792D01*
X652352Y570848D01*
X648652D01*
X641100Y578400D01*
X622722D01*
X621122Y580000D01*
X387501D01*
X381649Y574148D01*
X372353D01*
X367501Y579000D01*
X113800D01*
X111356Y576556D01*
Y535177D01*
X98927Y522748D01*
X92398D01*
X91650Y522000D01*
G01X702000Y571400D02*
X701252Y570652D01*
X697505D01*
X694213Y567360D01*
X657187D01*
X652747Y571800D01*
X649047D01*
X641494Y579353D01*
X640706D01*
X640705Y579352D01*
X623117D01*
X621516Y580953D01*
X620728D01*
X620727Y580952D01*
X387106D01*
X381254Y575100D01*
X372748D01*
X367896Y579952D01*
X113405D01*
X110404Y576951D01*
Y535572D01*
X98532Y523700D01*
X90196D01*
X88855Y522359D01*
G01X92326Y480398D02*
X93672Y479052D01*
X96252D01*
X102674Y485474D01*
X580938D01*
X599736Y504272D01*
X636326D01*
X642590Y498008D01*
X648539D01*
X651635Y501104D01*
X660570D01*
X666448Y506982D01*
X685818D01*
X689600Y503200D01*
Y499600D01*
X691000Y498200D01*
G01X688202Y497736D02*
X688500Y498034D01*
Y502800D01*
X685470Y505830D01*
X666926D01*
X661048Y499952D01*
X652113D01*
X649017Y496856D01*
X642678D01*
X636014Y503520D01*
X600048D01*
X581050Y484522D01*
X103069D01*
X96647Y478100D01*
X90598D01*
X89497Y479201D01*
G01X623600Y521700D02*
X618000Y527300D01*
Y538200D01*
X614555Y541645D01*
X385137D01*
X378682Y548100D01*
X374892D01*
X368574Y541782D01*
X145875D01*
X144300Y540207D01*
Y528000D01*
X138671Y522371D01*
X118948D01*
X98697Y502120D01*
X87390D01*
X86100Y503410D01*
Y505200D01*
G01X91952Y620900D02*
X98100D01*
X102891Y616109D01*
X114719D01*
X117366Y618756D01*
X392133D01*
X393133Y617756D01*
X642348D01*
X648604Y611500D01*
X655100D01*
G01X623000Y-3000D02*
X619196Y804D01*
X116696D01*
X114000Y3500D01*
G01X624770Y-640D02*
X622106Y2024D01*
X118196D01*
X114100Y6120D01*
G01X680300Y485700D02*
Y484500D01*
X667160Y471360D01*
X646170D01*
X635255Y482275D01*
Y486593D01*
X627671Y494177D01*
X618202D01*
X615957Y491932D01*
X602139D01*
X582121Y471914D01*
X208221D01*
X151680Y415373D01*
X151594D01*
X150671Y414450D01*
Y414364D01*
X149204Y412897D01*
X145303D01*
X143700Y414500D01*
Y420000D01*
X145939Y422239D01*
X148409D01*
G01X148300Y414600D02*
X147500D01*
X146700Y415400D01*
Y418000D01*
X147961Y419261D01*
X149564D01*
X153034Y422731D01*
X154025D01*
X207524Y476230D01*
X581623D01*
X600961Y495568D01*
X613991D01*
X616004Y497581D01*
X629083D01*
X629104Y497560D01*
X629105D01*
X630101Y496564D01*
Y496563D01*
X638868Y487796D01*
Y483576D01*
X647284Y475160D01*
X665585D01*
X675080Y484655D01*
Y485570D01*
G01X148666Y417397D02*
X148930D01*
X149195Y417132D01*
X150833D01*
X207351Y473650D01*
X581450D01*
X601666Y493866D01*
X615386D01*
X617378Y495858D01*
X617475D01*
X617496Y495879D01*
X628376D01*
X628397Y495858D01*
X628399D01*
X637166Y487091D01*
Y482871D01*
X646580Y473457D01*
X647988D01*
X647989Y473458D01*
X666290D01*
X677800Y484968D01*
Y485600D01*
G01X628589Y463649D02*
X626521Y465717D01*
Y476005D01*
X623481Y479045D01*
Y484450D01*
X622445Y485486D01*
X617662D01*
X617660Y485484D01*
X617038D01*
X617037Y485485D01*
X616415D01*
X616400Y485500D01*
X616024D01*
X615008Y486516D01*
X609337D01*
X607708Y484887D01*
Y480005D01*
X604052Y476349D01*
Y470330D01*
X577145Y443423D01*
Y363371D01*
X570061Y356287D01*
Y340243D01*
X564589Y334771D01*
G01X564189Y335521D02*
X569248Y340580D01*
Y356624D01*
X576332Y363708D01*
Y443760D01*
X603239Y470667D01*
Y476600D01*
X606938Y480299D01*
Y485181D01*
X609025Y487268D01*
X615696D01*
X616726Y486238D01*
X626691D01*
X630276Y482653D01*
Y477353D01*
X627283Y474360D01*
Y468412D01*
X628057Y467638D01*
X634033D01*
G01X563603Y343321D02*
X565298Y345016D01*
Y358262D01*
X572382Y365346D01*
Y445398D01*
X599289Y472305D01*
Y485875D01*
X603494Y490080D01*
X617082D01*
X618667Y488495D01*
X627626D01*
X633403Y482718D01*
Y479108D01*
X640522Y471989D01*
X641107D01*
G01X605176Y487581D02*
X601154Y483559D01*
Y471532D01*
X574247Y444625D01*
Y364573D01*
X567163Y357489D01*
Y341901D01*
X564685Y339423D01*
X563624D01*
G01X632771Y473269D02*
X632651Y473389D01*
Y482406D01*
X627314Y487743D01*
X625698D01*
X625697Y487742D01*
X618270D01*
X616684Y489328D01*
X603806D01*
X600102Y485624D01*
Y471968D01*
X573195Y445061D01*
Y365009D01*
X566111Y357925D01*
Y344679D01*
X564003Y342571D01*
G01X629359Y469583D02*
X631028Y471252D01*
Y482965D01*
X627003Y486990D01*
X617038D01*
X616008Y488020D01*
X608163D01*
X605277Y485134D01*
X604820D01*
X601906Y482220D01*
Y471220D01*
X574999Y444313D01*
Y364261D01*
X567915Y357177D01*
Y341589D01*
X564997Y338671D01*
X563624D01*
G01X498072Y264947D02*
Y264155D01*
X494881Y260964D01*
X494339D01*
X492445Y259070D01*
Y252759D01*
X486922Y247236D01*
X485978D01*
X484072Y245330D01*
X482713D01*
X480543Y243160D01*
X479124D01*
X477299Y241335D01*
X475616D01*
X473771Y239490D01*
X472914D01*
X471722Y238298D01*
Y208478D01*
X483066Y197134D01*
Y157182D01*
X507428Y132820D01*
X582049D01*
X584349Y130520D01*
X584419D01*
X599581Y115358D01*
Y115288D01*
X601777Y113092D01*
X606595D01*
X617910Y101777D01*
X619352D01*
X626751Y94378D01*
Y81380D01*
X630931Y77200D01*
X663237D01*
X667027Y73410D01*
X684872D01*
X687940Y76478D01*
X693340D01*
X694448Y75370D01*
X702672D01*
X710342Y67700D01*
X713969D01*
X716535Y65134D01*
Y63402D01*
X724225Y55712D01*
X726749D01*
X730680Y51781D01*
Y51772D01*
X730839Y51613D01*
Y47672D01*
X739568Y38943D01*
X746700D01*
X753819Y31824D01*
X759330D01*
X767647Y23507D01*
X1019123D01*
X1029691Y34075D01*
X1031459D01*
X1035988Y38604D01*
X1039528D01*
X1040614Y37518D01*
X1049907D01*
X1050386Y37997D01*
X1272456D01*
X1279301Y44842D01*
Y52330D01*
X1287086Y60115D01*
X1290851D01*
X1296846Y66110D01*
Y89088D01*
X1302270Y94512D01*
Y98571D01*
X1306354Y102655D01*
Y131198D01*
X1306900Y131744D01*
G01X626040Y98281D02*
Y100643D01*
X615745Y110938D01*
X610741D01*
X607179Y114500D01*
X602568D01*
X582840Y134228D01*
X508012D01*
X485135Y157105D01*
Y197235D01*
X475102Y207268D01*
Y236276D01*
X476643Y237817D01*
X477703D01*
X479437Y239551D01*
X480786D01*
X482797Y241562D01*
X484281D01*
X485836Y243117D01*
X488494D01*
X490767Y245390D01*
X495548D01*
X497175Y247017D01*
X498518D01*
X500751Y249250D01*
X502150D01*
X504577Y251677D01*
X506290D01*
X506642Y252029D01*
Y254009D01*
X510401Y257768D01*
Y260511D01*
G01X618800Y100100D02*
X617816D01*
X609892Y108024D01*
X600776D01*
X598329Y110471D01*
Y114839D01*
X581688Y131480D01*
X505516D01*
X481766Y155230D01*
Y196480D01*
X468342Y209904D01*
Y240246D01*
X469715Y241619D01*
X470688D01*
X472371Y243302D01*
X473892D01*
X475940Y245350D01*
X477400D01*
X479346Y247296D01*
X480380D01*
X482205Y249121D01*
X483806D01*
X485855Y251170D01*
X486956D01*
X489668Y253882D01*
Y260457D01*
X493100Y263889D01*
Y273104D01*
X494692Y274696D01*
G01X1301384Y618119D02*
X1298011Y621492D01*
X1103610D01*
X1101518Y619400D01*
X1041600D01*
X1040437Y620563D01*
X739555D01*
X733992Y615000D01*
X723500D01*
X717734Y609234D01*
Y604619D01*
X713971Y600856D01*
Y596742D01*
X711949Y594720D01*
X702224D01*
X694756Y587252D01*
X660653D01*
X647658Y600247D01*
X629638D01*
X627079Y602806D01*
X429630D01*
X421454Y610982D01*
Y612560D01*
G01X1281799Y193190D02*
Y186032D01*
X1284992Y182839D01*
X1290258D01*
X1301956Y171141D01*
Y162005D01*
X1302816Y161145D01*
Y153578D01*
X1301492Y152254D01*
Y131293D01*
X1297157Y126958D01*
Y110657D01*
X1294300Y107800D01*
Y101757D01*
X1297157Y98900D01*
Y92941D01*
X1294170Y89954D01*
Y66976D01*
X1289813Y62619D01*
X1286036D01*
X1276797Y53380D01*
Y45944D01*
X1271355Y40502D01*
X1042495D01*
X1041731Y41266D01*
X1035108D01*
X1030421Y36579D01*
X1028653D01*
X1018397Y26323D01*
X768373D01*
X760368Y34328D01*
X755024D01*
X747905Y41447D01*
X740606D01*
X733343Y48710D01*
Y52660D01*
X727619Y58384D01*
X725095D01*
X719039Y64440D01*
Y66172D01*
X715007Y70204D01*
X711381D01*
X703661Y77924D01*
X696547D01*
X695489Y78982D01*
X688868D01*
X681296Y86554D01*
X671695D01*
X665157Y80016D01*
X632613D01*
X629567Y83062D01*
Y99108D01*
X616329Y112346D01*
X611325D01*
X607764Y115907D01*
X603261D01*
X583488Y135680D01*
X508676D01*
X486543Y157813D01*
Y197757D01*
X479423Y204877D01*
X479401D01*
X478482Y205796D01*
Y234397D01*
X479725Y235640D01*
X480683D01*
X482680Y237637D01*
X484139D01*
X486066Y239564D01*
X487810D01*
X489986Y241740D01*
X495791D01*
X497168Y243117D01*
X499119D01*
X500526Y241710D01*
X502655D01*
X504267Y243322D01*
X505606D01*
X507941Y245657D01*
X509581D01*
X510941Y247017D01*
X511483D01*
X513393Y248927D01*
Y255912D01*
X514981Y257500D01*
X516000D01*
X517900Y259400D01*
X519500D01*
X520000Y259900D01*
Y271099D01*
X518352Y272747D01*
G01X1300300Y169900D02*
X1297676Y167276D01*
Y149676D01*
X1293100Y145100D01*
Y127900D01*
X1291700Y126500D01*
Y104811D01*
X1278033Y91144D01*
Y59910D01*
X1275482Y57359D01*
Y49748D01*
X1275483Y49747D01*
Y46559D01*
X1270261Y41337D01*
X1042724D01*
X1042015Y42046D01*
X1034058D01*
X1029793Y37781D01*
X763719D01*
X758672Y42828D01*
X740860D01*
X734790Y48898D01*
Y52801D01*
X727801Y59790D01*
X725424D01*
X720290Y64924D01*
Y66957D01*
X715347Y71900D01*
X711506D01*
X702154Y81252D01*
X689134D01*
X682490Y87896D01*
X671731D01*
X671448Y87613D01*
X670664D01*
X664326Y81275D01*
X633294D01*
X631073Y83496D01*
Y99951D01*
X616981Y114043D01*
X611856D01*
X608499Y117400D01*
X603801D01*
X583936Y137265D01*
X509155D01*
X488151Y158269D01*
Y209464D01*
X488382Y209695D01*
Y231812D01*
X494255Y237685D01*
X495305D01*
X496837Y239217D01*
X499247D01*
X500438Y238026D01*
X502642D01*
X504126Y239510D01*
X505606D01*
X507695Y241599D01*
X508871D01*
X511000Y243728D01*
X512825D01*
X514407Y245310D01*
X515107D01*
X516678Y246881D01*
Y253794D01*
X518089Y255205D01*
X518631D01*
X520426Y257000D01*
X522200D01*
X523477Y258277D01*
Y270123D01*
X524160Y270806D01*
Y271796D01*
X525111Y272747D01*
G01X1220702Y216708D02*
X1220524Y216530D01*
X1218308D01*
X1217298Y215520D01*
Y206773D01*
X1244797Y179274D01*
X1259805D01*
X1272976Y166103D01*
Y154355D01*
X1257099Y138478D01*
X1247686D01*
X1241695Y132487D01*
Y128798D01*
X1210568Y97671D01*
X1098051D01*
X1083090Y112632D01*
X1049089D01*
X1039330Y102873D01*
X1037420D01*
X1037419Y102874D01*
X1034485D01*
X1029341Y97730D01*
Y82445D01*
X1026891Y79995D01*
X1022872D01*
X1020586Y77709D01*
Y73712D01*
X1009184Y62310D01*
X773472D01*
X771457Y64325D01*
Y66653D01*
X770534Y67576D01*
X767398D01*
X761154Y73820D01*
Y76534D01*
X757594Y80094D01*
Y84749D01*
X747039Y95304D01*
X741547D01*
X737667Y91424D01*
Y88526D01*
X735745Y86604D01*
X720439D01*
X718996Y88047D01*
Y89814D01*
X710310Y98500D01*
X647431D01*
X624519Y121412D01*
X602188D01*
X585089Y138511D01*
X509539D01*
X489303Y158747D01*
Y229282D01*
X493551Y233530D01*
X495130D01*
X496500Y234900D01*
G01X499802Y234397D02*
X500073Y234126D01*
X502626D01*
X503815Y235315D01*
G01X505985D02*
X507174Y234126D01*
X509526D01*
X510716Y235316D01*
G01X510941D02*
X512883D01*
X514073Y234126D01*
X515927D01*
X517117Y235316D01*
X519003D01*
X520193Y234126D01*
X522626D01*
X524000Y235500D01*
X525185D01*
X526681Y236996D01*
Y247777D01*
X525111Y249347D01*
G01X514972Y243496D02*
X519000D01*
X520100Y244596D01*
Y252100D01*
X521200Y253200D01*
X522600D01*
G01X533057Y239293D02*
X534350Y238000D01*
X535440D01*
X538100Y235340D01*
X539630D01*
X541250Y233720D01*
X542750D01*
X544488Y231982D01*
X545718D01*
X547100Y230600D01*
G01X561200Y229600D02*
X565900D01*
X569181Y226319D01*
X583519D01*
X595900Y238700D01*
X622700D01*
X624500Y240500D01*
G01X609470Y484060D02*
Y483530D01*
X610970Y482030D01*
Y479240D01*
X609550Y477820D01*
Y475350D01*
X610498Y474402D01*
Y461423D01*
X604762Y449072D01*
X589841Y398265D01*
X587209Y393500D01*
X569652Y327603D01*
X562163Y323177D01*
G01X570596Y326728D02*
X570766Y327307D01*
X588286Y393067D01*
X590743Y397513D01*
X590851Y397612D01*
X605844Y448663D01*
X611650Y461167D01*
Y474880D01*
X611021Y475509D01*
Y476521D01*
X611250Y476750D01*
G01X651235Y249165D02*
X647970Y245900D01*
X633600D01*
X625200Y237500D01*
X595776D01*
X583787Y225511D01*
X566367D01*
X564703Y226200D01*
X561100D01*
G01X547421Y229471D02*
X546123Y228173D01*
X544491D01*
X543519Y229145D01*
X540285Y230485D01*
X539084Y231686D01*
X537189Y232471D01*
X536451Y233209D01*
X534300Y234100D01*
X533263Y235137D01*
X532877Y235297D01*
X532809Y235365D01*
X531434D01*
G01X523400Y250300D02*
Y245165D01*
X521731Y243496D01*
G01X1241381Y172040D02*
X1238549D01*
X1193872Y127363D01*
X1040237D01*
X1033638Y120764D01*
X1027527D01*
X1022563Y115800D01*
X955781D01*
X952682Y118899D01*
X880136D01*
X873413Y112176D01*
X640624D01*
X633800Y119000D01*
G01X609482Y124568D02*
X630744D01*
X642184Y113128D01*
X873301D01*
X879824Y119651D01*
X952994D01*
X956093Y116552D01*
X1021707D01*
X1026868Y121713D01*
X1033059D01*
X1039461Y128115D01*
X1193018D01*
X1242413Y177510D01*
X1245540D01*
X1246655Y176395D01*
G01X621165Y256075D02*
X624272Y259182D01*
Y270631D01*
X639621Y285980D01*
X639622Y285983D01*
Y290210D01*
G01X643823Y289650D02*
X641135Y286962D01*
Y285864D01*
X625500Y270229D01*
Y258066D01*
X620850Y253416D01*
G01X648025Y501575D02*
X649287D01*
X651212Y503500D01*
X659706D01*
X672505Y516299D01*
X689048D01*
X694848Y510499D01*
X695241D01*
X695242Y510500D01*
X719727D01*
X720565Y511338D01*
G01X721414Y508986D02*
X720852Y509548D01*
X695637D01*
X695636Y509547D01*
X694453D01*
X688653Y515347D01*
X673183D01*
X660092Y502256D01*
X651157D01*
X648619Y499718D01*
X646218D01*
X646200Y499700D01*
G01X1460661Y484891D02*
X1458950Y486602D01*
Y490837D01*
X1454628Y495159D01*
Y495773D01*
X1441451Y508950D01*
X1416248D01*
X1410347Y514851D01*
X1403470D01*
X1400177Y518144D01*
X1394614D01*
X1388829Y512359D01*
X1372191D01*
X1370550Y514000D01*
X1354057D01*
X1349289Y509232D01*
Y500431D01*
X1345564Y496706D01*
X1343715D01*
X1342851Y497570D01*
Y499678D01*
X1340122Y502407D01*
X1332602D01*
X1329283Y505726D01*
Y512474D01*
X1321903Y519854D01*
X1317050D01*
X1305447Y531457D01*
Y534297D01*
X1297568Y542176D01*
X1284712D01*
X1282784Y540248D01*
X1279568D01*
X1274664Y545152D01*
X1034048D01*
X1028618Y550582D01*
X1024311D01*
X1019277Y545548D01*
X760479D01*
X746760Y559267D01*
X744132D01*
X743103Y560296D01*
X658413D01*
X656033Y557916D01*
X651809D01*
X648653Y554760D01*
Y537130D01*
X646880Y535357D01*
Y524566D01*
X653714Y517732D01*
X689245D01*
X692118Y514859D01*
X713067D01*
X715009Y512917D01*
G01X655100Y614100D02*
X656676Y612524D01*
Y598089D01*
X662441Y592324D01*
X695957D01*
X707800Y604167D01*
Y607267D01*
X717516Y616983D01*
X732983D01*
X738867Y622867D01*
X1041133D01*
X1042500Y621500D01*
X1100358D01*
X1102254Y623396D01*
X1301104D01*
X1307076Y617424D01*
X1372872D01*
X1373596Y618148D01*
X1380905D01*
X1391176Y607877D01*
Y604528D01*
X1400704Y595000D01*
X1409001D01*
X1411376Y592625D01*
X1426863D01*
X1437824Y603586D01*
Y607141D01*
X1449128Y618445D01*
X1462145D01*
X1466598Y622898D01*
X1544932D01*
X1551630Y616200D01*
X1568800D01*
X1572448Y612552D01*
X1587581D01*
X1588933Y613904D01*
X1603470D01*
X1607914Y609460D01*
X1607925Y609458D01*
X1616460D01*
X1625976Y618974D01*
X1660555D01*
X1668182Y611347D01*
Y598882D01*
X1668152Y598852D01*
Y596872D01*
X1674424Y590600D01*
X1689187D01*
X1693197Y586590D01*
X1699088D01*
X1714110Y571568D01*
Y571330D01*
X1714111Y571329D01*
Y570375D01*
X1714110Y570374D01*
Y564418D01*
X1703846Y554154D01*
X1696910D01*
X1688379Y545623D01*
X1682471D01*
X1677281Y540433D01*
X1667722D01*
X1644297Y517008D01*
Y513605D01*
X1643047Y512355D01*
Y507979D01*
X1643084Y507942D01*
Y506162D01*
X1643075Y506153D01*
Y504847D01*
X1643084Y504838D01*
Y500705D01*
X1639113Y496734D01*
G01X701100Y8100D02*
X702600Y6600D01*
X705029D01*
X708100Y3529D01*
Y-4800D01*
X713700Y-10400D01*
Y-13552D01*
X721042Y-20894D01*
X1267756D01*
X1276346Y-12304D01*
Y-10250D01*
G01X1287700Y-16700D02*
X1286900Y-17500D01*
X1274208D01*
X1270062Y-21646D01*
X720730D01*
X712948Y-13864D01*
Y-10712D01*
X707300Y-5064D01*
Y2100D01*
X704450Y4950D01*
G01X1496660Y-10252D02*
X1496606D01*
Y-10206D01*
X1496600D01*
Y-10200D01*
X1490600D01*
X1487200Y-6800D01*
Y-3730D01*
X1467815Y15655D01*
X1440445D01*
X1427489Y28611D01*
Y36679D01*
X1425468Y38700D01*
X1419976D01*
X1419975Y38699D01*
X1418809D01*
X1413792Y43716D01*
Y50792D01*
X1417341Y54341D01*
Y72300D01*
X1414760Y74881D01*
Y74888D01*
X1414651Y74997D01*
Y81107D01*
X1410486Y85272D01*
X1398368D01*
X1397001Y86639D01*
X1387467D01*
X1381500Y80672D01*
Y76429D01*
X1375278Y70207D01*
Y60642D01*
X1364706Y50070D01*
X1351723D01*
X1331591Y29938D01*
X1326548D01*
X1320270Y23660D01*
X1304574D01*
X1297863Y16949D01*
Y8773D01*
X1291565Y2475D01*
X1284103D01*
X1271369Y-10259D01*
Y-12280D01*
X1266257Y-17392D01*
X736133D01*
X735605Y-17920D01*
X724384D01*
X722051Y-15587D01*
Y-13922D01*
X722898Y-13075D01*
Y-2074D01*
X720592Y232D01*
X712988D01*
X711310Y1910D01*
Y6590D01*
X710800Y7100D01*
G01X1303774Y-18842D02*
Y-16420D01*
X1298711Y-11357D01*
X1292280D01*
X1290895Y-12742D01*
X1282880D01*
X1278500Y-8362D01*
X1275444D01*
X1273818Y-9988D01*
Y-12192D01*
X1266556Y-19454D01*
X723724D01*
X720529Y-16259D01*
Y-13518D01*
X718975Y-11964D01*
Y-4451D01*
G01X720572Y88700D02*
X722812Y90940D01*
X732291D01*
X733859Y92508D01*
Y93004D01*
X739967Y99112D01*
X753866D01*
X755599Y97379D01*
X758336D01*
X759181Y98224D01*
X958904D01*
X960772Y100092D01*
X964956D01*
X966109Y101245D01*
X1021436D01*
X1021453Y101252D01*
X1031139Y110938D01*
X1036455D01*
X1045135Y119618D01*
X1200768D01*
X1234435Y153285D01*
X1263185D01*
X1264700Y154800D01*
G01X1267959Y47245D02*
Y51537D01*
X1269804Y53382D01*
Y54981D01*
X1268321Y56464D01*
X1266115D01*
X1265133Y57446D01*
X1047122D01*
X1046280Y58288D01*
X1043579D01*
X1041065Y60802D01*
X1033591D01*
X1032109Y59320D01*
X1030848D01*
X1027554Y56026D01*
Y47888D01*
X1022428Y42762D01*
X767334D01*
X758851Y51245D01*
Y54128D01*
X752131Y60848D01*
X739667D01*
X736512Y64003D01*
Y64927D01*
X735363Y66076D01*
Y70936D01*
X733868Y72431D01*
X729402D01*
X725025Y76808D01*
X713541D01*
X703845Y86504D01*
Y88830D01*
G01X1275577Y253123D02*
Y250999D01*
X1268362Y243784D01*
Y214518D01*
X1275602Y207278D01*
Y200535D01*
X1269799Y194732D01*
Y186047D01*
X1279606Y176240D01*
Y166675D01*
X1281379Y164902D01*
Y144938D01*
X1272286Y135845D01*
X1248314D01*
X1243999Y131530D01*
Y127842D01*
X1211523Y95366D01*
X1207910D01*
X1207909Y95367D01*
X1097095D01*
X1082560Y109902D01*
X1049619D01*
X1040286Y100569D01*
X1036464D01*
X1036463Y100570D01*
X1035441D01*
X1031645Y96774D01*
Y77206D01*
X1019328Y64889D01*
Y64819D01*
X1017731Y63222D01*
X1017661D01*
X1014445Y60006D01*
X771471D01*
X758850Y72627D01*
Y74920D01*
X754670Y79100D01*
X749233D01*
X748473Y79860D01*
X741369D01*
X736929Y84300D01*
X719483D01*
X716268Y87515D01*
Y88683D01*
G01X1277504Y250346D02*
X1277509Y250341D01*
Y247430D01*
X1270729Y240650D01*
Y215411D01*
X1277906Y208234D01*
Y199579D01*
X1272172Y193845D01*
Y186934D01*
X1281910Y177196D01*
Y167991D01*
X1283683Y166218D01*
Y143772D01*
X1280139Y140228D01*
Y132940D01*
X1274605Y127406D01*
Y119399D01*
X1265772Y110566D01*
Y98309D01*
X1266733Y97348D01*
Y90063D01*
X1270184Y86612D01*
Y68497D01*
X1264108Y62421D01*
X1048751D01*
X1048093Y63079D01*
X1046506D01*
X1044909Y64676D01*
Y67142D01*
X1046215Y68448D01*
Y71037D01*
X1043962Y73290D01*
Y74753D01*
X1040255Y78460D01*
X1036159D01*
X1021632Y63933D01*
Y63863D01*
X1018687Y60918D01*
X1018617D01*
X1015401Y57702D01*
X770515D01*
X756546Y71671D01*
Y73884D01*
X753678Y76752D01*
X748321D01*
X747517Y77556D01*
X737483D01*
X735118Y79921D01*
X734164D01*
X734163Y79920D01*
X731838D01*
X728610Y83148D01*
X717793D01*
X716894Y84047D01*
G01X1218868Y214869D02*
X1224227Y209510D01*
Y207146D01*
X1242087Y189286D01*
X1242365D01*
X1243288Y188363D01*
Y188085D01*
X1250947Y180426D01*
X1260283D01*
X1274128Y166581D01*
Y153877D01*
X1257577Y137326D01*
X1248164D01*
X1242847Y132009D01*
Y128320D01*
X1211046Y96519D01*
X1097573D01*
X1082612Y111480D01*
X1049567D01*
X1039808Y101721D01*
X1036942D01*
X1036941Y101722D01*
X1034963D01*
X1030493Y97252D01*
Y77684D01*
X1018176Y65367D01*
Y65297D01*
X1017253Y64374D01*
X1017183D01*
X1013967Y61158D01*
X771949D01*
X760002Y73105D01*
Y75398D01*
X755148Y80252D01*
X749711D01*
X748951Y81012D01*
X741847D01*
X737407Y85452D01*
X719961D01*
X717844Y87569D01*
Y89336D01*
X716921Y90259D01*
X714745D01*
X713115Y88629D01*
G01X1275154Y236296D02*
X1274002Y235144D01*
Y216498D01*
X1280370Y210130D01*
Y198162D01*
X1274862Y192654D01*
Y187538D01*
X1284708Y177692D01*
X1287874D01*
X1291994Y173572D01*
Y164694D01*
X1286200Y158900D01*
Y141967D01*
X1284300Y140067D01*
Y103404D01*
X1274057Y93161D01*
Y61859D01*
X1271600Y59402D01*
Y48150D01*
X1268638Y45188D01*
X1046541D01*
X1045938Y45791D01*
Y55432D01*
X1044406Y56964D01*
X1041854D01*
X1039787Y59031D01*
X1035525D01*
X1029276Y52782D01*
Y47606D01*
X1023280Y41610D01*
X766856D01*
X766756Y41710D01*
X766561D01*
X748575Y59696D01*
X733208D01*
X729525Y63379D01*
Y70678D01*
X724547Y75656D01*
X713063D01*
X703219Y85500D01*
X701500D01*
G01X1279950Y229338D02*
X1276859Y226247D01*
Y217442D01*
X1282974Y211327D01*
Y196979D01*
X1282514Y196519D01*
Y196493D01*
X1277454Y191433D01*
Y188606D01*
X1285664Y180396D01*
X1288829D01*
X1294498Y174727D01*
Y163656D01*
X1293224Y162382D01*
Y157460D01*
X1290159Y154395D01*
Y144889D01*
X1291848Y143200D01*
Y128989D01*
X1290159Y127300D01*
Y105041D01*
X1276781Y91663D01*
Y60429D01*
X1274230Y57878D01*
Y47141D01*
X1269678Y42589D01*
X1043243D01*
X1042534Y43298D01*
X1034090D01*
X1032838Y44550D01*
X1030057D01*
X1024540Y39033D01*
X764367D01*
X759320Y44080D01*
X741411D01*
X736042Y49449D01*
Y52307D01*
X736043Y52308D01*
Y53157D01*
X736042Y53158D01*
Y53320D01*
X727021Y62341D01*
Y69640D01*
X723509Y73152D01*
X712025D01*
X702673Y82504D01*
X697096D01*
X694600Y85000D01*
G01X1276628Y234270D02*
X1275607Y233249D01*
Y216923D01*
X1281722Y210808D01*
Y197498D01*
X1276128Y191904D01*
Y188072D01*
X1285133Y179067D01*
X1288387D01*
X1293246Y174208D01*
Y164175D01*
X1290896Y161825D01*
Y156903D01*
X1288907Y154914D01*
Y144370D01*
X1290596Y142681D01*
Y130589D01*
X1288907Y128900D01*
Y105647D01*
X1275363Y92103D01*
Y61394D01*
X1272852Y58883D01*
Y50777D01*
X1272853Y50776D01*
Y47630D01*
X1269064Y43841D01*
X1044246D01*
X1042312Y45775D01*
Y54720D01*
X1039357Y57675D01*
X1036097D01*
X1031661Y53239D01*
Y48014D01*
X1023932Y40285D01*
X766410D01*
X766237Y40458D01*
X766042D01*
X748056Y58444D01*
X732689D01*
X728273Y62860D01*
Y70159D01*
X724028Y74404D01*
X712544D01*
X703024Y83924D01*
X699676D01*
X698300Y85300D01*
G01X1270350Y98300D02*
X1272721Y95929D01*
Y65272D01*
X1267566Y60117D01*
X1047785D01*
X1047127Y60775D01*
X1044352D01*
X1042021Y63106D01*
X1032635D01*
X1031153Y61624D01*
X1029429D01*
X1024801Y56996D01*
Y48569D01*
X1021298Y45066D01*
X768713D01*
X761434Y52345D01*
Y53849D01*
X761435Y53850D01*
Y54804D01*
X761434Y54805D01*
Y55315D01*
X753564Y63185D01*
X747072D01*
X747039Y63152D01*
X741547D01*
X737667Y67032D01*
Y74112D01*
X734387Y77392D01*
X727701D01*
X724249Y80844D01*
X716238D01*
X715932Y81150D01*
X713058D01*
X709560Y84648D01*
G01X707329Y88955D02*
X708045D01*
X712600Y84400D01*
X714610D01*
X715318Y83692D01*
Y83394D01*
X716716Y81996D01*
X728132D01*
X731360Y78768D01*
X733685D01*
X733686Y78767D01*
X734642D01*
X737005Y76404D01*
X747039D01*
X747844Y75599D01*
X748798D01*
X748799Y75600D01*
X753200D01*
X755394Y73406D01*
Y71193D01*
X770037Y56550D01*
X1015879D01*
X1019095Y59766D01*
X1019165D01*
X1022784Y63385D01*
Y63455D01*
X1036637Y77308D01*
X1038624D01*
X1042164Y73768D01*
Y64593D01*
X1044830Y61927D01*
X1047615D01*
X1048273Y61269D01*
X1264586D01*
X1271376Y68059D01*
Y94504D01*
X1266924Y98956D01*
Y110088D01*
X1282842Y126006D01*
Y140582D01*
X1284835Y142575D01*
Y167159D01*
X1283062Y168932D01*
Y177674D01*
X1273505Y187231D01*
Y193548D01*
X1279058Y199101D01*
Y208712D01*
X1272305Y215465D01*
Y239943D01*
X1272657Y240295D01*
X1272686D01*
X1272761Y240220D01*
G01X1268111Y58040D02*
X1267422D01*
X1266497Y58965D01*
X1047307D01*
X1046649Y59623D01*
X1043874D01*
X1041543Y61954D01*
X1033113D01*
X1031631Y60472D01*
X1030204D01*
X1026402Y56670D01*
Y48366D01*
X1021950Y43914D01*
X768235D01*
X760282Y51867D01*
Y54327D01*
X752609Y62000D01*
X740145D01*
X737664Y64481D01*
Y65405D01*
X736515Y66554D01*
Y71414D01*
X734346Y73583D01*
X729880D01*
X725503Y77960D01*
X714019D01*
X705972Y86007D01*
Y86660D01*
G01X1233902Y173337D02*
Y170770D01*
X1192499Y129367D01*
X1038942D01*
X1032540Y122965D01*
X1026349D01*
X1021188Y117804D01*
X956637D01*
X953464Y120977D01*
X879379D01*
X872782Y114380D01*
X740109D01*
X740073Y114344D01*
X672865D01*
X671325Y115884D01*
X670503D01*
G01X674469Y287375D02*
X675241Y288147D01*
X688924D01*
G01X708700Y499400D02*
X711079Y501779D01*
X714321D01*
X718700Y497400D01*
X733994D01*
X734138Y497256D01*
X753556D01*
X755672Y495140D01*
X877370D01*
X883810Y488700D01*
X958790D01*
X960535Y490445D01*
X1040485D01*
X1043980Y486950D01*
X1204915D01*
X1219350Y501385D01*
X1263465D01*
X1267240Y497610D01*
X1269710D01*
X1270716Y496604D01*
X1273488D01*
X1276121Y499237D01*
X1282032D01*
X1289703Y491566D01*
X1295043D01*
X1295709Y490900D01*
X1314627D01*
X1316381Y489146D01*
X1350706D01*
X1356849Y495289D01*
Y500196D01*
X1360237Y503584D01*
X1379252D01*
X1380667Y504999D01*
X1390917D01*
X1397367Y498549D01*
X1441175D01*
X1447328Y492396D01*
Y487440D01*
X1446101Y486213D01*
Y482301D01*
X1452602Y475800D01*
X1459000D01*
X1470664Y464136D01*
Y456470D01*
X1476097Y451037D01*
Y404787D01*
X1471910Y400600D01*
X1458550D01*
X1452940Y394990D01*
Y367399D01*
X1444876Y359335D01*
Y355858D01*
X1439350Y350332D01*
Y319650D01*
X1441000Y318000D01*
Y317280D01*
X1440910Y317190D01*
Y316693D01*
G01X720565Y511338D02*
X721243Y510660D01*
X721741D01*
X730185Y519104D01*
X734179D01*
X740607Y525532D01*
X746242D01*
X750919Y530209D01*
Y540525D01*
X754790Y544396D01*
X1020085D01*
X1022165Y546476D01*
X1022166D01*
X1025120Y549430D01*
X1027781D01*
X1033211Y544000D01*
X1268400D01*
X1274700Y537700D01*
Y534508D01*
X1283551Y525657D01*
X1299315D01*
X1305645Y519327D01*
Y515126D01*
X1309966Y510805D01*
X1318895D01*
X1333746Y495954D01*
X1346288D01*
X1350041Y499707D01*
Y508919D01*
X1354240Y513118D01*
X1370029D01*
X1371540Y511607D01*
X1389141D01*
X1394927Y517392D01*
X1399218D01*
X1402511Y514099D01*
X1403400D01*
X1405178Y512321D01*
Y511422D01*
X1405950Y510650D01*
G01X721414Y508986D02*
X730580Y518152D01*
X734574D01*
X741002Y524580D01*
X746637D01*
X751871Y529814D01*
Y540130D01*
X755185Y543444D01*
X1020480D01*
X1022560Y545524D01*
X1022561D01*
X1025515Y548478D01*
X1027386D01*
X1032816Y543048D01*
X1267952D01*
X1273748Y537252D01*
Y534113D01*
X1283156Y524705D01*
X1298920D01*
X1304693Y518932D01*
Y514731D01*
X1309571Y509853D01*
X1318500D01*
X1333151Y495202D01*
X1346819D01*
X1350793Y499176D01*
Y508324D01*
X1354636Y512167D01*
X1355590D01*
X1355591Y512166D01*
X1369634D01*
X1371145Y510655D01*
X1389545D01*
X1395330Y516440D01*
X1398661D01*
X1401954Y513147D01*
X1403005D01*
X1403977Y512175D01*
Y511677D01*
X1402950Y510650D01*
G01X696000Y496800D02*
Y496750D01*
X701750Y491000D01*
X707450D01*
X711802Y495352D01*
X752442D01*
X754558Y493236D01*
X875364D01*
X882974Y485626D01*
X959718D01*
X962592Y488500D01*
X1039026D01*
X1042662Y484864D01*
X1206111D01*
X1220457Y499210D01*
X1260400D01*
X1262057Y497553D01*
X1262843D01*
G01X713200Y505500D02*
X715400Y507700D01*
X716279D01*
X717069Y506910D01*
X721570D01*
X724360Y509700D01*
X732120D01*
X734000Y511580D01*
Y515860D01*
X741568Y523428D01*
X747115D01*
X753023Y529336D01*
Y529673D01*
X764689Y541339D01*
X1020071D01*
X1024972Y536438D01*
X1027503D01*
X1032961Y541896D01*
X1266864D01*
X1272500Y536260D01*
Y533731D01*
X1282678Y523553D01*
X1298442D01*
X1303541Y518454D01*
Y514253D01*
X1309093Y508701D01*
X1318022D01*
X1332673Y494050D01*
X1347297D01*
X1351945Y498698D01*
Y507846D01*
X1355113Y511014D01*
X1369086D01*
X1370672Y509428D01*
X1378159D01*
X1378634Y509903D01*
X1391028D01*
X1391078Y509953D01*
X1391125D01*
X1396035Y514863D01*
G01X715900Y505650D02*
X716208Y505958D01*
X718491D01*
X718691Y506158D01*
X721882D01*
X724376Y508652D01*
X724659D01*
X724755Y508748D01*
X732515D01*
X735204Y511437D01*
Y515717D01*
X741963Y522476D01*
X747227D01*
X753775Y529024D01*
Y529361D01*
X764052Y539638D01*
X764335D01*
X764821Y540124D01*
X1019460D01*
X1024299Y535285D01*
X1027980D01*
X1033776Y541081D01*
X1264917D01*
X1265054Y540944D01*
X1266469D01*
X1271376Y536037D01*
Y533508D01*
X1282283Y522601D01*
X1298047D01*
X1302589Y518059D01*
Y513858D01*
X1308947Y507500D01*
X1317876D01*
X1321440Y503936D01*
Y499440D01*
X1320300Y498300D01*
G01X679049Y503746D02*
X686753Y496042D01*
X691322D01*
X698597Y503317D01*
X716626D01*
X717269Y503960D01*
X717840D01*
X719086Y505206D01*
X722277D01*
X724771Y507700D01*
X733010D01*
X737500Y512190D01*
Y516658D01*
X742342Y521500D01*
X747598D01*
X754727Y528629D01*
Y528966D01*
X764447Y538686D01*
X1019198D01*
X1023551Y534333D01*
X1028375D01*
X1034171Y540129D01*
X1264522D01*
X1268150Y536501D01*
Y531200D01*
X1271877Y527473D01*
X1274627D01*
X1280800Y521300D01*
X1291600D01*
X1294200Y518700D01*
Y508560D01*
X1295600Y507160D01*
X1298194D01*
X1308058Y497296D01*
X1317450D01*
X1318911Y495835D01*
X1328515D01*
X1331452Y492898D01*
X1347775D01*
X1353097Y498220D01*
Y501751D01*
X1358682Y507336D01*
X1373260D01*
X1374110Y508186D01*
X1378547D01*
X1379112Y508751D01*
X1391506D01*
X1391555Y508800D01*
X1398964D01*
X1400191Y507573D01*
X1406147D01*
X1408587Y505133D01*
X1442574D01*
X1451621Y496086D01*
Y493945D01*
X1456590Y488976D01*
G01X1282600Y581000D02*
X1276122Y587478D01*
X1271044D01*
X1265344Y581778D01*
X1032402D01*
X1030735Y583445D01*
X1022148D01*
X1020766Y582063D01*
X759560D01*
X758697Y581200D01*
X735712D01*
X728660Y574148D01*
X710648D01*
X706300Y569800D01*
X703100D01*
X702100Y568800D01*
G01X1282600Y583600D02*
X1281700D01*
X1276700Y588600D01*
X1270435D01*
X1264765Y582930D01*
X1033270D01*
X1031603Y584597D01*
X1021670D01*
X1020288Y583215D01*
X759082D01*
X758019Y582152D01*
X735317D01*
X728265Y575100D01*
X710253D01*
X705953Y570800D01*
X702600D01*
X702000Y571400D01*
G01X729600Y17991D02*
Y15707D01*
X739291Y6016D01*
X739297D01*
X740049Y5264D01*
X761332D01*
X764164Y2432D01*
X1023524D01*
X1025856Y100D01*
X1027464D01*
X1032545Y5181D01*
X1271819D01*
X1275548Y8910D01*
Y16793D01*
X1283073Y24318D01*
X1290353D01*
X1303068Y37033D01*
X1305602D01*
X1305603Y37032D01*
X1305825D01*
X1307892Y39099D01*
X1326984D01*
X1331682Y43797D01*
Y80248D01*
X1334079Y82645D01*
Y91051D01*
X1336045Y93017D01*
X1340834D01*
X1341241Y93424D01*
X1371368D01*
X1373651Y95707D01*
X1395748D01*
X1404577Y104536D01*
Y111994D01*
X1400300Y116271D01*
Y121500D01*
G01X734256Y17991D02*
X732424Y16159D01*
Y13953D01*
X740361Y6016D01*
X763342D01*
X766174Y3184D01*
X1019969D01*
X1025969Y9184D01*
X1031702D01*
X1034953Y5933D01*
X1271507D01*
X1274796Y9222D01*
Y17105D01*
X1282761Y25070D01*
X1290041D01*
X1302756Y37785D01*
X1305356D01*
X1307421Y39850D01*
X1307579D01*
X1307580Y39851D01*
X1326672D01*
X1330930Y44109D01*
Y80560D01*
X1333327Y82957D01*
Y94886D01*
X1336641Y98200D01*
X1350927D01*
X1352682Y99955D01*
X1365282D01*
X1368220Y97017D01*
X1395994D01*
X1403659Y104682D01*
Y111041D01*
X1399100Y115600D01*
Y116000D01*
X1398600Y116500D01*
G01X732734Y82626D02*
X734230Y81130D01*
X735539D01*
X737961Y78708D01*
X747995D01*
X748755Y77948D01*
X754192D01*
X757698Y74442D01*
Y72149D01*
X770993Y58854D01*
X1014923D01*
X1018139Y62070D01*
X1018209D01*
X1020480Y64341D01*
Y64411D01*
X1035788Y79719D01*
X1040859D01*
X1045301Y75277D01*
Y73849D01*
X1047865Y71285D01*
Y68264D01*
X1046061Y66460D01*
Y65154D01*
X1046984Y64231D01*
X1048571D01*
X1049229Y63573D01*
X1261914D01*
X1263389Y65048D01*
Y109813D01*
X1273453Y119877D01*
Y127884D01*
X1278987Y133418D01*
Y140811D01*
X1282531Y144355D01*
Y165380D01*
X1280758Y167153D01*
Y176718D01*
X1270951Y186525D01*
Y194254D01*
X1276754Y200057D01*
Y207756D01*
X1269577Y214933D01*
Y242589D01*
X1270478Y243490D01*
G01X730038Y88408D02*
X731780Y90150D01*
X732565D01*
X734611Y92196D01*
Y92692D01*
X740279Y98360D01*
X753464D01*
X758850Y92974D01*
X765714D01*
X769781Y97041D01*
X959351D01*
X961250Y98940D01*
X966104D01*
X967257Y100093D01*
X1021924D01*
X1031617Y109786D01*
X1036933D01*
X1045891Y118744D01*
X1201524D01*
X1235025Y152245D01*
X1264941D01*
X1266646Y150540D01*
G01X1259950Y144650D02*
X1257724Y146876D01*
X1251347D01*
X1234618Y130147D01*
Y127640D01*
X1206953Y99975D01*
X1099007D01*
X1084046Y114936D01*
X1048133D01*
X1038375Y105178D01*
X1033529D01*
X1023836Y95485D01*
X969169D01*
X968016Y94332D01*
X963422D01*
X962400Y93310D01*
Y89506D01*
X961282Y88388D01*
X959012D01*
X958430Y88970D01*
X957121D01*
X955800Y87649D01*
Y87349D01*
X948117Y79666D01*
X764904D01*
X763350Y81220D01*
G01X732599Y88408D02*
Y89050D01*
X735363Y91814D01*
Y92380D01*
X740591Y97608D01*
X753152D01*
X758938Y91822D01*
X766192D01*
X770259Y95889D01*
X959899D01*
X961798Y97788D01*
X966582D01*
X967735Y98941D01*
X1022402D01*
X1032095Y108634D01*
X1037411D01*
X1046769Y117992D01*
X1202402D01*
X1234994Y150584D01*
X1261546D01*
G01X1264146D02*
X1262570Y149008D01*
X1250219D01*
X1231505Y130294D01*
Y128323D01*
X1205920Y102738D01*
X1099504D01*
X1085402Y116840D01*
X1047247D01*
X1037889Y107482D01*
X1032573D01*
X1022880Y97789D01*
X968213D01*
X967060Y96636D01*
X962326D01*
X960427Y94737D01*
X949337D01*
X941200Y86600D01*
Y84963D01*
X939359Y83122D01*
X772591D01*
X771240Y84473D01*
Y85189D01*
X768910Y87519D01*
X761930D01*
X758779Y90670D01*
X758460D01*
X752674Y96456D01*
X741069D01*
X736515Y91902D01*
Y91336D01*
X735241Y90062D01*
Y88329D01*
G01X1262569Y147201D02*
X1259099D01*
X1258444Y147856D01*
X1250697D01*
X1233079Y130238D01*
Y128267D01*
X1206398Y101586D01*
X1099026D01*
X1084924Y115688D01*
X1047725D01*
X1038367Y106330D01*
X1033051D01*
X1023358Y96637D01*
X968691D01*
X967538Y95484D01*
X962944D01*
X957960Y90500D01*
X956550D01*
X955060Y91990D01*
X953233D01*
X950750Y89507D01*
Y88992D01*
X943728Y81970D01*
X769221D01*
X766824Y84367D01*
Y85943D01*
G01X1252000Y145300D02*
X1236359Y129659D01*
Y127751D01*
X1207431Y98823D01*
X1098529D01*
X1083568Y113784D01*
X1048611D01*
X1038852Y104025D01*
X1037898D01*
X1037897Y104026D01*
X1034007D01*
X1024314Y94333D01*
X969647D01*
X968494Y93180D01*
X968309D01*
X965720Y90591D01*
Y86907D01*
X964629Y85816D01*
X962334D01*
X961860Y86290D01*
X959390D01*
X951250Y78150D01*
X769900D01*
X768474Y76724D01*
X762747D01*
X761774Y77697D01*
Y82944D01*
X763930Y85100D01*
G01X1263300Y169450D02*
X1259998Y172752D01*
X1251052D01*
X1248270Y169970D01*
X1238120D01*
X1194568Y126418D01*
X1041065D01*
X1034379Y119732D01*
X1028025D01*
X1022941Y114648D01*
X955384D01*
X952286Y117746D01*
X880613D01*
X874151Y111284D01*
X742454D01*
X738835Y107665D01*
Y103335D01*
X731910Y96410D01*
Y92790D01*
G01X1259200Y168350D02*
X1256950Y166100D01*
X1236944D01*
X1195587Y124743D01*
X1041588D01*
X1034295Y117450D01*
X1028437D01*
X1023731Y112744D01*
X954594D01*
X951496Y115842D01*
X881686D01*
X875024Y109180D01*
X746051D01*
X741700Y104829D01*
Y102000D01*
G01X1267800Y161800D02*
X1264600Y158600D01*
X1234334D01*
X1198221Y122487D01*
X1044222D01*
X1035729Y113994D01*
X1029871D01*
X1025129Y109252D01*
X964202D01*
X956506Y101556D01*
X776516D01*
X773596Y104476D01*
X756376D01*
X752900Y101000D01*
G01X1271400Y161900D02*
X1269824Y163476D01*
X1235950D01*
X1196465Y123991D01*
X1042466D01*
X1034773Y116298D01*
X1028915D01*
X1024209Y111592D01*
X954116D01*
X951018Y114690D01*
X883258D01*
X876200Y107632D01*
X747456D01*
X744200Y104376D01*
Y102800D01*
G01X1261800Y154973D02*
X1260181Y156592D01*
X1235020D01*
X1199083Y120655D01*
X1045084D01*
X1036519Y112090D01*
X1030661D01*
X1025771Y107200D01*
X970434D01*
X964478Y101244D01*
X960224D01*
X958380Y99400D01*
X756800D01*
G01X746600Y103900D02*
X748427Y105727D01*
X774757D01*
X777776Y102708D01*
X956008D01*
X963704Y110404D01*
X1024651D01*
X1029393Y115146D01*
X1035251D01*
X1043344Y123239D01*
X1197343D01*
X1236004Y161900D01*
X1240309D01*
G01X1267050Y169800D02*
X1265124Y167874D01*
X1262626D01*
X1260574Y169926D01*
X1253678D01*
X1251452Y167700D01*
X1237480D01*
X1195275Y125495D01*
X1041276D01*
X1033983Y118202D01*
X1028125D01*
X1023419Y113496D01*
X954906D01*
X951808Y116594D01*
X881091D01*
X874628Y110131D01*
X744967D01*
X739763Y104927D01*
Y100022D01*
X734971Y95230D01*
X733740D01*
G01X1269810Y154398D02*
X1268302D01*
X1265036Y157664D01*
X1235028D01*
X1198968Y121604D01*
X1044969D01*
X1036207Y112842D01*
X1030349D01*
X1025606Y108099D01*
X969563D01*
X963460Y101996D01*
X959696D01*
X958104Y100404D01*
X760347D01*
X758751Y102000D01*
X756800D01*
G01X739307Y598850D02*
X1292862D01*
X1296524Y595188D01*
Y589347D01*
X1297606Y588265D01*
Y563873D01*
X1295924Y562191D01*
Y548076D01*
X1308680Y535320D01*
Y532480D01*
X1318258Y522902D01*
X1329938D01*
X1336165Y529129D01*
X1394129D01*
X1403027Y520231D01*
G01X726857Y610871D02*
X729938Y613952D01*
X735013D01*
X740215Y619154D01*
X1039403D01*
X1039404Y619155D01*
X1040192D01*
X1041390Y617957D01*
X1102040D01*
X1103975Y619892D01*
X1296405D01*
X1300997Y615300D01*
X1326220D01*
X1329552Y611968D01*
Y549948D01*
X1332184Y547316D01*
X1348152D01*
X1357007Y556171D01*
X1370982D01*
X1374096Y553057D01*
X1379227D01*
X1380064Y553894D01*
X1385406D01*
X1387942Y556430D01*
Y556503D01*
X1398343Y566904D01*
X1434907D01*
X1439289Y562522D01*
Y561734D01*
X1439288Y561733D01*
Y559596D01*
X1443126Y555758D01*
X1453011D01*
X1462148Y564895D01*
Y573698D01*
X1467975Y579525D01*
X1500075D01*
X1506900Y586350D01*
X1539850D01*
X1541000Y587500D01*
X1543424D01*
X1545200Y585724D01*
G01X1542600D02*
X1542274Y585398D01*
X1507295D01*
X1500470Y578573D01*
X1468370D01*
X1463100Y573303D01*
Y564500D01*
X1453406Y554806D01*
X1442731D01*
X1438336Y559201D01*
Y562128D01*
X1434512Y565952D01*
X1398811D01*
X1385801Y552942D01*
X1380459D01*
X1379622Y552105D01*
X1373701D01*
X1370587Y555219D01*
X1357402D01*
X1348547Y546364D01*
X1331789D01*
X1328600Y549553D01*
Y611461D01*
X1325721Y614340D01*
X1300610D01*
X1296010Y618940D01*
X1104370D01*
X1102435Y617005D01*
X1040995D01*
X1039798Y618202D01*
X740610D01*
X735408Y613000D01*
X730309D01*
X729616Y612307D01*
Y610863D01*
G01X1327956Y545655D02*
X1327278Y546333D01*
Y610881D01*
X1324971Y613188D01*
X1295293D01*
X1291599Y616882D01*
X1103942D01*
X1102913Y615853D01*
X1040647D01*
X1039450Y617050D01*
X741088D01*
X735038Y611000D01*
X732500D01*
G01X818960Y202230D02*
X820146Y201044D01*
X842895D01*
X848322Y206471D01*
X916718D01*
G03X919113Y207463I0J3387D01*
G03X919483Y207946I-1647J1645D01*
G02X920799Y208733I1364J-787D01*
G01X920912D01*
G03X922863Y209896I-65J2327D01*
G02X924179Y210683I1364J-787D01*
G01X924308D01*
G03X926243Y211846I-81J2326D01*
G02X927579Y212634I1364J-786D01*
G01X927702D01*
G03X929623Y213796I-95J2326D01*
G02X930939Y214583I1364J-787D01*
G01X931068D01*
G03X933003Y215746I-81J2326D01*
G02X934339Y216534I1364J-786D01*
G01X934462D01*
G03X936383Y217696I-95J2326D01*
G02X937699Y218483I1364J-787D01*
G01X937828D01*
G03X939763Y219646I-81J2326D01*
G02X941099Y220434I1364J-786D01*
G01X941222D01*
G03X943143Y221596I-95J2326D01*
G02X944459Y222383I1364J-787D01*
G01X944588D01*
G03X946523Y223546I-81J2326D01*
G02X947859Y224334I1364J-786D01*
G01X947982D01*
G03X949903Y225496I-95J2326D01*
G02X951219Y226283I1364J-787D01*
G01X951311D01*
G03X953283Y227447I-44J2327D01*
G02X954573Y228233I1364J-787D01*
G01X954728D01*
G03X956663Y229396I-81J2326D01*
G02X957991Y230183I1363J-786D01*
G01X958107D01*
G03X960042Y231346I-81J2326D01*
G02X961358Y232133I1364J-787D01*
G01X961471D01*
G03X963422Y233296I-65J2327D01*
G02X964738Y234083I1364J-787D01*
G01X964867D01*
G03X966802Y235246I-81J2326D01*
G02X968138Y236034I1364J-786D01*
G01X968261D01*
G03X970182Y237196I-95J2326D01*
G02X971498Y237983I1364J-787D01*
G01X971627D01*
G03X973562Y239146I-81J2326D01*
G02X974898Y239934I1364J-786D01*
G01X975021D01*
G03X976942Y241096I-95J2326D01*
G02X978258Y241883I1364J-787D01*
G01X978387D01*
G03X980322Y243046I-81J2326D01*
G02X981658Y243834I1364J-786D01*
G01X981781D01*
G03X983702Y244996I-95J2326D01*
G02X985018Y245783I1364J-787D01*
G01X985147D01*
G03X987082Y246946I-81J2326D01*
G02X988418Y247734I1364J-786D01*
G01X988541D01*
G03X990462Y248896I-95J2326D01*
G02X991778Y249683I1364J-787D01*
G01X991907D01*
G03X993842Y250846I-81J2326D01*
G02X995178Y251634I1364J-786D01*
G01X995301D01*
G03X997222Y252796I-95J2326D01*
G02X998358Y253567I1364J-787D01*
G01X998586Y253339D01*
Y252009D01*
G01X814849Y205001D02*
X816001Y206153D01*
X846684D01*
X847935Y207404D01*
X917158D01*
G03X918581Y207995I-3J2015D01*
G03X918831Y208322I-1116J1112D01*
G02X920803Y209486I2016J-1163D01*
G01X920895D01*
G03X922211Y210273I-48J1574D01*
G02X924132Y211435I2016J-1164D01*
G01X924255D01*
G03X925591Y212223I-28J1574D01*
G02X927526Y213386I2016J-1163D01*
G01X927655D01*
G03X928971Y214173I-48J1574D01*
G02X930892Y215335I2016J-1164D01*
G01X931015D01*
G03X932351Y216123I-28J1574D01*
G02X934286Y217286I2016J-1163D01*
G01X934415D01*
G03X935731Y218073I-48J1574D01*
G02X937652Y219235I2016J-1164D01*
G01X937775D01*
G03X939111Y220023I-28J1574D01*
G02X941046Y221186I2016J-1163D01*
G01X941175D01*
G03X942491Y221973I-48J1574D01*
G02X944412Y223135I2016J-1164D01*
G01X944535D01*
G03X945871Y223923I-28J1574D01*
G02X947806Y225086I2016J-1163D01*
G01X947935D01*
G03X949251Y225873I-48J1574D01*
G02X951202Y227036I2016J-1164D01*
G01X951315D01*
G03X952631Y227823I-48J1574D01*
G02X954566Y228986I2016J-1163D01*
G01X954682D01*
G03X956010Y229773I-35J1573D01*
G02X957945Y230936I2016J-1163D01*
G01X958100D01*
G03X959390Y231722I-74J1573D01*
G02X961362Y232886I2016J-1163D01*
G01X961454D01*
G03X962770Y233673I-48J1574D01*
G02X964691Y234835I2016J-1164D01*
G01X964814D01*
G03X966150Y235623I-28J1574D01*
G02X968085Y236786I2016J-1163D01*
G01X968214D01*
G03X969530Y237573I-48J1574D01*
G02X971451Y238735I2016J-1164D01*
G01X971574D01*
G03X972910Y239523I-28J1574D01*
G02X974845Y240686I2016J-1163D01*
G01X974974D01*
G03X976290Y241473I-48J1574D01*
G02X978211Y242635I2016J-1164D01*
G01X978334D01*
G03X979670Y243423I-28J1574D01*
G02X981605Y244586I2016J-1163D01*
G01X981734D01*
G03X983050Y245373I-48J1574D01*
G02X984971Y246535I2016J-1164D01*
G01X985094D01*
G03X986430Y247323I-28J1574D01*
G02X988365Y248486I2016J-1163D01*
G01X988494D01*
G03X989810Y249273I-48J1574D01*
G02X991731Y250435I2016J-1164D01*
G01X991854D01*
G03X993190Y251223I-28J1574D01*
G02X995125Y252386I2016J-1163D01*
G01X995254D01*
G03X996570Y253173I-48J1574D01*
G02X998330Y254323I2016J-1164D01*
G01X998586Y254579D01*
Y255909D01*
G01X808165Y203529D02*
X809851D01*
X813324Y207002D01*
X845370D01*
X847192Y208824D01*
X914340D01*
X920099Y214583D01*
X924308D01*
G03X926243Y215746I-81J2326D01*
G02X927579Y216534I1364J-786D01*
G01X927702D01*
G03X929623Y217696I-95J2326D01*
G02X930939Y218483I1364J-787D01*
G01X931068D01*
G03X933003Y219646I-81J2326D01*
G02X934339Y220434I1364J-786D01*
G01X934462D01*
G03X936383Y221596I-95J2326D01*
G02X937699Y222383I1364J-787D01*
G01X937828D01*
G03X939763Y223546I-81J2326D01*
G02X941099Y224334I1364J-786D01*
G01X941222D01*
G03X943143Y225496I-95J2326D01*
G02X944459Y226283I1364J-787D01*
G01X944551D01*
G03X946523Y227447I-44J2327D01*
G02X947813Y228233I1364J-787D01*
G01X947968D01*
G03X949903Y229396I-81J2326D01*
G02X951205Y230183I1364J-786D01*
G01X951348D01*
G03X953283Y231346I-81J2326D01*
G02X954599Y232133I1364J-787D01*
G01X954712D01*
G03X956663Y233296I-65J2327D01*
G01X956672Y233311D01*
G02X958026Y234083I1354J-801D01*
G01X958107D01*
G03X960042Y235246I-81J2326D01*
G02X961378Y236034I1364J-786D01*
G01X961501D01*
G03X963422Y237196I-95J2326D01*
G02X964738Y237983I1364J-787D01*
G01X964867D01*
G03X966802Y239146I-81J2326D01*
G02X968138Y239934I1364J-786D01*
G01X968261D01*
G03X970182Y241096I-95J2326D01*
G02X971498Y241883I1364J-787D01*
G01X971627D01*
G03X973562Y243046I-81J2326D01*
G02X974898Y243834I1364J-786D01*
G01X975021D01*
G03X976942Y244996I-95J2326D01*
G02X978258Y245783I1364J-787D01*
G01X978387D01*
G03X980322Y246946I-81J2326D01*
G02X981658Y247734I1364J-786D01*
G01X981781D01*
G03X983702Y248896I-95J2326D01*
G02X985018Y249683I1364J-787D01*
G01X985147D01*
G03X987082Y250846I-81J2326D01*
G02X988418Y251634I1364J-786D01*
G01X988541D01*
G03X990462Y252796I-95J2326D01*
G02X991778Y253583I1364J-787D01*
G01X991907D01*
G03X993842Y254746I-81J2326D01*
G02X995178Y255534I1364J-786D01*
G01X995301D01*
G03X997222Y256696I-95J2326D01*
G02X998538Y257483I1364J-787D01*
G01X998667D01*
G03X1000461Y258429I-80J2326D01*
G01X1000813Y258524D01*
X1001965Y257860D01*
G01X797717Y201907D02*
X801954Y206144D01*
X809951D01*
X812512Y208705D01*
X843413D01*
X845865Y211157D01*
X913355D01*
X920681Y218483D01*
X924308D01*
G03X926243Y219646I-81J2326D01*
G02X927579Y220434I1364J-786D01*
G01X927702D01*
G03X929623Y221596I-95J2326D01*
G02X930939Y222383I1364J-787D01*
G01X931068D01*
G03X933003Y223546I-81J2326D01*
G02X934339Y224334I1364J-786D01*
G01X934462D01*
G03X936383Y225496I-95J2326D01*
G02X937699Y226283I1364J-787D01*
G01X937791D01*
G03X939763Y227447I-44J2327D01*
G02X941053Y228233I1364J-787D01*
G01X941208D01*
G03X943143Y229396I-81J2326D01*
G02X944445Y230183I1364J-786D01*
G01X944588D01*
G03X946523Y231346I-81J2326D01*
G02X947839Y232133I1364J-787D01*
G01X947952D01*
G03X949903Y233296I-65J2327D01*
G02X951219Y234083I1364J-787D01*
G01X951348D01*
G03X953283Y235246I-81J2326D01*
G02X954619Y236034I1364J-786D01*
G01X954742D01*
G03X956663Y237196I-95J2326D01*
G01X956672Y237211D01*
G02X958026Y237983I1354J-801D01*
G01X958107D01*
G03X960042Y239146I-81J2326D01*
G02X961378Y239934I1364J-786D01*
G01X961501D01*
G03X963422Y241096I-95J2326D01*
G02X964738Y241883I1364J-787D01*
G01X964867D01*
G03X966802Y243046I-81J2326D01*
G02X968138Y243834I1364J-786D01*
G01X968261D01*
G03X970182Y244996I-95J2326D01*
G02X971498Y245783I1364J-787D01*
G01X971627D01*
G03X973562Y246946I-81J2326D01*
G02X974898Y247734I1364J-786D01*
G01X975021D01*
G03X976942Y248896I-95J2326D01*
G02X978258Y249683I1364J-787D01*
G01X978387D01*
G03X980322Y250846I-81J2326D01*
G02X981658Y251634I1364J-786D01*
G01X981781D01*
G03X983702Y252796I-95J2326D01*
G02X985018Y253583I1364J-787D01*
G01X985147D01*
G03X987082Y254746I-81J2326D01*
G02X988418Y255534I1364J-786D01*
G01X988541D01*
G03X990462Y256696I-95J2326D01*
G02X991778Y257483I1364J-787D01*
G01X991907D01*
G03X993842Y258646I-81J2326D01*
G02X994979Y259417I1363J-787D01*
G01X995206Y259190D01*
Y257860D01*
G01X803134Y202969D02*
X805557Y205392D01*
X810457D01*
X812968Y207903D01*
X844996D01*
X846818Y209725D01*
X914178D01*
X919788Y215335D01*
X924255D01*
G03X925591Y216123I-28J1574D01*
G02X927526Y217286I2016J-1163D01*
G01X927655D01*
G03X928971Y218073I-48J1574D01*
G02X930892Y219235I2016J-1164D01*
G01X931015D01*
G03X932351Y220023I-28J1574D01*
G02X934286Y221186I2016J-1163D01*
G01X934415D01*
G03X935731Y221973I-48J1574D01*
G02X937652Y223135I2016J-1164D01*
G01X937775D01*
G03X939111Y223923I-28J1574D01*
G02X941046Y225086I2016J-1163D01*
G01X941175D01*
G03X942491Y225873I-48J1574D01*
G02X944442Y227036I2016J-1164D01*
G01X944555D01*
G03X945871Y227823I-48J1574D01*
G02X947806Y228986I2016J-1163D01*
G01X947949D01*
G03X949251Y229773I-62J1573D01*
G02X951186Y230936I2016J-1163D01*
G01X951341D01*
G03X952631Y231722I-74J1573D01*
G02X954603Y232886I2016J-1163D01*
G01X954647D01*
G03X956001Y233658I0J1573D01*
G01X956010Y233673D01*
G02X957931Y234835I2016J-1164D01*
G01X958054D01*
G03X959390Y235623I-28J1574D01*
G02X961325Y236786I2016J-1163D01*
G01X961454D01*
G03X962770Y237573I-48J1574D01*
G02X964691Y238735I2016J-1164D01*
G01X964814D01*
G03X966150Y239523I-28J1574D01*
G02X968085Y240686I2016J-1163D01*
G01X968214D01*
G03X969530Y241473I-48J1574D01*
G02X971451Y242635I2016J-1164D01*
G01X971574D01*
G03X972910Y243423I-28J1574D01*
G02X974845Y244586I2016J-1163D01*
G01X974974D01*
G03X976290Y245373I-48J1574D01*
G02X978211Y246535I2016J-1164D01*
G01X978334D01*
G03X979670Y247323I-28J1574D01*
G02X981605Y248486I2016J-1163D01*
G01X981734D01*
G03X983050Y249273I-48J1574D01*
G02X984971Y250435I2016J-1164D01*
G01X985094D01*
G03X986430Y251223I-28J1574D01*
G02X988365Y252386I2016J-1163D01*
G01X988494D01*
G03X989810Y253173I-48J1574D01*
G02X991731Y254335I2016J-1164D01*
G01X991854D01*
G03X993190Y255123I-28J1574D01*
G02X995125Y256286I2016J-1163D01*
G01X995254D01*
G03X996570Y257073I-48J1574D01*
G02X998491Y258235I2016J-1164D01*
G01X998586D01*
G03X999821Y258834I-1J1574D01*
G01X999738Y259145D01*
X998586Y259809D01*
G01X792514Y201290D02*
X798119Y206895D01*
X809357D01*
X812053Y209591D01*
X843046D01*
X845498Y212043D01*
X913178D01*
X920370Y219235D01*
X924255D01*
G03X925591Y220023I-28J1574D01*
G02X927526Y221186I2016J-1163D01*
G01X927655D01*
G03X928971Y221973I-48J1574D01*
G02X930892Y223135I2016J-1164D01*
G01X931015D01*
G03X932351Y223923I-28J1574D01*
G02X934286Y225086I2016J-1163D01*
G01X934415D01*
G03X935731Y225873I-48J1574D01*
G02X937682Y227036I2016J-1164D01*
G01X937795D01*
G03X939111Y227823I-48J1574D01*
G02X941046Y228986I2016J-1163D01*
G01X941189D01*
G03X942491Y229773I-62J1573D01*
G02X944426Y230936I2016J-1163D01*
G01X944581D01*
G03X945871Y231722I-74J1573D01*
G02X947843Y232886I2016J-1163D01*
G01X947935D01*
G03X949251Y233673I-48J1574D01*
G02X951172Y234835I2016J-1164D01*
G01X951295D01*
G03X952631Y235623I-28J1574D01*
G02X954566Y236786I2016J-1163D01*
G01X954647D01*
G03X956001Y237558I0J1573D01*
G01X956010Y237573D01*
G02X957931Y238735I2016J-1164D01*
G01X958054D01*
G03X959390Y239523I-28J1574D01*
G02X961325Y240686I2016J-1163D01*
G01X961454D01*
G03X962770Y241473I-48J1574D01*
G02X964691Y242635I2016J-1164D01*
G01X964814D01*
G03X966150Y243423I-28J1574D01*
G02X968085Y244586I2016J-1163D01*
G01X968214D01*
G03X969530Y245373I-48J1574D01*
G02X971451Y246535I2016J-1164D01*
G01X971574D01*
G03X972910Y247323I-28J1574D01*
G02X974845Y248486I2016J-1163D01*
G01X974974D01*
G03X976290Y249273I-48J1574D01*
G02X978211Y250435I2016J-1164D01*
G01X978334D01*
G03X979670Y251223I-28J1574D01*
G02X981605Y252386I2016J-1163D01*
G01X981734D01*
G03X983050Y253173I-48J1574D01*
G02X984971Y254335I2016J-1164D01*
G01X985094D01*
G03X986430Y255123I-28J1574D01*
G02X988365Y256286I2016J-1163D01*
G01X988494D01*
G03X989810Y257073I-48J1574D01*
G02X991731Y258235I2016J-1164D01*
G01X991854D01*
G03X993190Y259023I-28J1574D01*
G02X994950Y260174I2016J-1162D01*
G01X995206Y260430D01*
Y261760D01*
G01X1610004Y-17346D02*
X1606358Y-13700D01*
X1589600D01*
X1588300Y-12400D01*
X1580600D01*
X1575400Y-7200D01*
X1547500D01*
X1546400Y-8300D01*
Y-8400D01*
X1545900Y-8900D01*
X1505929D01*
X1497707Y-678D01*
Y9093D01*
X1486329Y20471D01*
X1444227D01*
X1435807Y28891D01*
Y38179D01*
X1427324Y46662D01*
X1424356D01*
X1422622Y48396D01*
Y74198D01*
X1419611Y77209D01*
Y86749D01*
X1409310Y97050D01*
X1403181D01*
X1397630Y91499D01*
X1384625D01*
X1382210Y89084D01*
X1342855D01*
X1341583Y87812D01*
Y76071D01*
X1339500Y73988D01*
Y57477D01*
X1336623Y54600D01*
Y42784D01*
X1328730Y34891D01*
X1309834D01*
X1304615Y29672D01*
X1301661D01*
X1292099Y20110D01*
X1284894D01*
X1279846Y15062D01*
Y6716D01*
X1274103Y973D01*
X1035582D01*
X1028639Y-5970D01*
Y-6615D01*
G01X1108125Y276799D02*
X1116152Y284826D01*
X1125296D01*
X1126611Y286141D01*
X1128304D01*
X1130129Y287966D01*
X1131431D01*
X1133256Y286141D01*
X1135231D01*
X1137170Y284202D01*
X1138373D01*
X1140211Y282364D01*
X1141614D01*
X1142651Y281327D01*
Y268545D01*
X1144300Y266896D01*
G01X1198835Y237700D02*
X1197800D01*
X1195900Y239600D01*
X1194200D01*
X1192400Y241400D01*
X1190800D01*
X1188900Y243300D01*
X1187200D01*
X1185400Y241500D01*
X1183800D01*
X1182000Y243300D01*
X1180400D01*
X1178700Y241600D01*
X1177100D01*
X1175200Y243500D01*
X1173900D01*
X1172100Y245300D01*
X1171000D01*
X1169600Y246700D01*
Y265800D01*
X1168400Y267000D01*
X1165600D01*
X1161800Y270800D01*
X1160300D01*
X1158200Y268700D01*
X1157300D01*
X1155300Y270700D01*
X1153900D01*
X1151900Y272700D01*
X1150100D01*
X1148104Y274696D01*
X1144300D01*
G01X1114839Y320075D02*
X1115748Y319166D01*
X1120172D01*
X1122100Y317238D01*
Y298100D01*
X1125623Y294577D01*
X1128178D01*
X1130129Y292626D01*
X1131560D01*
X1133509Y290677D01*
X1134051D01*
X1136762Y287966D01*
X1138191D01*
X1140057Y286100D01*
X1142300D01*
X1144334Y284066D01*
X1144951D01*
X1147680Y281337D01*
Y280547D01*
G01X1220702Y216708D02*
X1221587Y217593D01*
Y220974D01*
X1220531Y222030D01*
X1209809D01*
X1209439Y222400D01*
G01X1203358Y238683D02*
X1202183Y239858D01*
X1200504D01*
X1198452Y241910D01*
X1197147D01*
X1195357Y243700D01*
X1194237D01*
X1190920Y247017D01*
X1187556D01*
X1186365Y245826D01*
X1183830D01*
X1182639Y247017D01*
X1180730D01*
X1179539Y245826D01*
X1177448D01*
X1174719Y248555D01*
Y249347D01*
G01X1157820Y266896D02*
X1163700D01*
X1166300Y264296D01*
Y244300D01*
X1167200Y243400D01*
X1168800D01*
X1170900Y241300D01*
X1172200D01*
X1174100Y239400D01*
X1175800D01*
X1177400Y237800D01*
X1178800D01*
X1180550Y239550D01*
X1182150D01*
X1184100Y237600D01*
X1185300D01*
X1187100Y239400D01*
X1189200D01*
X1190900Y237700D01*
X1192400D01*
X1194600Y235500D01*
X1195500D01*
X1197500Y233500D01*
X1199300D01*
X1200900Y231900D01*
X1201858D01*
G01X1207741Y223034D02*
X1210259Y220516D01*
X1211592D01*
X1214008Y218100D01*
X1218000D01*
G01X1268404Y246304D02*
X1259664D01*
X1234952Y221592D01*
Y203812D01*
X1253412Y185352D01*
X1263786D01*
X1277605Y171533D01*
Y155811D01*
X1280227Y153189D01*
Y147214D01*
X1278793Y145780D01*
X1278000D01*
G01X1268236Y141938D02*
Y145678D01*
X1276302Y153744D01*
Y170612D01*
X1262895Y184019D01*
X1252757D01*
X1233294Y203482D01*
Y221892D01*
X1266702Y255300D01*
X1274100D01*
G01X1347546Y476897D02*
X1344587D01*
X1334212Y487272D01*
X1303728D01*
X1301444Y489556D01*
X1295423D01*
X1294565Y490414D01*
X1289225D01*
X1281554Y498085D01*
X1278777D01*
X1277800Y497108D01*
G01X1266162Y496404D02*
Y495842D01*
X1268000Y494004D01*
X1274872D01*
X1275056Y493820D01*
X1278422D01*
X1284684Y487558D01*
X1293380D01*
X1294238Y486700D01*
X1300259D01*
X1302543Y484416D01*
X1330273D01*
X1344435Y470254D01*
X1349154D01*
X1353041Y474141D01*
X1354462D01*
G01X1350500Y475100D02*
Y473700D01*
X1348133Y471333D01*
X1345182D01*
X1331147Y485368D01*
X1302938D01*
X1300654Y487652D01*
X1294633D01*
X1293775Y488510D01*
X1285091D01*
X1278762Y494839D01*
X1275421D01*
X1275293Y494967D01*
X1270055D01*
X1269006Y496016D01*
G01X1341050Y498275D02*
Y499250D01*
X1338645Y501655D01*
X1332290D01*
X1328531Y505414D01*
Y512162D01*
X1321643Y519050D01*
X1316790D01*
X1304695Y531145D01*
Y533959D01*
X1298654Y540000D01*
X1283676D01*
Y539947D01*
X1282753Y539024D01*
X1277276D01*
X1277200Y539100D01*
G01X1680033Y-16711D02*
X1675098Y-21646D01*
X1450957D01*
X1446816Y-17505D01*
Y-523D01*
X1430125Y16168D01*
X1398898D01*
X1396552Y13822D01*
Y4459D01*
X1392600Y507D01*
Y-17615D01*
X1388572Y-21643D01*
X1291499D01*
X1289382Y-19526D01*
Y-15860D01*
X1288646Y-15124D01*
X1286776D01*
X1285800Y-16100D01*
X1283605D01*
X1282252Y-14747D01*
G01X1284859Y-14524D02*
X1285411Y-13972D01*
X1289124D01*
X1290534Y-15382D01*
Y-19048D01*
X1291977Y-20491D01*
X1354409D01*
X1356800Y-18100D01*
X1358209D01*
X1360600Y-20491D01*
X1388001D01*
X1391382Y-17110D01*
Y1012D01*
X1395400Y5030D01*
Y14300D01*
X1398486Y17386D01*
X1430537D01*
X1447968Y-45D01*
Y-17027D01*
X1451435Y-20494D01*
X1673104D01*
X1676819Y-16779D01*
G01X1425081Y48412D02*
Y73470D01*
X1421167Y77384D01*
Y86834D01*
X1410562Y97439D01*
Y118172D01*
X1401406Y127328D01*
Y127845D01*
X1401364Y127887D01*
Y128336D01*
X1397006Y132694D01*
X1329794D01*
X1327500Y130400D01*
X1319350D01*
X1318000Y129050D01*
Y97676D01*
X1320000Y95676D01*
Y85500D01*
G01X1304500Y40066D02*
X1302866D01*
X1300500Y37700D01*
X1297708D01*
X1296908Y36900D01*
G01X1326474Y216500D02*
Y216300D01*
X1324974Y214800D01*
X1320185D01*
X1318814Y216171D01*
Y225186D01*
X1312700Y231300D01*
Y241312D01*
X1315277Y243889D01*
Y258733D01*
X1301962Y272048D01*
Y296136D01*
X1302768Y296942D01*
G01X1290500Y482700D02*
X1291400D01*
X1293509Y480591D01*
X1326300D01*
X1340465Y466426D01*
X1348409D01*
X1349652Y465183D01*
Y462084D01*
X1347975Y460407D01*
Y420658D01*
X1339033Y411716D01*
Y394038D01*
X1341173Y391898D01*
Y371860D01*
X1338881Y369568D01*
Y365989D01*
X1327552Y354660D01*
Y352332D01*
X1323219Y347999D01*
Y323051D01*
X1323750Y322520D01*
Y319750D01*
G01X1320900Y321300D02*
X1322067Y322467D01*
Y348477D01*
X1326400Y352810D01*
Y355138D01*
X1337666Y366404D01*
Y370445D01*
X1340021Y372800D01*
Y391420D01*
X1337881Y393560D01*
Y412740D01*
X1346823Y421682D01*
Y461146D01*
X1348379Y462702D01*
Y464508D01*
X1347617Y465270D01*
X1339991D01*
X1325822Y479439D01*
X1293031D01*
X1291820Y480650D01*
X1290950D01*
X1290500Y480200D01*
G01X1329757Y346511D02*
Y339229D01*
X1328820Y338292D01*
Y337785D01*
X1327989Y336954D01*
Y301886D01*
X1334320Y295555D01*
X1345284D01*
X1348797Y292042D01*
X1364554D01*
X1387118Y269478D01*
Y249534D01*
X1388600Y248052D01*
Y230900D01*
X1388500Y230800D01*
Y230789D01*
X1388518D01*
G01X1336336Y333825D02*
X1333226Y330715D01*
Y301745D01*
X1336204Y298767D01*
X1346293D01*
X1349349Y295711D01*
X1364427D01*
X1389977Y270161D01*
Y250734D01*
X1391352Y249359D01*
Y246460D01*
X1400066Y237746D01*
Y236274D01*
G01X1332613Y346417D02*
X1331333Y345137D01*
Y338527D01*
X1329241Y336435D01*
Y303152D01*
X1335252Y297141D01*
X1345900D01*
X1349289Y293752D01*
X1364615D01*
X1388578Y269789D01*
Y250362D01*
X1390100Y248840D01*
Y231406D01*
X1391206Y230300D01*
X1397706D01*
X1397748Y230342D01*
X1398136D01*
X1399176Y231382D01*
Y233423D01*
X1399528Y233775D01*
X1399978D01*
G01X1316600Y305500D02*
X1313678D01*
X1309534Y309644D01*
Y348193D01*
X1312840Y351499D01*
Y363100D01*
X1313976Y364236D01*
Y415677D01*
X1313004Y416649D01*
Y423004D01*
X1318000Y428000D01*
Y434500D01*
X1322400Y438900D01*
Y459820D01*
X1321172Y461048D01*
Y464474D01*
G01X1303380Y309441D02*
Y310226D01*
X1305941Y312787D01*
Y349341D01*
X1309488Y352888D01*
Y365011D01*
X1310970Y366493D01*
Y413942D01*
X1308500Y416412D01*
Y433101D01*
X1302011Y439590D01*
X1294419D01*
X1288671Y445338D01*
G01X1308887Y285015D02*
Y285521D01*
X1316533Y293167D01*
Y301639D01*
X1318176Y303282D01*
Y307130D01*
X1310286Y315020D01*
Y347787D01*
X1313909Y351410D01*
Y362700D01*
X1314744Y363535D01*
Y415975D01*
X1314004Y416715D01*
Y422898D01*
X1316606Y425500D01*
X1322000D01*
X1323450Y426950D01*
Y461602D01*
X1323815Y461967D01*
Y463543D01*
G01X1286831Y443058D02*
X1289970Y439919D01*
Y435479D01*
X1303500Y421949D01*
Y419782D01*
X1309818Y413464D01*
Y367425D01*
X1308336Y365943D01*
Y353535D01*
X1304789Y349988D01*
Y313265D01*
X1299932Y308408D01*
Y305879D01*
X1302491Y303320D01*
Y300410D01*
X1301552Y299476D01*
X1300651D01*
X1300606Y299431D01*
X1300599D01*
X1300195Y299038D01*
X1299700Y298557D01*
G01X1285769Y440062D02*
X1288830Y437001D01*
Y435204D01*
X1302500Y421534D01*
Y419434D01*
X1308866Y413068D01*
Y367798D01*
X1307384Y366316D01*
Y353983D01*
X1303837Y350436D01*
Y313660D01*
X1298980Y308803D01*
Y305484D01*
X1301539Y302925D01*
Y300806D01*
X1301159Y300428D01*
X1300583D01*
X1299735Y301298D01*
G01X1326014Y347732D02*
Y346070D01*
X1324684Y344740D01*
Y324958D01*
X1325500Y324142D01*
Y298052D01*
X1335162Y288390D01*
X1338271D01*
X1343121Y283540D01*
X1346821D01*
X1348301Y285020D01*
Y286574D01*
X1350508Y288781D01*
X1365742D01*
X1370290Y284233D01*
Y276429D01*
X1377669Y269050D01*
X1383009D01*
X1385624Y266435D01*
Y259904D01*
X1383384Y257664D01*
Y231608D01*
X1386898Y228094D01*
X1392650D01*
X1393366Y228810D01*
X1395747D01*
X1397211Y227346D01*
Y226041D01*
G01X1390100Y457500D02*
X1384145Y463455D01*
X1367065D01*
X1365015Y461405D01*
X1357811D01*
X1354946Y458540D01*
Y445402D01*
X1355942Y444406D01*
X1355943D01*
X1356960Y443389D01*
Y424708D01*
X1342037Y409785D01*
Y395284D01*
X1347136Y390185D01*
Y358749D01*
X1339999Y351612D01*
X1337385D01*
X1336886Y351113D01*
G01X1335250Y344250D02*
X1337451D01*
X1350650Y357449D01*
Y391485D01*
X1345441Y396694D01*
Y408375D01*
X1360364Y423298D01*
Y444799D01*
X1358350Y446813D01*
Y453521D01*
X1362665Y457836D01*
X1366260D01*
X1368475Y460051D01*
X1380959D01*
X1388510Y452500D01*
X1390100D01*
G01X1395100Y447500D02*
X1392200Y450400D01*
Y453899D01*
X1391539Y454560D01*
X1390309D01*
X1383116Y461753D01*
X1367770D01*
X1365556Y459539D01*
X1358450D01*
X1356648Y457737D01*
Y446108D01*
X1358662Y444094D01*
Y424003D01*
X1343739Y409080D01*
Y395989D01*
X1348839Y390889D01*
Y389481D01*
X1348838Y389480D01*
Y358044D01*
X1340550Y349756D01*
X1339597D01*
G01X1341528Y463528D02*
X1333087D01*
X1327800Y458241D01*
Y427540D01*
X1324930Y424670D01*
X1316840D01*
X1315004Y422834D01*
Y416995D01*
X1315496Y416503D01*
Y361190D01*
G01X1347196Y472941D02*
X1333817Y486320D01*
X1303333D01*
X1301049Y488604D01*
X1295028D01*
X1294170Y489462D01*
X1288830D01*
X1281853Y496439D01*
X1280595D01*
G01X1314476Y619501D02*
X1314713Y619738D01*
X1381429D01*
X1383768Y617399D01*
X1387992D01*
X1391928Y613463D01*
Y604840D01*
X1400968Y595800D01*
X1409265D01*
X1411688Y593377D01*
X1426551D01*
X1436883Y603709D01*
Y616993D01*
X1439305Y619415D01*
X1461415D01*
X1465650Y623650D01*
X1545244D01*
X1545969Y622925D01*
X1546317D01*
X1551130Y618112D01*
X1569941D01*
X1574749Y613304D01*
X1582895D01*
X1585717Y616126D01*
X1595223D01*
X1601695Y622598D01*
X1690355D01*
X1696544Y616409D01*
Y614255D01*
X1702294Y608505D01*
X1711419D01*
X1715297Y612383D01*
X1755847D01*
X1755848Y612384D01*
X1756470D01*
X1756471Y612383D01*
X1758328D01*
X1767976Y602735D01*
Y597068D01*
X1767228Y596320D01*
Y585600D01*
X1760048Y578420D01*
Y570952D01*
X1764000Y567000D01*
Y554986D01*
X1767053Y551933D01*
Y535987D01*
X1762089Y531023D01*
X1752592D01*
X1733479Y511910D01*
X1731356D01*
X1724016Y504570D01*
X1723703D01*
X1723699Y504566D01*
X1723683D01*
X1722817Y503700D01*
X1717534D01*
X1707569Y493735D01*
X1684841D01*
X1680747Y489641D01*
Y484698D01*
X1680698D01*
X1678500Y482500D01*
Y478575D01*
X1675283Y475358D01*
Y460355D01*
X1674465Y459537D01*
Y457479D01*
X1675744Y456200D01*
G01X1676041Y458884D02*
Y475052D01*
X1679494Y478505D01*
Y482223D01*
X1681499Y484228D01*
Y489329D01*
X1685153Y492983D01*
X1707881D01*
X1714098Y499200D01*
X1719381D01*
X1723995Y503814D01*
X1724011D01*
X1724015Y503818D01*
X1724328D01*
X1731668Y511158D01*
X1734074D01*
X1752994Y530078D01*
X1762208D01*
X1768005Y535875D01*
Y552328D01*
X1765000Y555333D01*
Y567100D01*
X1760800Y571300D01*
Y577820D01*
X1767980Y585000D01*
Y595568D01*
X1767989D01*
X1768728Y596307D01*
Y603047D01*
X1758640Y613135D01*
X1756783D01*
X1756782Y613136D01*
X1755536D01*
X1755535Y613135D01*
X1714575D01*
X1710897Y609457D01*
X1702751D01*
X1697496Y614712D01*
Y616804D01*
X1690750Y623550D01*
X1601300D01*
X1594828Y617078D01*
X1585322D01*
X1582500Y614256D01*
X1575144D01*
X1570336Y619064D01*
X1551640D01*
X1546925Y623779D01*
X1546179D01*
X1545556Y624402D01*
X1465055D01*
X1461020Y620367D01*
X1438758D01*
X1435858Y617467D01*
Y605358D01*
X1434500Y604000D01*
Y602390D01*
X1426239Y594129D01*
X1412000D01*
X1409529Y596600D01*
X1401232D01*
X1392680Y605152D01*
Y614311D01*
X1388517Y618474D01*
X1384192D01*
X1381903Y620763D01*
X1315443D01*
X1315129Y621077D01*
X1313452D01*
X1311876Y619501D01*
G01X1362000Y209300D02*
X1362620Y209920D01*
Y243313D01*
X1373003Y253696D01*
Y270897D01*
X1359000Y284900D01*
G01X1356926Y209100D02*
Y242979D01*
X1361019Y247072D01*
Y275881D01*
X1352400Y284500D01*
Y285000D01*
G01X1359500Y209200D02*
Y229670D01*
X1360900Y231070D01*
Y244546D01*
X1370974Y254620D01*
Y269826D01*
X1355800Y285000D01*
G01X1394881Y226997D02*
Y223748D01*
X1401091Y217538D01*
X1401761D01*
X1402870Y216429D01*
Y207918D01*
G01X1403400Y204766D02*
X1406953Y208319D01*
Y220539D01*
X1408057Y221643D01*
Y223427D01*
X1410175Y225545D01*
Y239973D01*
X1409512Y240636D01*
Y243648D01*
X1408546Y248193D01*
X1406625Y250114D01*
Y254872D01*
X1400550Y260951D01*
Y282747D01*
X1400516Y282781D01*
Y286726D01*
X1405000Y291210D01*
Y297571D01*
X1401261Y301310D01*
Y313531D01*
X1404730Y317000D01*
Y326475D01*
X1410190Y331935D01*
Y334594D01*
X1408348Y336436D01*
G01X1396470Y330014D02*
X1395700Y329244D01*
Y329060D01*
X1388000Y321360D01*
Y283910D01*
X1395942Y275968D01*
Y262864D01*
X1395941Y262863D01*
Y258493D01*
X1401806Y252628D01*
Y245370D01*
X1403352Y243824D01*
Y231222D01*
X1401565Y229435D01*
G01X1402400Y223600D02*
Y226270D01*
X1405656Y229526D01*
Y244780D01*
X1404110Y246326D01*
Y253590D01*
X1398245Y259457D01*
Y261907D01*
X1398246Y261908D01*
Y276924D01*
X1390319Y284851D01*
Y311319D01*
X1391700Y312700D01*
X1393555D01*
X1395334Y314479D01*
Y320831D01*
X1401552Y327049D01*
Y333058D01*
X1408376Y339882D01*
G01X1410489Y337988D02*
X1410512Y338011D01*
Y340392D01*
X1409108Y341796D01*
X1402636D01*
X1394554Y333714D01*
Y329802D01*
X1386524Y321772D01*
Y315531D01*
X1383193Y312200D01*
X1380300D01*
X1378772Y310672D01*
Y291313D01*
X1394790Y275295D01*
Y263342D01*
X1394789Y263341D01*
Y257416D01*
X1399852Y252353D01*
G01X1392400Y330800D02*
Y329500D01*
X1385162Y322262D01*
X1380174D01*
X1377466Y319554D01*
Y290848D01*
X1393538Y274776D01*
Y263861D01*
X1393537Y263860D01*
Y255734D01*
X1395502Y253769D01*
X1400554Y248715D01*
Y244851D01*
X1402100Y243305D01*
Y232200D01*
X1398600Y228700D01*
G01X1399600Y223600D02*
Y225100D01*
X1404504Y230004D01*
Y244302D01*
X1402958Y245848D01*
Y253106D01*
X1397093Y258971D01*
Y262385D01*
X1397094Y262386D01*
Y276446D01*
X1389166Y284374D01*
Y311796D01*
X1391223Y313853D01*
X1393078D01*
X1394182Y314957D01*
Y321587D01*
X1400400Y327805D01*
Y335400D01*
G01X1408250Y333000D02*
X1404912D01*
X1402800Y330888D01*
Y326668D01*
X1402704Y326572D01*
Y326571D01*
X1396486Y320353D01*
Y314848D01*
X1400000Y311334D01*
Y295600D01*
X1395300Y290900D01*
Y281500D01*
X1399398Y277402D01*
Y261430D01*
X1399397Y261429D01*
Y260474D01*
X1405340Y254526D01*
Y247586D01*
X1407274Y245652D01*
G01X1363700Y321600D02*
X1364800Y322700D01*
Y324700D01*
X1361512Y327988D01*
X1357547D01*
X1352502Y333033D01*
Y392384D01*
X1347293Y397593D01*
Y407607D01*
X1362398Y422712D01*
Y454657D01*
X1363725Y455984D01*
X1367006D01*
X1367082Y456060D01*
X1381540D01*
X1385100Y452500D01*
G01X1367200Y321600D02*
X1366000Y322800D01*
Y325000D01*
X1362260Y328740D01*
X1358142D01*
X1353254Y333628D01*
Y392696D01*
X1348045Y397905D01*
Y407295D01*
X1363150Y422400D01*
Y454345D01*
X1364037Y455232D01*
X1367318D01*
X1367394Y455308D01*
X1381228D01*
X1382783Y453752D01*
Y449817D01*
X1385100Y447500D01*
G01X1375100D02*
X1373000Y445400D01*
Y441352D01*
X1373852Y440500D01*
X1389000D01*
X1391748Y437752D01*
X1404977D01*
X1408225Y441000D01*
G01X1370100Y452500D02*
X1372600D01*
X1377200Y447900D01*
Y446300D01*
X1378952Y444548D01*
X1396612D01*
X1399282Y447218D01*
X1405282D01*
X1411752Y440748D01*
X1412484D01*
G01X1375100Y452500D02*
Y451064D01*
X1377952Y448212D01*
Y446612D01*
X1379264Y445300D01*
X1396300D01*
X1398970Y447970D01*
X1405594D01*
X1410019Y443545D01*
X1412375D01*
G01X1370100Y447500D02*
X1372248Y445352D01*
Y441040D01*
X1373540Y439748D01*
X1388688D01*
X1391436Y437000D01*
X1405565D01*
X1407065Y438500D01*
X1407958D01*
X1408225Y438233D01*
G01X1452728Y243306D02*
X1453500Y242534D01*
Y213600D01*
X1446016Y206116D01*
Y204497D01*
X1446609Y203904D01*
X1448764D01*
X1448914Y204054D01*
X1450346D01*
X1458856Y195544D01*
Y192430D01*
X1458569Y192143D01*
G01X1488900Y172576D02*
X1487736Y171412D01*
X1476735D01*
X1475767Y172380D01*
Y175652D01*
X1468941Y182478D01*
Y184670D01*
X1464416Y189195D01*
Y202385D01*
X1455361Y211440D01*
Y244891D01*
X1453636Y246616D01*
X1445384D01*
X1439700Y252300D01*
Y253100D01*
G01X1438500Y255400D02*
X1440001D01*
X1441276Y254125D01*
Y251973D01*
X1445855Y247394D01*
X1453922D01*
X1456113Y245203D01*
Y212278D01*
X1465169Y203222D01*
Y189506D01*
X1469693Y184982D01*
Y182790D01*
X1477388Y175095D01*
Y172988D01*
G01X1447999Y205645D02*
X1451287D01*
X1463664Y193268D01*
Y188883D01*
X1468051Y184496D01*
Y179558D01*
X1473888Y173721D01*
G01X1452200Y254500D02*
Y259300D01*
X1450086Y261414D01*
Y271050D01*
X1449212Y271924D01*
X1448203D01*
X1447133Y272994D01*
Y289960D01*
X1450073Y292900D01*
Y302701D01*
X1451000Y303628D01*
X1452362D01*
X1453223Y304489D01*
Y312006D01*
X1452362Y312867D01*
X1450296D01*
X1449711Y313452D01*
X1449697D01*
X1448603Y314546D01*
G01X1492597Y172636D02*
X1490933Y174300D01*
X1487664D01*
X1484537Y177427D01*
X1476120D01*
X1470550Y182997D01*
Y185376D01*
X1465921Y190005D01*
Y222235D01*
X1459913Y228243D01*
Y243697D01*
X1455463Y248147D01*
X1449208D01*
X1449207Y248146D01*
X1446281D01*
X1442028Y252399D01*
Y254573D01*
X1438301Y258300D01*
X1437800D01*
G01X1461202Y305098D02*
X1462672Y303628D01*
Y272556D01*
X1463656Y271572D01*
Y268061D01*
X1462875Y267280D01*
X1460573D01*
X1459178Y265885D01*
Y263123D01*
X1464101Y258200D01*
X1465629D01*
X1467176Y256653D01*
Y254174D01*
X1468450Y252900D01*
G01X1466404Y245350D02*
Y246287D01*
X1464691Y248000D01*
X1460101D01*
X1457025Y251076D01*
X1452515D01*
X1452514Y251075D01*
X1451268D01*
X1444536Y257807D01*
Y262980D01*
X1440833Y266683D01*
Y268984D01*
X1442303Y270454D01*
G01X1464700Y256100D02*
Y256412D01*
X1458338Y262774D01*
Y266564D01*
X1460167Y268393D01*
X1461569D01*
X1462770Y269594D01*
Y271009D01*
X1461909Y271870D01*
X1460856D01*
X1459600Y273126D01*
Y308778D01*
X1458451Y309927D01*
X1457443D01*
X1456400Y310970D01*
Y313048D01*
X1454902Y314546D01*
G01Y311397D02*
X1456372Y309927D01*
Y273204D01*
X1457704Y271872D01*
X1458711D01*
X1459572Y271011D01*
Y269518D01*
X1457449Y267395D01*
Y262599D01*
X1461128Y258920D01*
Y253442D01*
X1461676Y252894D01*
X1464413D01*
X1465063Y253544D01*
G01X1470556Y256900D02*
Y260744D01*
X1468016Y263284D01*
X1465084D01*
X1464090Y264278D01*
Y265983D01*
X1465561Y267454D01*
Y269775D01*
X1466684Y270898D01*
Y318255D01*
X1463610Y321329D01*
G01X1471604Y246287D02*
X1468391Y249500D01*
X1465319D01*
X1465315Y249504D01*
X1460797D01*
X1457721Y252580D01*
X1451891D01*
X1450624Y253847D01*
Y259416D01*
X1446924Y263116D01*
Y271145D01*
X1445454Y272615D01*
Y273603D01*
G01X1464351Y301948D02*
X1465894Y300405D01*
Y271799D01*
X1464662Y270567D01*
Y267848D01*
X1462984Y266170D01*
X1460791D01*
X1459930Y265309D01*
Y264091D01*
X1465021Y259000D01*
X1465893D01*
X1468228Y256665D01*
Y255850D01*
X1469506Y254572D01*
X1471603D01*
X1472640Y253535D01*
Y250910D01*
X1482375Y241175D01*
Y238879D01*
X1493593Y227661D01*
Y219058D01*
X1493205Y218670D01*
Y201092D01*
X1493712Y200585D01*
Y197399D01*
X1493711Y197398D01*
Y196776D01*
X1493712Y196775D01*
Y182893D01*
X1498440Y178165D01*
Y174351D01*
X1491399Y167310D01*
X1489892D01*
X1485804Y163222D01*
Y156806D01*
X1492476Y150134D01*
Y139789D01*
X1497786Y134479D01*
Y132089D01*
X1499912Y129963D01*
X1501800D01*
X1503931Y127832D01*
Y106237D01*
X1509917Y100251D01*
X1512354D01*
X1516870Y95735D01*
Y90653D01*
X1516150Y89933D01*
Y84695D01*
X1515477Y84022D01*
Y77960D01*
X1517269Y76168D01*
X1521505D01*
X1523073Y77736D01*
Y81437D01*
X1525740Y84104D01*
X1526312D01*
X1526732Y84524D01*
X1538967D01*
X1545721Y77770D01*
X1554280D01*
X1559270Y72780D01*
Y72779D01*
X1561382Y70667D01*
X1568029D01*
X1569960Y68736D01*
X1574864D01*
X1576456Y67144D01*
X1580427Y66300D01*
X1582100D01*
X1584748Y68948D01*
Y70840D01*
G01X1491265Y226492D02*
X1482257Y235500D01*
X1473499D01*
X1464626Y244373D01*
Y245660D01*
X1463286Y247000D01*
X1460037D01*
X1456986Y250051D01*
X1448430D01*
X1448403Y250024D01*
X1446373D01*
X1443784Y252613D01*
Y262545D01*
X1440113Y266216D01*
Y266339D01*
X1440081Y266371D01*
Y269296D01*
X1440113Y269328D01*
Y289599D01*
X1441500Y290986D01*
X1443086D01*
X1443880Y291780D01*
Y309821D01*
X1442304Y311397D01*
G01X1498810Y108290D02*
X1500176Y106924D01*
X1502256D01*
X1503179Y107847D01*
Y127520D01*
X1501488Y129211D01*
X1499600D01*
X1497034Y131777D01*
Y134167D01*
X1484171Y147030D01*
Y165482D01*
X1488751Y170062D01*
X1492853D01*
X1495000Y172209D01*
Y175895D01*
X1496359Y177254D01*
Y178560D01*
X1496264Y178655D01*
Y178681D01*
X1490560Y184385D01*
Y214602D01*
X1489572Y215590D01*
Y222226D01*
X1492841Y225495D01*
Y227349D01*
X1481622Y238568D01*
Y239190D01*
X1481623Y239191D01*
Y240043D01*
X1478016Y243650D01*
X1474050D01*
X1473300Y244400D01*
Y247200D01*
X1472600Y247900D01*
X1471055D01*
X1468703Y250252D01*
X1465631D01*
X1465627Y250256D01*
X1461197D01*
X1457176Y254277D01*
Y260744D01*
X1455926Y261994D01*
Y266788D01*
X1453223Y269491D01*
Y271063D01*
X1452362Y271924D01*
X1451353D01*
X1450283Y272994D01*
Y291193D01*
X1453432Y294342D01*
Y297328D01*
X1454902Y298798D01*
G01X1483457Y244568D02*
X1481957D01*
X1476500Y250025D01*
Y250026D01*
X1476096Y250430D01*
Y252393D01*
X1474237Y254252D01*
X1472987D01*
X1471915Y255324D01*
X1469818D01*
X1468980Y256162D01*
Y261256D01*
X1467704Y262532D01*
X1463568D01*
X1461400Y264700D01*
G01X1469004Y246287D02*
X1466543Y248748D01*
X1465007D01*
X1465003Y248752D01*
X1460449D01*
X1457373Y251828D01*
X1452203D01*
X1452202Y251827D01*
X1451580D01*
X1445288Y258119D01*
Y263688D01*
X1443984Y264992D01*
Y289960D01*
X1444845Y290821D01*
X1446063D01*
X1447107Y291865D01*
Y297302D01*
X1448603Y298798D01*
G01X1451753Y289351D02*
X1453300Y287804D01*
Y273126D01*
X1454502Y271924D01*
X1455511D01*
X1456600Y270835D01*
Y269800D01*
X1456678Y269722D01*
Y262306D01*
X1460376Y258608D01*
Y253100D01*
X1462224Y251252D01*
X1469356D01*
X1470950Y252846D01*
G01X1445454Y301948D02*
X1447124Y303618D01*
Y312813D01*
X1445998Y313939D01*
Y315667D01*
X1447124Y316793D01*
Y318525D01*
X1449190Y320591D01*
X1450571D01*
X1459980Y330000D01*
X1469502D01*
X1470276Y330774D01*
G01X1452188Y487223D02*
X1452305D01*
Y483163D01*
X1456719Y478749D01*
X1458683D01*
X1472700Y464732D01*
Y457836D01*
X1477600Y452936D01*
Y451662D01*
X1477601Y451661D01*
Y422678D01*
X1479191Y421088D01*
X1486732D01*
X1489855Y417965D01*
Y416535D01*
X1491045Y415345D01*
Y413915D01*
X1492995Y411965D01*
Y410535D01*
X1494945Y408585D01*
Y407283D01*
X1493600Y405938D01*
Y405532D01*
X1492995Y404927D01*
Y403903D01*
X1492076Y402984D01*
X1492074D01*
X1491853Y402763D01*
X1486209D01*
X1485614Y403358D01*
X1482852D01*
X1479057Y399563D01*
Y394376D01*
X1473462Y388781D01*
X1473144D01*
X1473143Y388780D01*
X1470469D01*
X1467989Y386300D01*
Y379821D01*
X1470418Y377392D01*
Y374200D01*
X1466918Y370700D01*
X1462400D01*
X1447924Y356224D01*
Y354163D01*
X1450938Y351149D01*
X1452385D01*
X1457438Y346096D01*
X1460176D01*
X1469731Y336541D01*
Y333605D01*
X1471852Y331484D01*
Y330121D01*
X1470731Y329000D01*
X1460978D01*
X1450146Y318168D01*
Y317160D01*
X1449212Y316226D01*
X1448204D01*
X1447133Y315155D01*
Y313937D01*
X1448203Y312867D01*
X1449212D01*
X1450073Y312006D01*
Y304489D01*
X1449212Y303628D01*
X1448204D01*
X1447133Y302557D01*
Y300477D01*
X1445454Y298798D01*
G01X1486574Y267127D02*
Y268695D01*
X1486863Y268984D01*
X1487006D01*
X1487867Y269845D01*
Y271063D01*
X1487006Y271924D01*
X1485997D01*
X1484717Y273204D01*
Y274212D01*
X1483856Y275073D01*
X1482848D01*
X1481777Y276144D01*
Y277153D01*
X1477558Y281372D01*
X1476549D01*
X1475478Y282443D01*
Y289960D01*
X1478418Y292900D01*
Y296258D01*
X1477443Y297233D01*
X1476434D01*
X1475478Y298189D01*
Y299407D01*
X1476339Y300268D01*
X1483646D01*
X1484717Y301339D01*
Y302557D01*
X1483856Y303418D01*
X1482848D01*
X1481777Y304489D01*
Y315007D01*
X1480922Y315862D01*
Y319722D01*
X1477348Y323296D01*
Y341853D01*
X1470057Y349144D01*
X1458835D01*
X1456228Y351751D01*
Y354456D01*
X1455870Y354814D01*
Y358341D01*
X1457576Y360047D01*
Y363804D01*
X1463217Y369445D01*
X1466727D01*
X1471450Y374168D01*
Y377448D01*
X1471069Y377829D01*
Y377830D01*
X1468928Y379971D01*
Y386175D01*
X1470653Y387900D01*
X1473962D01*
G01X1495409Y403740D02*
Y404063D01*
X1495697Y404351D01*
Y409465D01*
X1496895Y410663D01*
Y411965D01*
X1494945Y413915D01*
Y415728D01*
X1492995Y417678D01*
Y418725D01*
X1491805Y419915D01*
Y422105D01*
X1493302Y423602D01*
Y425920D01*
X1494945Y427563D01*
Y431153D01*
X1493755Y432343D01*
Y434719D01*
X1494945Y435909D01*
Y437437D01*
X1493046Y439336D01*
Y441310D01*
X1491514Y442842D01*
Y444616D01*
X1487905Y448225D01*
Y451532D01*
X1489095Y452722D01*
Y454337D01*
X1485038Y458394D01*
Y461463D01*
X1486669Y463094D01*
Y469248D01*
X1486670Y469249D01*
Y470551D01*
X1486669Y470552D01*
Y470773D01*
X1485004Y472438D01*
Y478280D01*
X1484752Y478532D01*
Y478533D01*
X1483163Y480122D01*
X1475007D01*
X1467808Y487321D01*
Y493211D01*
X1464522Y496497D01*
Y508841D01*
X1464553Y508872D01*
G01X1453900Y353350D02*
Y351951D01*
X1458251Y347600D01*
X1460800D01*
X1464150Y344250D01*
X1471553D01*
X1474692Y341111D01*
Y322074D01*
X1476350Y320416D01*
Y314074D01*
X1478418Y312006D01*
Y309717D01*
X1476948Y308247D01*
G01X1470649Y301948D02*
Y302983D01*
X1472200Y304534D01*
Y305579D01*
X1473398Y306777D01*
X1474407D01*
X1475268Y307638D01*
Y320434D01*
X1473940Y321762D01*
Y330460D01*
X1470483Y333917D01*
Y336853D01*
X1460488Y346848D01*
X1457750D01*
X1452050Y352548D01*
Y355151D01*
X1451453Y355748D01*
Y358689D01*
X1453464Y360700D01*
X1456000D01*
G01X1483247Y314546D02*
Y314966D01*
X1481679Y316534D01*
Y320279D01*
X1478250Y323708D01*
Y342249D01*
X1470603Y349896D01*
X1459147D01*
X1456980Y352063D01*
Y354976D01*
X1456622Y355334D01*
Y358029D01*
X1458328Y359735D01*
Y362187D01*
X1462434Y366293D01*
X1464523D01*
X1466417Y368187D01*
X1471387D01*
X1475300Y372100D01*
Y377230D01*
X1474650Y377880D01*
X1472082D01*
X1471821Y378141D01*
Y378142D01*
X1469864Y380099D01*
Y385303D01*
X1471666Y387105D01*
X1477605D01*
X1484600Y394100D01*
G01X1483247Y311397D02*
Y312362D01*
X1484717Y313832D01*
Y318453D01*
X1479002Y324168D01*
Y342821D01*
X1471175Y350648D01*
X1459459D01*
X1457848Y352259D01*
Y355273D01*
X1457374Y355747D01*
Y357374D01*
X1459160Y359160D01*
Y361630D01*
X1461370Y363840D01*
X1464160D01*
X1466620Y361380D01*
X1469060D01*
X1471210Y363530D01*
Y364610D01*
X1478290Y371690D01*
Y379190D01*
X1475260Y382220D01*
X1472322D01*
X1471370Y383172D01*
Y384681D01*
X1472289Y385600D01*
X1486630D01*
X1486874Y385844D01*
X1489886D01*
X1491805Y387763D01*
Y388305D01*
X1493755Y390255D01*
Y391685D01*
X1495428Y393358D01*
Y394788D01*
X1497655Y397015D01*
Y398926D01*
X1499605Y400876D01*
Y402713D01*
X1500795Y403903D01*
Y405965D01*
X1499605Y407155D01*
Y408585D01*
X1501759Y410739D01*
X1506224D01*
X1508613Y408350D01*
X1509350D01*
X1511926Y405774D01*
G01X1531330Y411810D02*
X1539839D01*
X1540049Y412020D01*
X1546290D01*
X1548720Y414450D01*
Y419882D01*
X1549325Y420487D01*
Y421777D01*
X1551578Y424030D01*
Y425852D01*
X1550280Y427150D01*
Y429410D01*
X1552060Y431190D01*
Y432270D01*
X1553950Y434160D01*
Y437250D01*
X1556000Y439300D01*
Y441550D01*
X1557345Y442895D01*
Y444855D01*
X1556100Y446100D01*
Y454850D01*
X1557345Y456095D01*
Y457755D01*
X1556155Y458945D01*
G01X1574510Y461981D02*
X1580396Y467867D01*
X1607883D01*
X1611250Y464500D01*
X1613718D01*
X1615061Y463157D01*
G01X1460400Y353000D02*
X1462100D01*
X1462900Y352200D01*
X1471751D01*
X1480506Y343445D01*
Y324832D01*
X1483076Y322262D01*
X1487088D01*
X1491016Y318334D01*
Y308963D01*
X1491965Y308014D01*
Y303856D01*
X1492891Y302930D01*
X1493349D01*
X1495300Y300979D01*
Y297300D01*
G01X1493290Y287984D02*
X1491149Y290125D01*
Y302424D01*
X1489275Y304298D01*
Y305904D01*
X1488076Y307103D01*
Y318543D01*
X1485109Y321510D01*
X1482764D01*
X1479754Y324520D01*
Y343133D01*
X1471487Y351400D01*
X1459771D01*
X1458824Y352347D01*
Y354659D01*
X1459111Y354946D01*
Y356353D01*
G01X1453251Y356676D02*
Y356228D01*
X1455476Y354003D01*
Y351439D01*
X1458523Y348392D01*
X1461076D01*
X1462042Y347426D01*
X1470505D01*
X1476596Y341335D01*
Y322907D01*
X1479994Y319509D01*
Y318291D01*
X1478378Y316675D01*
Y313338D01*
X1480098Y311618D01*
Y311397D01*
G01X1431690Y521530D02*
X1443278D01*
X1462266Y502542D01*
Y495561D01*
X1465346Y492481D01*
Y484554D01*
X1479650Y470250D01*
Y461950D01*
X1483225Y458375D01*
X1483375D01*
G01X1467597Y363000D02*
X1476360Y371771D01*
Y377670D01*
X1475210Y378820D01*
X1472269D01*
X1470617Y380472D01*
Y384992D01*
X1471977Y386352D01*
X1477916D01*
X1478354Y386790D01*
X1479100D01*
X1481200Y388890D01*
X1482990D01*
X1483217Y388663D01*
X1483297D01*
X1484430Y387530D01*
X1487423D01*
X1487953Y388060D01*
G01X1496488Y402539D02*
X1497074Y403125D01*
Y405179D01*
X1498853Y406958D01*
Y408262D01*
X1497655Y409460D01*
Y412853D01*
X1498845Y414043D01*
Y417334D01*
X1495630Y420549D01*
Y422918D01*
X1496895Y424183D01*
Y426372D01*
X1495705Y427562D01*
Y431565D01*
X1496895Y432755D01*
Y434945D01*
X1495705Y436135D01*
Y438325D01*
X1496895Y439515D01*
Y441206D01*
X1495110Y442991D01*
Y444494D01*
X1492995Y446609D01*
Y448465D01*
X1491805Y449655D01*
Y451085D01*
X1489855Y453035D01*
Y454715D01*
X1491045Y455905D01*
Y457717D01*
X1489886Y458876D01*
X1486874D01*
X1485955Y459795D01*
Y461097D01*
X1487606Y462748D01*
Y471664D01*
X1485955Y473315D01*
Y479979D01*
X1482556Y483378D01*
X1476193D01*
X1471561Y488010D01*
X1471537D01*
X1470055Y489492D01*
Y489493D01*
X1468686Y490862D01*
Y493742D01*
X1466430Y495998D01*
Y512708D01*
X1459490Y519648D01*
X1458488D01*
X1455739Y522397D01*
Y542510D01*
X1458701Y545472D01*
Y554520D01*
X1465070Y560889D01*
Y563989D01*
X1464124Y564935D01*
Y571194D01*
X1465160Y572230D01*
X1466431D01*
X1468649Y570012D01*
G01X1436358Y525142D02*
X1440730D01*
X1463018Y502854D01*
Y495873D01*
X1466099Y492792D01*
Y485901D01*
X1474200Y477800D01*
X1482200D01*
G01X1456602Y485864D02*
X1458166Y487428D01*
Y490184D01*
X1453613Y494737D01*
Y495724D01*
X1442837Y506500D01*
X1414900D01*
X1408649Y512751D01*
X1407884D01*
G01X1465700Y570500D02*
X1465840Y570360D01*
Y559240D01*
X1461000Y554400D01*
Y544000D01*
X1456781Y539781D01*
Y522419D01*
X1458800Y520400D01*
X1460400D01*
X1467190Y513610D01*
Y496302D01*
X1469438Y494054D01*
Y491174D01*
X1470807Y489805D01*
Y489804D01*
X1471849Y488762D01*
X1471938D01*
X1476170Y484530D01*
X1483721D01*
X1487525Y480726D01*
G01X1451150Y569900D02*
X1452298Y571048D01*
X1457824D01*
X1467459Y580683D01*
X1499376D01*
X1506212Y587519D01*
X1539616D01*
X1540495Y588398D01*
X1549180D01*
X1550990Y586588D01*
G01X1451150Y573200D02*
X1452250Y572100D01*
X1457529D01*
X1466864Y581435D01*
X1499064D01*
X1506100Y588471D01*
X1539221D01*
X1540100Y589350D01*
X1552266D01*
X1554358Y587258D01*
G01X1597504Y-17346D02*
Y-18496D01*
X1596658Y-19342D01*
X1486342D01*
X1482000Y-15000D01*
G01X1519580Y81313D02*
Y81702D01*
X1524638Y86760D01*
X1525210D01*
X1526414Y87964D01*
X1532147D01*
X1533797Y89614D01*
Y112701D01*
X1528340Y118158D01*
Y121660D01*
X1526728Y123272D01*
Y124168D01*
G01X1519599Y86117D02*
X1520014Y86532D01*
Y113178D01*
X1518224Y114968D01*
Y127976D01*
X1516549Y129651D01*
Y148195D01*
X1511560Y153184D01*
Y160078D01*
X1514276Y162794D01*
Y190998D01*
X1513484Y191790D01*
Y193096D01*
X1514276Y193888D01*
Y201150D01*
X1510949Y204477D01*
Y212820D01*
X1515476Y217347D01*
Y218884D01*
X1513008Y221352D01*
Y221353D01*
X1511218Y223143D01*
Y235924D01*
X1508187Y238955D01*
Y253504D01*
X1509305Y254622D01*
Y257061D01*
X1509148Y257218D01*
Y257222D01*
X1507624Y258746D01*
Y260875D01*
X1504034Y264465D01*
Y269256D01*
X1501808Y271482D01*
Y277114D01*
X1503161Y278467D01*
Y281353D01*
X1498217Y286297D01*
Y289399D01*
X1496900Y290716D01*
Y293900D01*
G01X1476948Y295649D02*
X1472328Y291029D01*
Y279293D01*
X1473398Y278223D01*
X1474407D01*
X1475478Y277152D01*
Y272994D01*
X1476472Y272000D01*
X1477481D01*
X1478418Y271063D01*
Y269845D01*
X1477568Y268995D01*
Y266462D01*
X1481672Y262358D01*
Y252599D01*
X1484705Y249566D01*
X1487510D01*
X1489385Y247691D01*
Y246009D01*
X1490064Y245330D01*
Y245028D01*
X1490063Y245027D01*
Y234446D01*
X1495849Y228660D01*
Y218122D01*
X1495461Y217734D01*
Y202028D01*
X1495968Y201521D01*
Y183829D01*
X1500696Y179101D01*
Y175361D01*
X1500697Y175360D01*
Y174738D01*
X1500698Y174737D01*
Y173491D01*
X1500696Y173489D01*
Y173415D01*
X1492334Y165053D01*
X1492260D01*
X1490872Y163665D01*
Y161470D01*
X1491594Y160748D01*
Y158358D01*
X1493920Y156032D01*
X1497034D01*
X1497726Y155340D01*
Y147201D01*
X1496500Y145975D01*
Y138436D01*
X1499698Y135238D01*
X1502190D01*
X1504117Y133311D01*
Y128710D01*
X1504683Y128144D01*
Y106549D01*
X1510229Y101003D01*
X1512042D01*
X1512043Y101004D01*
X1512665D01*
X1517622Y96047D01*
Y90341D01*
X1516971Y89690D01*
Y84452D01*
X1516229Y83710D01*
Y79717D01*
X1517162Y78784D01*
G01X1520314Y78880D02*
X1520531D01*
X1521355Y79704D01*
Y81847D01*
X1525116Y85608D01*
X1525688D01*
X1526108Y86028D01*
X1535496D01*
X1538260Y88792D01*
Y99185D01*
X1542819Y103744D01*
Y105911D01*
X1542997Y106089D01*
Y107395D01*
X1530851Y119541D01*
Y122249D01*
X1530000Y123100D01*
Y124756D01*
X1536681Y131437D01*
Y141504D01*
X1543856Y148679D01*
Y158716D01*
X1542012Y160560D01*
Y163332D01*
X1539164Y166180D01*
Y178030D01*
X1537716Y179478D01*
Y186361D01*
X1538680Y187325D01*
Y205025D01*
X1541415Y207760D01*
Y235096D01*
X1541114Y235397D01*
Y238821D01*
X1538245Y241690D01*
Y253640D01*
X1538246Y253641D01*
Y256175D01*
X1531924Y262497D01*
Y274253D01*
X1533528Y275857D01*
Y280020D01*
X1527899Y285649D01*
Y291636D01*
X1528476Y292213D01*
Y297105D01*
X1520340Y305241D01*
Y314877D01*
X1521540Y316077D01*
Y320464D01*
X1522421Y321345D01*
Y321967D01*
X1522420Y321968D01*
Y328104D01*
X1514236Y336288D01*
X1512445D01*
X1509100Y339633D01*
Y342059D01*
X1506079Y345080D01*
X1502300D01*
X1499847Y347533D01*
Y353304D01*
X1498246Y354905D01*
G01X1480098Y270454D02*
X1478628Y268984D01*
Y266695D01*
X1482424Y262899D01*
Y256078D01*
X1483500Y255002D01*
X1485003D01*
X1486110Y253895D01*
Y252568D01*
X1490438Y248240D01*
Y246191D01*
X1493625Y243004D01*
Y232493D01*
X1500261Y225857D01*
Y224062D01*
X1499599Y223400D01*
Y204088D01*
X1496720Y201209D01*
Y184141D01*
X1501497Y179364D01*
Y173226D01*
X1501448Y173177D01*
Y173103D01*
X1492621Y164276D01*
X1492547D01*
X1491624Y163353D01*
Y161782D01*
X1492346Y161060D01*
Y158670D01*
X1493997Y157019D01*
X1497370D01*
X1498478Y155911D01*
Y146889D01*
X1497491Y145902D01*
Y138509D01*
X1500010Y135990D01*
X1502502D01*
X1504869Y133623D01*
Y129022D01*
X1505435Y128456D01*
Y106861D01*
X1510491Y101805D01*
X1513020D01*
X1518374Y96451D01*
Y90029D01*
X1517723Y89378D01*
Y84140D01*
X1516981Y83398D01*
Y81194D01*
X1518738Y79437D01*
Y77412D01*
X1519090Y77060D01*
X1520998D01*
X1522108Y78170D01*
Y81536D01*
X1525428Y84856D01*
X1526000D01*
X1526420Y85276D01*
X1539279D01*
X1545957Y78598D01*
X1554661D01*
X1561780Y71479D01*
X1568281D01*
X1570272Y69488D01*
X1575176D01*
X1576830Y67834D01*
X1580507Y67052D01*
X1581751D01*
X1583172Y68473D01*
Y71493D01*
X1584554Y72875D01*
X1590657D01*
X1592715Y70817D01*
G01X1485210Y134837D02*
X1476994Y143053D01*
Y149606D01*
X1473354Y153246D01*
G01X1514600Y126650D02*
X1511550Y129700D01*
X1510841D01*
X1508877Y131664D01*
Y136923D01*
X1505299Y140501D01*
X1502498D01*
X1501500Y141499D01*
Y142749D01*
X1502813Y144062D01*
X1505645D01*
X1507500Y145917D01*
Y148500D01*
X1506000Y150000D01*
Y163000D01*
X1507025Y164025D01*
Y181636D01*
X1505111Y183550D01*
X1505113Y183552D01*
Y220997D01*
X1505773Y221657D01*
Y233297D01*
X1502728Y236342D01*
Y241738D01*
X1495951Y248515D01*
Y250526D01*
X1491623Y254854D01*
Y256340D01*
X1494034Y258751D01*
Y260293D01*
X1496030Y262289D01*
Y267665D01*
G01X1518376Y111499D02*
X1517072Y112803D01*
Y126628D01*
X1512796Y130904D01*
X1511595D01*
X1510029Y132470D01*
Y137971D01*
X1507656Y140344D01*
Y143662D01*
X1509206Y145212D01*
Y151497D01*
X1508704Y151999D01*
Y161487D01*
X1508729Y161512D01*
Y182753D01*
X1507341Y184141D01*
Y214317D01*
X1509400Y216376D01*
Y219165D01*
X1507599Y220964D01*
Y234128D01*
X1504579Y237148D01*
Y242435D01*
X1497896Y249118D01*
Y251396D01*
X1500963Y254463D01*
Y256464D01*
X1498452Y258975D01*
Y268669D01*
X1495075Y272046D01*
Y275100D01*
X1493775Y276400D01*
X1490900D01*
X1488076Y279224D01*
Y283991D01*
X1487335Y284732D01*
X1485788D01*
X1484927Y285593D01*
Y291060D01*
X1487867Y294000D01*
Y297328D01*
X1486397Y298798D01*
G01X1476948D02*
X1478598Y297148D01*
X1480678D01*
X1481568Y296258D01*
Y293045D01*
X1478628Y290105D01*
Y285593D01*
X1479699Y284522D01*
X1480707D01*
X1481660Y283569D01*
Y282560D01*
X1482638Y281582D01*
X1483646D01*
X1485200Y280028D01*
Y277943D01*
X1491768Y271375D01*
Y269533D01*
X1491767Y269532D01*
Y268594D01*
X1491127Y267954D01*
Y262731D01*
X1488679Y260283D01*
Y257009D01*
X1488678Y257008D01*
Y256054D01*
X1489318Y255414D01*
Y253899D01*
X1493647Y249570D01*
Y249471D01*
X1493646Y249470D01*
Y247560D01*
X1497381Y243825D01*
Y238429D01*
X1503469Y232341D01*
Y222731D01*
X1502807Y222069D01*
Y182593D01*
X1504721Y180679D01*
Y171523D01*
X1499367Y166169D01*
Y162182D01*
X1500573Y160976D01*
X1501689D01*
X1503294Y159371D01*
Y152612D01*
X1500182Y149500D01*
Y145818D01*
X1499196Y144832D01*
Y139767D01*
X1500766Y138197D01*
X1504043D01*
X1506573Y135667D01*
Y129729D01*
X1512252Y124050D01*
X1512897D01*
X1516120Y120827D01*
Y110880D01*
X1518438Y108562D01*
Y100926D01*
G01X1510184Y142614D02*
X1510910Y143340D01*
Y152204D01*
X1510408Y152706D01*
Y160780D01*
X1513013Y163385D01*
Y180880D01*
X1509045Y184848D01*
Y213610D01*
X1511105Y215670D01*
Y217082D01*
X1511104Y217083D01*
Y220283D01*
X1509303Y222084D01*
Y235145D01*
X1506283Y238165D01*
Y250676D01*
X1503444Y253515D01*
Y256394D01*
X1500156Y259682D01*
Y269376D01*
X1499152Y270380D01*
Y274912D01*
X1498658Y275406D01*
Y278887D01*
X1499681Y279910D01*
G01X1503466Y142486D02*
X1505133D01*
X1508252Y145605D01*
Y148188D01*
X1508253Y148189D01*
Y148811D01*
X1508251Y148813D01*
Y151105D01*
X1507752Y151604D01*
Y161882D01*
X1507777Y161907D01*
Y182358D01*
X1505948Y184187D01*
Y220733D01*
X1506547Y221332D01*
Y233833D01*
X1503627Y236753D01*
Y242040D01*
X1496944Y248723D01*
Y254728D01*
X1497410Y255194D01*
Y266966D01*
X1497500Y267056D01*
Y268274D01*
X1494000Y271774D01*
Y272750D01*
X1494323Y273073D01*
Y274375D01*
X1494000Y274698D01*
Y274723D01*
X1493523Y275200D01*
X1493498D01*
X1493404Y275294D01*
X1490206D01*
X1487089Y278411D01*
Y282360D01*
X1486397Y283052D01*
G01X1500643Y154819D02*
X1497538Y157924D01*
X1494286D01*
X1493363Y158847D01*
Y160544D01*
X1495051Y162232D01*
Y162283D01*
X1495050Y162284D01*
Y165327D01*
X1502249Y172526D01*
Y179676D01*
X1497472Y184453D01*
Y200897D01*
X1500351Y203776D01*
Y223088D01*
X1501013Y223750D01*
Y226169D01*
X1494586Y232596D01*
Y243107D01*
X1491190Y246503D01*
Y248552D01*
X1486862Y252880D01*
Y254395D01*
X1485669Y255588D01*
Y256210D01*
X1485670Y256211D01*
Y261620D01*
X1481568Y265722D01*
Y271063D01*
X1480707Y271924D01*
X1479698D01*
X1478628Y272994D01*
Y278222D01*
X1476948Y279902D01*
G01X1511660Y138510D02*
X1510887D01*
X1508608Y140789D01*
Y143267D01*
X1510158Y144817D01*
Y151892D01*
X1509656Y152394D01*
Y161092D01*
X1512261Y163697D01*
Y180568D01*
X1508293Y184536D01*
Y213922D01*
X1510353Y215982D01*
Y216770D01*
X1510352Y216771D01*
Y219667D01*
X1508551Y221468D01*
Y234523D01*
X1505531Y237543D01*
Y250364D01*
X1502692Y253203D01*
Y256082D01*
X1499404Y259370D01*
Y269064D01*
X1498400Y270068D01*
Y274600D01*
X1497400Y275600D01*
X1496400D01*
X1489700Y282300D01*
Y283691D01*
X1487189Y286202D01*
X1486397D01*
G01X1480098Y273603D02*
X1481701Y272000D01*
X1483780D01*
X1484927Y270853D01*
Y266695D01*
X1486422Y265200D01*
Y255899D01*
X1487614Y254707D01*
Y253192D01*
X1491942Y248864D01*
Y246853D01*
X1495340Y243455D01*
Y243446D01*
X1495339D01*
Y232907D01*
X1501765Y226481D01*
Y223438D01*
X1501103Y222776D01*
Y203464D01*
X1498224Y200585D01*
Y184765D01*
X1503017Y179972D01*
Y172230D01*
X1495803Y165016D01*
Y161147D01*
X1496926Y160024D01*
X1501294D01*
X1502342Y158976D01*
Y154342D01*
X1502219Y154219D01*
Y154166D01*
X1501296Y153243D01*
X1501243D01*
X1499230Y151230D01*
Y146577D01*
X1498244Y145591D01*
Y142792D01*
X1498243Y142791D01*
Y141047D01*
X1498244Y141046D01*
Y139372D01*
X1500371Y137245D01*
X1503648D01*
X1505621Y135272D01*
Y129334D01*
X1506187Y128768D01*
Y117263D01*
X1510850Y112600D01*
X1513130D01*
X1513879Y113349D01*
G01X1483247Y298798D02*
X1484717Y297328D01*
Y293300D01*
X1481777Y290360D01*
Y285593D01*
X1482638Y284732D01*
X1483646D01*
X1484927Y283451D01*
Y282442D01*
X1485951Y281418D01*
Y278305D01*
X1494267Y269989D01*
Y264241D01*
X1489831Y259805D01*
Y256531D01*
X1490471Y255891D01*
Y254376D01*
X1494799Y250048D01*
Y248037D01*
X1501576Y241260D01*
Y235864D01*
X1504621Y232819D01*
Y222135D01*
X1503961Y221475D01*
Y221381D01*
X1503959Y221379D01*
Y183071D01*
X1505873Y181157D01*
Y171045D01*
X1500519Y165691D01*
Y162660D01*
X1501051Y162128D01*
X1502167D01*
X1504446Y159849D01*
Y158733D01*
X1504500Y158679D01*
Y147488D01*
X1500348Y143336D01*
Y140245D01*
X1501244Y139349D01*
X1504521D01*
X1507725Y136145D01*
Y130625D01*
X1511300Y127050D01*
X1511800D01*
G01X1524900Y139100D02*
X1521005Y142995D01*
Y176329D01*
X1526142Y181466D01*
Y205757D01*
X1527166Y206781D01*
Y210446D01*
X1530285Y213565D01*
Y229701D01*
X1528883Y231103D01*
Y239118D01*
X1526904Y241097D01*
Y243995D01*
X1521956Y248943D01*
Y274020D01*
X1518585Y277391D01*
Y282679D01*
X1516298Y284966D01*
Y296586D01*
X1508468Y304418D01*
Y310556D01*
X1506754Y312270D01*
Y313970D01*
X1508460Y315676D01*
Y320939D01*
X1500400Y328999D01*
Y333000D01*
X1498600Y334800D01*
G01X1526310Y142190D02*
Y150140D01*
X1522727Y153723D01*
Y175183D01*
X1527844Y180300D01*
Y205052D01*
X1528868Y206076D01*
Y209741D01*
X1533511Y214384D01*
Y230289D01*
X1530585Y233215D01*
Y244641D01*
X1528017Y247209D01*
Y251545D01*
X1523658Y255904D01*
Y274725D01*
X1520287Y278096D01*
Y286713D01*
X1518102Y288898D01*
Y297189D01*
X1510205Y305088D01*
Y307991D01*
X1510206Y307992D01*
Y321600D01*
X1502350Y329456D01*
Y333500D01*
X1498910Y336940D01*
X1496964D01*
X1496400Y336376D01*
G01X1473798Y276753D02*
X1472328Y275283D01*
Y272994D01*
X1473322Y272000D01*
X1474331D01*
X1475268Y271063D01*
Y266597D01*
X1480827Y261038D01*
Y251802D01*
X1483976Y248653D01*
Y247633D01*
X1485533Y246076D01*
X1488254D01*
X1489311Y245019D01*
Y234071D01*
X1495097Y228285D01*
Y218434D01*
X1494709Y218046D01*
Y201716D01*
X1495216Y201209D01*
Y183517D01*
X1499944Y178789D01*
Y175049D01*
X1499945Y175048D01*
Y174426D01*
X1499946Y174425D01*
Y173803D01*
X1499944Y173801D01*
Y173727D01*
X1492022Y165805D01*
X1491948D01*
X1490119Y163976D01*
Y163354D01*
X1490120Y163353D01*
Y161158D01*
X1490842Y160436D01*
Y157522D01*
X1490237Y156917D01*
Y153437D01*
X1493074Y150600D01*
X1495848D01*
G01X1524000Y123300D02*
Y124985D01*
X1525454Y126439D01*
X1528981D01*
X1534285Y131743D01*
Y138625D01*
X1532912Y139998D01*
X1528727D01*
X1526095Y137366D01*
X1522534D01*
X1520253Y139647D01*
Y177705D01*
X1524638Y182090D01*
Y206485D01*
X1525661Y207508D01*
Y211069D01*
X1528131Y213539D01*
Y221861D01*
X1527019Y222973D01*
Y228073D01*
X1528131Y229185D01*
Y238270D01*
X1526144Y240257D01*
Y243691D01*
X1520899Y248936D01*
Y274001D01*
X1520223Y274677D01*
Y274689D01*
X1517081Y277831D01*
Y281919D01*
X1514658Y284342D01*
Y288035D01*
X1512865Y289828D01*
X1512378D01*
X1510305Y291901D01*
Y300893D01*
X1507673Y303525D01*
Y310210D01*
X1506002Y311881D01*
Y314282D01*
X1507708Y315988D01*
Y320583D01*
X1498896Y329395D01*
Y330388D01*
X1493414Y335870D01*
Y372564D01*
X1493755Y372905D01*
Y378165D01*
X1495705Y380115D01*
Y381545D01*
X1497088Y382928D01*
Y385246D01*
X1498845Y387003D01*
Y388433D01*
X1501555Y391143D01*
Y391685D01*
X1503505Y393635D01*
Y395065D01*
X1506645Y398205D01*
Y402310D01*
X1505075Y403880D01*
Y407934D01*
G01X1489475Y380894D02*
Y371906D01*
X1490560Y370821D01*
Y356970D01*
X1487900Y354310D01*
Y345570D01*
X1491510Y341960D01*
Y334898D01*
X1496780Y329628D01*
Y328620D01*
X1505530Y319870D01*
Y316759D01*
X1502689Y313918D01*
Y304770D01*
X1508175Y299284D01*
Y291303D01*
X1510324Y289154D01*
Y285602D01*
X1510724Y285202D01*
Y279194D01*
X1512446Y277472D01*
X1513730D01*
X1518953Y272249D01*
Y248095D01*
X1520908Y246140D01*
Y241259D01*
X1521990Y240177D01*
Y234209D01*
X1524977Y231222D01*
Y222338D01*
X1527146Y220169D01*
Y213618D01*
X1524909Y211381D01*
Y207820D01*
X1523886Y206797D01*
Y182402D01*
X1519501Y178017D01*
Y138899D01*
X1524744Y133656D01*
G01X1482004Y222483D02*
X1481720Y222199D01*
Y219706D01*
X1478685Y216671D01*
X1476729D01*
X1472041Y211983D01*
Y194640D01*
X1482918Y183763D01*
X1485350D01*
X1489056Y180057D01*
Y179832D01*
X1489015D01*
G01X1487000Y333300D02*
X1485702Y332002D01*
Y328399D01*
X1498985Y315116D01*
Y303234D01*
X1504141Y298078D01*
Y285264D01*
X1507020Y282385D01*
Y277658D01*
X1511152Y273526D01*
Y272023D01*
X1510800Y271671D01*
X1510377D01*
X1510025Y271319D01*
Y270171D01*
X1510377Y269819D01*
X1510800D01*
X1511152Y269467D01*
Y268319D01*
X1510800Y267967D01*
X1510161D01*
X1509809Y267615D01*
Y266467D01*
X1510161Y266115D01*
X1510800D01*
X1511152Y265763D01*
Y260315D01*
X1511667Y259800D01*
X1512397D01*
X1512912Y260315D01*
Y270920D01*
X1513412Y271420D01*
X1514172D01*
X1514672Y270920D01*
Y255002D01*
X1512568Y252898D01*
Y243161D01*
X1511131Y241724D01*
Y239271D01*
X1514660Y235742D01*
Y223815D01*
X1515175Y223300D01*
X1515905D01*
X1516420Y223815D01*
Y229185D01*
X1516935Y229700D01*
X1517665D01*
X1518180Y229185D01*
Y209969D01*
X1518695Y209454D01*
X1519425D01*
X1519940Y209969D01*
Y229185D01*
X1520455Y229700D01*
X1521185D01*
X1521700Y229185D01*
Y210621D01*
X1520975Y209896D01*
Y194069D01*
X1520300Y193394D01*
X1518941D01*
X1518408Y193927D01*
Y205499D01*
X1518116Y205791D01*
X1516870D01*
X1516616Y205537D01*
G01X1488300Y158300D02*
X1486556Y160044D01*
Y162723D01*
X1490366Y166533D01*
X1491612D01*
X1491637Y166558D01*
X1491711D01*
X1499192Y174039D01*
Y174113D01*
X1499193Y174114D01*
Y174736D01*
X1499192Y174737D01*
Y178477D01*
X1494464Y183205D01*
Y200897D01*
X1493957Y201404D01*
Y218358D01*
X1494345Y218746D01*
Y227973D01*
X1483935Y238383D01*
Y241526D01*
X1474520Y250941D01*
Y251740D01*
G01X1480098Y283052D02*
Y280972D01*
X1482638Y278432D01*
X1483647D01*
X1491016Y271063D01*
Y269845D01*
X1490155Y268984D01*
X1489147D01*
X1488076Y267913D01*
Y266409D01*
X1487423Y265756D01*
Y255962D01*
X1488366Y255019D01*
Y253504D01*
X1492694Y249176D01*
Y247165D01*
X1496336Y243523D01*
Y238127D01*
X1502517Y231946D01*
Y223126D01*
X1501855Y222464D01*
Y182198D01*
X1503769Y180284D01*
Y171918D01*
X1497700Y165849D01*
Y162285D01*
X1497493Y162078D01*
G01X1486397Y308247D02*
Y307411D01*
X1488076Y305732D01*
Y298455D01*
X1489569Y296962D01*
Y288632D01*
X1493980Y284221D01*
X1497599D01*
X1501257Y280563D01*
Y279257D01*
X1499904Y277904D01*
Y270692D01*
X1500908Y269688D01*
Y259994D01*
X1504196Y256706D01*
Y253827D01*
X1507035Y250988D01*
Y238477D01*
X1510066Y235446D01*
Y222665D01*
X1511856Y220875D01*
Y217395D01*
X1511857Y217394D01*
Y215358D01*
X1509797Y213298D01*
Y202540D01*
X1512500Y199837D01*
G01X1482386Y336926D02*
X1484126Y335186D01*
Y332726D01*
X1482524Y331124D01*
Y329075D01*
X1483347Y328252D01*
X1484219D01*
X1497712Y314759D01*
Y309926D01*
X1495609Y307823D01*
Y305514D01*
X1495897Y305226D01*
Y302619D01*
X1497286Y301230D01*
Y299115D01*
X1499746Y296655D01*
Y292915D01*
X1502989Y289672D01*
Y284786D01*
X1505868Y281907D01*
Y277180D01*
X1508832Y274216D01*
Y271324D01*
X1507515Y270007D01*
Y265416D01*
X1509973Y262958D01*
Y259657D01*
X1511700Y257930D01*
Y253660D01*
X1511400Y253360D01*
Y243623D01*
X1509979Y242202D01*
Y238793D01*
X1512500Y236272D01*
Y223499D01*
X1516628Y219371D01*
Y216869D01*
X1514700Y214941D01*
Y202700D01*
X1515600Y201800D01*
Y193367D01*
X1515060Y192827D01*
Y192443D01*
G01X1526150Y234300D02*
Y234450D01*
X1526400Y234700D01*
Y238401D01*
X1525324Y239477D01*
Y243402D01*
X1520147Y248579D01*
Y273689D01*
X1519471Y274365D01*
Y274377D01*
X1515153Y278695D01*
X1514358D01*
X1513906Y279147D01*
Y287723D01*
X1512554Y289075D01*
X1512067D01*
X1509459Y291683D01*
Y299868D01*
X1504028Y305299D01*
Y313372D01*
X1506810Y316154D01*
Y320389D01*
X1498144Y329055D01*
Y330076D01*
X1492662Y335558D01*
Y363880D01*
X1492663Y363881D01*
Y373174D01*
X1492995Y373506D01*
Y380514D01*
X1493375Y380894D01*
G01X1509814Y247215D02*
Y253404D01*
X1510457Y254047D01*
Y257539D01*
X1510300Y257696D01*
Y257700D01*
X1508776Y259224D01*
Y262225D01*
X1505328Y265673D01*
Y273007D01*
X1506218Y273897D01*
Y275200D01*
X1504716Y276702D01*
Y281428D01*
X1501837Y284307D01*
Y288868D01*
X1498517Y292188D01*
Y296162D01*
X1496199Y298480D01*
Y301209D01*
X1495145Y302263D01*
Y302264D01*
X1494970Y302439D01*
Y305009D01*
X1494181Y305798D01*
Y316370D01*
X1486451Y324100D01*
X1482700D01*
X1481258Y325542D01*
Y332308D01*
X1482550Y333600D01*
G01X1482585Y340856D02*
Y338956D01*
X1485941Y335600D01*
X1487010D01*
X1489010Y333600D01*
Y326748D01*
X1498297Y317461D01*
Y317434D01*
X1500137Y315594D01*
Y303712D01*
X1505293Y298556D01*
Y285742D01*
X1508172Y282863D01*
Y278136D01*
X1511388Y274920D01*
X1512420D01*
X1516159Y271181D01*
Y242514D01*
X1514824Y241179D01*
Y238500D01*
X1516549Y236775D01*
Y234278D01*
G01X1478500Y252000D02*
Y252500D01*
X1475672Y255328D01*
Y262749D01*
X1472328Y266093D01*
Y271924D01*
X1470649Y273603D01*
G01X1473798Y308247D02*
X1472328Y306777D01*
X1470249D01*
X1468386Y304914D01*
Y269474D01*
X1467369Y268457D01*
Y266226D01*
X1472400Y261195D01*
Y255903D01*
X1473298Y255005D01*
X1474548D01*
X1476848Y252705D01*
Y251052D01*
X1481476Y246424D01*
X1484019D01*
X1485943Y244500D01*
X1487500D01*
G01X1489546Y308247D02*
X1490896Y306897D01*
Y303741D01*
X1491901Y302736D01*
Y298299D01*
X1494900Y295300D01*
Y286099D01*
X1495465Y285534D01*
X1497350D01*
X1502009Y280875D01*
Y278945D01*
X1500656Y277592D01*
Y271004D01*
X1501660Y270000D01*
Y264840D01*
X1506472Y260028D01*
Y254958D01*
X1505946Y254432D01*
G01X1495445Y338724D02*
X1495724D01*
X1497180Y340180D01*
X1498592D01*
X1500141Y338631D01*
Y338169D01*
X1506090Y332220D01*
Y328123D01*
X1511908Y322305D01*
Y307286D01*
X1511907Y307285D01*
Y305793D01*
X1519804Y297894D01*
Y289604D01*
X1521989Y287419D01*
Y282411D01*
X1524379Y280021D01*
Y276411D01*
X1525360Y275430D01*
Y256609D01*
X1529719Y252250D01*
Y247915D01*
X1532287Y245347D01*
Y233920D01*
X1535213Y230994D01*
Y213679D01*
X1530570Y209036D01*
Y205371D01*
X1529546Y204347D01*
Y164963D01*
X1532454Y162055D01*
Y161154D01*
X1534708Y158900D01*
Y152520D01*
X1530409Y148221D01*
Y145291D01*
X1531182Y144518D01*
X1532923D01*
G01X1531985Y147000D02*
X1536410Y151425D01*
Y159605D01*
X1534156Y161859D01*
Y162760D01*
X1533141Y163775D01*
Y177298D01*
X1531268Y179171D01*
Y203567D01*
X1532272Y204571D01*
Y208331D01*
X1536915Y212974D01*
Y231700D01*
X1534076Y234539D01*
Y250300D01*
X1527062Y257314D01*
Y276135D01*
X1526081Y277116D01*
Y281119D01*
X1523691Y283509D01*
Y288124D01*
X1521506Y290309D01*
Y298684D01*
X1513610Y306581D01*
Y312854D01*
X1515711Y314955D01*
Y322789D01*
X1512220Y326280D01*
Y331910D01*
X1511600Y332530D01*
X1508200D01*
X1503159Y337571D01*
Y340132D01*
X1502041Y341250D01*
X1499829D01*
G01X1466006Y265300D02*
X1466460Y265754D01*
Y268951D01*
X1467497Y269988D01*
Y310324D01*
X1470249Y313076D01*
X1472328D01*
X1473798Y314546D01*
G01X1474096Y256706D02*
X1473400Y257402D01*
Y261259D01*
X1468350Y266309D01*
Y267961D01*
X1469179Y268790D01*
Y290724D01*
X1472119Y293664D01*
Y302348D01*
X1473190Y303419D01*
X1481776D01*
X1483247Y301948D01*
G01X1541765Y114000D02*
X1540235Y115530D01*
Y127842D01*
X1544531Y132138D01*
Y141843D01*
X1548482Y145794D01*
Y157719D01*
X1550007Y159244D01*
Y164350D01*
X1549177Y165180D01*
X1545163Y169196D01*
Y181025D01*
X1546387Y182249D01*
Y186598D01*
X1543447Y189538D01*
Y202081D01*
X1543446Y202082D01*
Y203339D01*
X1545975Y205868D01*
Y209311D01*
X1548976Y212312D01*
Y237291D01*
X1546977Y239290D01*
Y241694D01*
X1545351Y243320D01*
Y254492D01*
X1535735Y264108D01*
Y268614D01*
X1538836Y271715D01*
Y281722D01*
X1537054Y283504D01*
Y284240D01*
X1537053Y284241D01*
Y284863D01*
X1537054Y284864D01*
Y289900D01*
X1532824Y294130D01*
Y298898D01*
X1524101Y307621D01*
Y312488D01*
X1529734Y318121D01*
Y319714D01*
G01X1535065Y164300D02*
Y177005D01*
X1532420Y179650D01*
Y203089D01*
X1533424Y204093D01*
Y207853D01*
X1538067Y212496D01*
Y231612D01*
X1535189Y234490D01*
Y254908D01*
X1528868Y261229D01*
Y275521D01*
X1529600Y276253D01*
Y279624D01*
X1524843Y284381D01*
Y288602D01*
X1522658Y290787D01*
Y298597D01*
X1516138Y305117D01*
Y310749D01*
G01X1498309Y360005D02*
X1500600Y357714D01*
Y347860D01*
X1502610Y345850D01*
X1506401D01*
X1510851Y341400D01*
Y340113D01*
G01X1500800Y374794D02*
Y360400D01*
X1501360Y359840D01*
Y348164D01*
X1502922Y346602D01*
X1506713D01*
X1519532Y333783D01*
X1522307D01*
X1523470Y332620D01*
Y321330D01*
X1522292Y320152D01*
Y315765D01*
X1521092Y314565D01*
Y306374D01*
X1529633Y297833D01*
Y292306D01*
X1528900Y291573D01*
Y286100D01*
X1535828Y279172D01*
Y273127D01*
X1532727Y270026D01*
Y262860D01*
X1539749Y255838D01*
Y241250D01*
X1542690Y238309D01*
Y236050D01*
G01X1502970Y350610D02*
X1503769D01*
X1519667Y334712D01*
X1525102D01*
X1529113Y330701D01*
Y329395D01*
X1526263Y326545D01*
Y316778D01*
X1522596Y313111D01*
Y312489D01*
X1522597Y312488D01*
Y307621D01*
X1522596Y307620D01*
Y306998D01*
X1531320Y298274D01*
Y293453D01*
X1535550Y289223D01*
Y285488D01*
X1535549Y285487D01*
Y284865D01*
X1535548Y284864D01*
Y283618D01*
X1535550Y283616D01*
Y282880D01*
X1537332Y281098D01*
Y272339D01*
X1534231Y269238D01*
Y263484D01*
X1543846Y253869D01*
Y242697D01*
X1545391Y241152D01*
Y237828D01*
X1547378Y235841D01*
Y212842D01*
X1544471Y209935D01*
Y206492D01*
X1541736Y203757D01*
Y186057D01*
X1540772Y185093D01*
Y181143D01*
X1542860Y179055D01*
Y177145D01*
X1542859Y177144D01*
Y168104D01*
X1547751Y163212D01*
Y160358D01*
X1546226Y158833D01*
Y147438D01*
X1539400Y140612D01*
Y138488D01*
X1541390Y136498D01*
G01X1498246Y352305D02*
Y347974D01*
X1501990Y344230D01*
X1505789D01*
X1508300Y341719D01*
Y339369D01*
X1512134Y335535D01*
X1513925D01*
X1521668Y327792D01*
Y321656D01*
X1520788Y320776D01*
Y316389D01*
X1519588Y315189D01*
Y304929D01*
X1524962Y299555D01*
Y291743D01*
X1527147Y289558D01*
Y285337D01*
X1532776Y279708D01*
Y276169D01*
X1531172Y274565D01*
Y262185D01*
X1537494Y255863D01*
Y253953D01*
X1537493Y253952D01*
Y241378D01*
X1540362Y238509D01*
Y235085D01*
X1540663Y234784D01*
Y208072D01*
X1534724Y202133D01*
Y197876D01*
X1537001Y195599D01*
Y186710D01*
X1536964Y186673D01*
Y179166D01*
X1538412Y177718D01*
Y167742D01*
X1538410Y167740D01*
Y166494D01*
X1538411Y166493D01*
Y165869D01*
X1541260Y163020D01*
Y160248D01*
X1543071Y158437D01*
Y150270D01*
X1541831Y149030D01*
G01X1496000Y350000D02*
Y348570D01*
X1501600Y342970D01*
X1505391D01*
X1506900Y341461D01*
Y339139D01*
X1511709Y334330D01*
X1512660D01*
X1515430Y331560D01*
Y329370D01*
X1519636Y325164D01*
Y316867D01*
X1518436Y315667D01*
Y304449D01*
X1523810Y299075D01*
Y291265D01*
X1525995Y289080D01*
Y284859D01*
X1531624Y279230D01*
Y276647D01*
X1530020Y275043D01*
Y261707D01*
X1536341Y255386D01*
Y234968D01*
X1539511Y231798D01*
Y208550D01*
X1533572Y202611D01*
Y180928D01*
X1537258Y177242D01*
Y165392D01*
X1539513Y163137D01*
Y153738D01*
X1541351Y151900D01*
G01X1545250Y88360D02*
Y88695D01*
X1545887Y89332D01*
Y93621D01*
X1543541Y95967D01*
Y103402D01*
X1543571Y103432D01*
Y105599D01*
X1543749Y105777D01*
Y107707D01*
X1539483Y111973D01*
Y128290D01*
X1540615Y129422D01*
Y133635D01*
X1542020Y135040D01*
X1542400D01*
X1543027Y135667D01*
Y142467D01*
X1546978Y146418D01*
Y158521D01*
X1548503Y160046D01*
Y163725D01*
X1543659Y168572D01*
Y180551D01*
X1541524Y182686D01*
Y184781D01*
X1542488Y185745D01*
Y203445D01*
X1545223Y206180D01*
Y209623D01*
X1548224Y212624D01*
Y236979D01*
X1546169Y239034D01*
Y241438D01*
X1544599Y243008D01*
Y254180D01*
X1534983Y263796D01*
Y268926D01*
X1538084Y272027D01*
Y281410D01*
X1536302Y283192D01*
Y283928D01*
X1536300Y283930D01*
Y284552D01*
X1536301Y284553D01*
Y285175D01*
X1536302Y285176D01*
Y289535D01*
X1532072Y293765D01*
Y298586D01*
X1523349Y307309D01*
Y312800D01*
X1527015Y316466D01*
Y326233D01*
X1529865Y329083D01*
Y331013D01*
X1525341Y335537D01*
X1520680D01*
X1516934Y339283D01*
Y340201D01*
X1502112Y355023D01*
Y360152D01*
G01X1501800Y369465D02*
Y376184D01*
G01X1511190Y393703D02*
X1511901Y394414D01*
X1512875D01*
G01X1527537Y330048D02*
Y329484D01*
X1525511Y327458D01*
Y317090D01*
X1521844Y313423D01*
Y312177D01*
X1521845Y312176D01*
Y307933D01*
X1521844Y307932D01*
Y306686D01*
X1530568Y297962D01*
Y292031D01*
X1532238Y290361D01*
Y285232D01*
X1534798Y282672D01*
Y282568D01*
X1536580Y280786D01*
Y272651D01*
X1533479Y269550D01*
Y263172D01*
X1543056Y253595D01*
Y242403D01*
X1544630Y240829D01*
Y235651D01*
X1542167Y233188D01*
Y207448D01*
X1539432Y204713D01*
Y187013D01*
X1538468Y186049D01*
Y180187D01*
X1540555Y178100D01*
Y169060D01*
X1540554Y169059D01*
Y167149D01*
X1540555Y167148D01*
Y166143D01*
X1545023Y161675D01*
G01X1478524Y318900D02*
Y319566D01*
X1475444Y322646D01*
Y341423D01*
X1471017Y345850D01*
X1469000D01*
G01X1505450Y375500D02*
X1507215Y373735D01*
Y369985D01*
X1509654Y367546D01*
Y364135D01*
X1509653Y364134D01*
Y363824D01*
X1509652Y363823D01*
Y363513D01*
X1508789Y362650D01*
Y351889D01*
X1508600Y351700D01*
Y349734D01*
X1517686Y340648D01*
Y339595D01*
X1520992Y336289D01*
X1525653D01*
X1530617Y331325D01*
Y328771D01*
X1528529Y326683D01*
Y323215D01*
X1531348Y320396D01*
Y312798D01*
X1530249Y311699D01*
Y303022D01*
X1536300Y296971D01*
Y294429D01*
X1535924Y294053D01*
Y292147D01*
X1537806Y290265D01*
Y283816D01*
X1539588Y282034D01*
Y271403D01*
X1536487Y268302D01*
Y264420D01*
X1546732Y254175D01*
Y248768D01*
X1550480Y245020D01*
Y211688D01*
X1547479Y208687D01*
Y200130D01*
X1549693Y197916D01*
Y196707D01*
G01X1510925Y377514D02*
Y374384D01*
X1512050Y373259D01*
Y361214D01*
X1511123Y360287D01*
Y353887D01*
X1513572Y351438D01*
Y348217D01*
X1519213Y342576D01*
X1519791D01*
X1519792Y342575D01*
X1520414D01*
X1520415Y342576D01*
X1521419D01*
X1522342Y341653D01*
Y340943D01*
X1524740Y338545D01*
X1527779D01*
X1532910Y333414D01*
Y327872D01*
X1530785Y325747D01*
Y324151D01*
X1533604Y321332D01*
Y311862D01*
X1532505Y310763D01*
Y308833D01*
X1534533Y306805D01*
X1537622D01*
X1539900Y304527D01*
Y299786D01*
X1539899Y299785D01*
Y299163D01*
X1542432Y296630D01*
Y290582D01*
X1541795Y289945D01*
Y285147D01*
X1543348Y283594D01*
Y279224D01*
X1550839Y271733D01*
Y250605D01*
X1550838Y250604D01*
Y249982D01*
X1554241Y246579D01*
Y214497D01*
X1554242Y214496D01*
Y210130D01*
X1552063Y207951D01*
Y202031D01*
G01X1515328Y363389D02*
X1511875Y359936D01*
Y354205D01*
X1514324Y351756D01*
Y348529D01*
X1519525Y343328D01*
X1521731D01*
X1523094Y341965D01*
Y341255D01*
X1525052Y339297D01*
X1528091D01*
X1533693Y333695D01*
Y326764D01*
X1534804Y325653D01*
Y324347D01*
X1534414Y323957D01*
Y311608D01*
X1533257Y310451D01*
Y309145D01*
X1534845Y307557D01*
X1537934D01*
X1540652Y304839D01*
Y299474D01*
X1543184Y296942D01*
Y290270D01*
X1542547Y289633D01*
Y285459D01*
X1544100Y283906D01*
Y279536D01*
X1551591Y272045D01*
Y250293D01*
X1554993Y246891D01*
Y214809D01*
X1554994Y214808D01*
Y209818D01*
X1554167Y208991D01*
Y207121D01*
X1554168Y207120D01*
Y203494D01*
X1554672Y202990D01*
Y196704D01*
X1554671Y196703D01*
Y196267D01*
X1554672Y196266D01*
Y195020D01*
X1554669Y195017D01*
Y194539D01*
X1553955Y193825D01*
Y175471D01*
X1555763Y173663D01*
Y172382D01*
X1557999Y170146D01*
X1559355D01*
X1563767Y165734D01*
Y160088D01*
X1562184Y158505D01*
Y138784D01*
X1562936Y138032D01*
Y131130D01*
X1565943Y128123D01*
Y124335D01*
X1564120Y122512D01*
Y95836D01*
X1564119Y95835D01*
Y92600D01*
X1569260Y87459D01*
X1577834D01*
X1581580Y91205D01*
X1585769D01*
X1586243Y90731D01*
X1616192D01*
X1618456Y88467D01*
Y86282D01*
X1622401Y82337D01*
X1626114D01*
X1626802Y81649D01*
Y80579D01*
X1630312Y77069D01*
X1647813D01*
X1648902Y75980D01*
X1660387D01*
X1660842Y75525D01*
X1666590D01*
X1669045Y73070D01*
X1678470D01*
X1679900Y74500D01*
G01X1659196Y70291D02*
X1624540D01*
X1622889Y71942D01*
X1619379D01*
X1609919Y81402D01*
X1607329D01*
X1605154Y83577D01*
Y84793D01*
X1602959Y86988D01*
X1585880D01*
X1583883Y84991D01*
X1582107D01*
X1578908Y81792D01*
X1569009D01*
X1560828Y89973D01*
Y122465D01*
X1559876Y123417D01*
Y129662D01*
X1558836Y130702D01*
X1553166D01*
X1553136Y130672D01*
X1551206D01*
X1549843Y132035D01*
Y133965D01*
X1552672Y136794D01*
Y139965D01*
X1553929Y141222D01*
Y149114D01*
X1557978Y153163D01*
Y162201D01*
X1557979Y162202D01*
Y166974D01*
X1554476Y170477D01*
X1551398D01*
X1550475Y171400D01*
Y175566D01*
X1551699Y176790D01*
Y194761D01*
X1552340Y195402D01*
Y197397D01*
X1548983Y200754D01*
Y208063D01*
X1551984Y211064D01*
Y245644D01*
X1548582Y249046D01*
Y270798D01*
X1541092Y278288D01*
Y282658D01*
X1539539Y284211D01*
Y290881D01*
X1540176Y291518D01*
Y295694D01*
X1534451Y301419D01*
Y305823D01*
X1531753Y308521D01*
Y311075D01*
X1532852Y312174D01*
Y321020D01*
X1530033Y323839D01*
Y326059D01*
X1532121Y328147D01*
Y331949D01*
X1526277Y337793D01*
X1521744D01*
X1519190Y340347D01*
Y341535D01*
X1512820Y347905D01*
Y351110D01*
X1510371Y353559D01*
Y360599D01*
X1511155Y361383D01*
Y371593D01*
X1509355Y373393D01*
G01X1621100Y69600D02*
X1619759D01*
X1608709Y80650D01*
X1607017D01*
X1604402Y83265D01*
Y84327D01*
X1602653Y86076D01*
X1586771D01*
X1584354Y83659D01*
X1582504D01*
X1579885Y81040D01*
X1567731D01*
X1552851Y95920D01*
Y117634D01*
X1549508Y120977D01*
Y130910D01*
X1549091Y131327D01*
Y134277D01*
X1549508Y134694D01*
Y138346D01*
X1553177Y142015D01*
Y149426D01*
X1557226Y153475D01*
Y162513D01*
X1557227Y162514D01*
Y166662D01*
X1554164Y169725D01*
X1551086D01*
X1549723Y171088D01*
Y175878D01*
X1550947Y177102D01*
Y195073D01*
X1551269Y195395D01*
Y197404D01*
X1548231Y200442D01*
Y208375D01*
X1551232Y211376D01*
Y245332D01*
X1547484Y249080D01*
Y254487D01*
X1539424Y262547D01*
Y270175D01*
X1540340Y271091D01*
Y282346D01*
X1538787Y283899D01*
Y291193D01*
X1539076Y291482D01*
Y295348D01*
X1531001Y303423D01*
Y311387D01*
X1532100Y312486D01*
Y320708D01*
X1529281Y323527D01*
Y326371D01*
X1531369Y328459D01*
Y331637D01*
X1525965Y337041D01*
X1521432D01*
X1518438Y340035D01*
Y340960D01*
X1513076Y346322D01*
G01X1524575Y394414D02*
X1525560D01*
X1528095Y391879D01*
Y389641D01*
X1526905Y388451D01*
Y386293D01*
X1528095Y385103D01*
Y383623D01*
X1526399Y381927D01*
Y379611D01*
X1524955Y378167D01*
Y363525D01*
X1527074Y361406D01*
Y357155D01*
X1531638Y352591D01*
Y347813D01*
X1541824Y337627D01*
Y332160D01*
X1542238Y331746D01*
Y330890D01*
X1545440Y327688D01*
Y311055D01*
X1546820Y309675D01*
Y307428D01*
X1547539Y306709D01*
Y301723D01*
X1549200Y300062D01*
Y291751D01*
X1552783Y288168D01*
Y283882D01*
X1551324Y282423D01*
Y281047D01*
X1559217Y273154D01*
Y256127D01*
X1561761Y253583D01*
Y246170D01*
X1565689Y242242D01*
Y239748D01*
X1565688Y239747D01*
Y232032D01*
X1564453Y230797D01*
Y191627D01*
X1562068Y189242D01*
Y179327D01*
X1564888Y176507D01*
Y174650D01*
X1568052Y171486D01*
X1573470D01*
X1574393Y170563D01*
Y164893D01*
X1571672Y162172D01*
Y146460D01*
X1572346Y145786D01*
Y122386D01*
X1570351Y120391D01*
Y112286D01*
X1569867Y111802D01*
Y109706D01*
X1570351Y109222D01*
Y104135D01*
X1575696Y98790D01*
Y96000D01*
X1575693Y95997D01*
Y94691D01*
X1576616Y93768D01*
X1578673D01*
X1580023Y95118D01*
X1580645D01*
X1580646Y95119D01*
X1582770D01*
X1585361Y97710D01*
X1587516D01*
X1590268Y100462D01*
X1596482D01*
X1600042Y96902D01*
X1610771D01*
X1611950Y98081D01*
X1620028D01*
X1622185Y95924D01*
Y95302D01*
X1622186Y95301D01*
Y94679D01*
X1622184Y94677D01*
Y94037D01*
X1622493Y93728D01*
X1622494D01*
X1623245Y92977D01*
X1623246D01*
X1629459Y86764D01*
Y86763D01*
X1631422Y84800D01*
X1654807D01*
X1659492Y80115D01*
X1661542D01*
X1661797Y79860D01*
X1678710D01*
X1687500Y88650D01*
X1700836D01*
X1707014Y82472D01*
X1710441D01*
X1713911Y85942D01*
X1716110D01*
X1716111Y85943D01*
X1717357D01*
X1717358Y85942D01*
X1720841D01*
X1723499Y88600D01*
X1734094D01*
X1736747Y91253D01*
X1736748D01*
X1737499Y92004D01*
X1737500D01*
X1737710Y92214D01*
X1751138D01*
X1765000Y106076D01*
X1776239D01*
X1787739Y94576D01*
X1788853D01*
X1789776Y93653D01*
Y93163D01*
X1812169Y70770D01*
Y69503D01*
X1819972Y61700D01*
Y42715D01*
X1817186Y39929D01*
G01X1472940Y384030D02*
X1475800D01*
X1478250Y381580D01*
X1487940D01*
X1489064Y382704D01*
X1492076D01*
X1492995Y383623D01*
Y384165D01*
X1495705Y386875D01*
Y388305D01*
X1497655Y390255D01*
Y391685D01*
X1499585Y393615D01*
Y395805D01*
X1501555Y397775D01*
Y398445D01*
X1502745Y399635D01*
Y401825D01*
X1501555Y403015D01*
Y405205D01*
X1503168Y406818D01*
Y409006D01*
X1503666Y409504D01*
X1505726D01*
X1509355Y405875D01*
Y403903D01*
X1510388Y402870D01*
X1512558D01*
G01X1539843Y406300D02*
X1548090D01*
X1549900Y404490D01*
X1549950D01*
G01X1557344Y435470D02*
Y434034D01*
X1556030Y432720D01*
Y430910D01*
X1554205Y429085D01*
Y426225D01*
X1553278Y425298D01*
Y425246D01*
X1552330Y424298D01*
Y423719D01*
X1550191Y421580D01*
Y417847D01*
X1549512Y417168D01*
Y413871D01*
X1547787Y412146D01*
Y408874D01*
X1551520Y405141D01*
Y403839D01*
X1550461Y402780D01*
X1541963D01*
G01X1504700Y374200D02*
Y369700D01*
X1506500Y367900D01*
Y361000D01*
X1505400Y359900D01*
Y357800D01*
X1507200Y356000D01*
G01X1558000Y205100D02*
Y208568D01*
X1558002Y208570D01*
Y216056D01*
X1558001Y216057D01*
Y248280D01*
X1555017Y251264D01*
Y254685D01*
X1555016Y254686D01*
Y255932D01*
X1555015Y255933D01*
Y256555D01*
X1555017Y256557D01*
Y273098D01*
X1548200Y279915D01*
Y282899D01*
X1548316Y283015D01*
Y283671D01*
X1549775Y285130D01*
Y286920D01*
X1546192Y290503D01*
Y298768D01*
X1544516Y300444D01*
Y305311D01*
X1540026Y309801D01*
Y313042D01*
X1541308Y314324D01*
Y315197D01*
X1537759Y318746D01*
Y321040D01*
X1538344Y321625D01*
Y322871D01*
X1538343Y322872D01*
Y326576D01*
X1536830Y328089D01*
Y338359D01*
X1529048Y346141D01*
X1525316D01*
X1520824Y350633D01*
Y351416D01*
X1520823Y351417D01*
Y351448D01*
X1518756Y353515D01*
Y356397D01*
X1518737Y356416D01*
Y357722D01*
X1518756Y357741D01*
Y360735D01*
X1519154Y361133D01*
Y362843D01*
X1519200Y362889D01*
Y362890D01*
X1519246Y362936D01*
Y363216D01*
X1521196Y365166D01*
Y366468D01*
X1517155Y370509D01*
Y380514D01*
X1516775Y380894D01*
G01X1520675Y394414D02*
X1522354D01*
X1524575Y392193D01*
Y390286D01*
X1523005Y388716D01*
Y386311D01*
X1524195Y385121D01*
Y383097D01*
X1523005Y381907D01*
Y379355D01*
X1524195Y378165D01*
Y363221D01*
X1526322Y361094D01*
Y355231D01*
X1530188Y351365D01*
Y348199D01*
X1541072Y337315D01*
Y331848D01*
X1541486Y331434D01*
Y326115D01*
X1540624Y325253D01*
Y323340D01*
X1543564Y320400D01*
Y313388D01*
X1542282Y312106D01*
Y310737D01*
X1546787Y306232D01*
Y301411D01*
X1548448Y299750D01*
Y291439D01*
X1552031Y287856D01*
Y284194D01*
X1550572Y282735D01*
Y280735D01*
X1558465Y272842D01*
Y255235D01*
X1561009Y252691D01*
Y245858D01*
X1564937Y241930D01*
Y240060D01*
X1564936Y240059D01*
Y232344D01*
X1563501Y230909D01*
Y191739D01*
X1561316Y189554D01*
Y179015D01*
X1564136Y176195D01*
Y174338D01*
X1568342Y170132D01*
X1569775D01*
X1571870Y168037D01*
Y164147D01*
X1570920Y163197D01*
Y146148D01*
X1571594Y145474D01*
Y122698D01*
X1569428Y120532D01*
Y112427D01*
X1569115Y112114D01*
Y104364D01*
X1569599Y103880D01*
Y103823D01*
X1574384Y99038D01*
Y97437D01*
X1572586Y95639D01*
G01X1558042Y172448D02*
X1554707Y175783D01*
Y193513D01*
X1555424Y194230D01*
Y202678D01*
X1555425Y202679D01*
Y203301D01*
X1554920Y203806D01*
Y207432D01*
X1554919Y207433D01*
Y208679D01*
X1555746Y209506D01*
Y215120D01*
X1555745Y215121D01*
Y247203D01*
X1552485Y250463D01*
Y272252D01*
X1544852Y279885D01*
Y284218D01*
X1543299Y285771D01*
Y289321D01*
X1543936Y289958D01*
Y297335D01*
X1541434Y299837D01*
Y305139D01*
X1537640Y308933D01*
Y310461D01*
X1535322Y312779D01*
Y322585D01*
X1535560Y322823D01*
Y326167D01*
X1534574Y327153D01*
Y333961D01*
X1527959Y340576D01*
Y342134D01*
X1526778Y343315D01*
X1523009D01*
X1521803Y344521D01*
X1519541D01*
X1515076Y348986D01*
Y351444D01*
X1515077Y351445D01*
Y352073D01*
X1512649Y354501D01*
Y359325D01*
X1514958Y361634D01*
X1516463D01*
X1516898Y362069D01*
Y364040D01*
X1516475Y364463D01*
Y367325D01*
X1513335Y370465D01*
Y374387D01*
X1512503Y375219D01*
Y380522D01*
X1512875Y380894D01*
G01X1518725Y377514D02*
Y370009D01*
X1521196Y367538D01*
Y367531D01*
X1521947Y366780D01*
Y364854D01*
X1520148Y363055D01*
Y360453D01*
X1522000Y358601D01*
Y355037D01*
X1522005Y355032D01*
Y353726D01*
X1522000Y353721D01*
Y350521D01*
X1525628Y346893D01*
X1529360D01*
X1538384Y337869D01*
Y332408D01*
X1539982Y330810D01*
Y326739D01*
X1539120Y325877D01*
Y322709D01*
X1542060Y319769D01*
Y314012D01*
X1540778Y312730D01*
Y310113D01*
X1545268Y305623D01*
Y300756D01*
X1546944Y299080D01*
Y290815D01*
X1550527Y287232D01*
Y284818D01*
X1549068Y283359D01*
Y281359D01*
X1549067Y281358D01*
Y280112D01*
X1555769Y273410D01*
Y256245D01*
X1555768Y256244D01*
Y254998D01*
X1555769Y254997D01*
Y251576D01*
X1558753Y248592D01*
Y244922D01*
X1562680Y240995D01*
Y233280D01*
X1559600Y230200D01*
Y195032D01*
X1557787Y193219D01*
Y192236D01*
G01X1561538Y174649D02*
Y176665D01*
X1559597Y178606D01*
Y193965D01*
X1560448Y194816D01*
Y229984D01*
X1563432Y232968D01*
Y240683D01*
X1563433Y240684D01*
Y241306D01*
X1559505Y245234D01*
Y248904D01*
X1556521Y251888D01*
Y273722D01*
X1549819Y280424D01*
Y281046D01*
X1549820Y281047D01*
Y283047D01*
X1551279Y284506D01*
Y287544D01*
X1547696Y291127D01*
Y299438D01*
X1546035Y301099D01*
Y305920D01*
X1541530Y310425D01*
Y312418D01*
X1542812Y313700D01*
Y320081D01*
X1539872Y323021D01*
Y325565D01*
X1540734Y326427D01*
Y331122D01*
X1540320Y331536D01*
Y336997D01*
X1529672Y347645D01*
X1525940D01*
X1522752Y350833D01*
Y353409D01*
X1522757Y353414D01*
Y355344D01*
X1522752Y355349D01*
Y358913D01*
X1520900Y360765D01*
Y362744D01*
X1522698Y364542D01*
Y367387D01*
X1520295Y369790D01*
Y379053D01*
X1519105Y380243D01*
G01X1516395Y378165D02*
Y369531D01*
X1518056Y367870D01*
Y365166D01*
X1518402Y364820D01*
Y361445D01*
X1517985Y361028D01*
Y353222D01*
X1520071Y351136D01*
Y350322D01*
X1525005Y345388D01*
X1528737D01*
X1536078Y338047D01*
Y327777D01*
X1537418Y326437D01*
Y321763D01*
X1536874Y321219D01*
Y313369D01*
X1539200Y311043D01*
Y309563D01*
X1543764Y304999D01*
Y299910D01*
X1545440Y298234D01*
Y289334D01*
X1544803Y288697D01*
Y286395D01*
X1546498Y284700D01*
Y280400D01*
X1554264Y272634D01*
Y256868D01*
X1554263Y256867D01*
Y255621D01*
X1554264Y255620D01*
Y250953D01*
X1557248Y247969D01*
Y247828D01*
X1557249Y247827D01*
Y215745D01*
X1557250Y215744D01*
Y208882D01*
X1556424Y208056D01*
Y204447D01*
X1556928Y203943D01*
Y203926D01*
X1556929Y203925D01*
Y202055D01*
X1556928Y202054D01*
Y193606D01*
X1556211Y192889D01*
Y188383D01*
X1557409Y187185D01*
Y179730D01*
X1559962Y177177D01*
Y173909D01*
X1565982Y167889D01*
Y158003D01*
X1565983Y158002D01*
Y157380D01*
X1565271Y156668D01*
Y138785D01*
X1564440Y137954D01*
Y132077D01*
X1568023Y128494D01*
Y123574D01*
X1565624Y121175D01*
Y95212D01*
X1571420Y89416D01*
X1577513D01*
X1580959Y92862D01*
X1581581D01*
X1581582Y92863D01*
X1582204D01*
X1582206Y92861D01*
X1586834D01*
X1587460Y92235D01*
X1620796D01*
X1627203Y85828D01*
Y85827D01*
X1628769Y84261D01*
Y81638D01*
X1631794Y78613D01*
X1646626D01*
X1647572Y79559D01*
Y79565D01*
X1648935Y80928D01*
X1648941D01*
X1649268Y81255D01*
X1649890D01*
X1649891Y81254D01*
X1654537D01*
X1654538Y81255D01*
X1655160D01*
X1658556Y77859D01*
X1660606D01*
X1660861Y77604D01*
X1679667D01*
X1684515Y82452D01*
X1703842D01*
X1706079Y80215D01*
X1711376D01*
X1714847Y83686D01*
X1721777D01*
X1724288Y86197D01*
X1734883D01*
X1738646Y89960D01*
X1752226D01*
X1759094Y96828D01*
X1769641D01*
X1791359Y75110D01*
X1796931D01*
X1801704Y70337D01*
Y58884D01*
X1800543Y57723D01*
Y54841D01*
X1815288Y40096D01*
Y36744D01*
X1818108Y33924D01*
X1820453D01*
X1823504Y36975D01*
X1825261D01*
X1825348Y37062D01*
X1828022D01*
X1829580Y38620D01*
G01X1513255Y378199D02*
Y376332D01*
X1514692Y374895D01*
Y370171D01*
X1517305Y367558D01*
Y364696D01*
X1517650Y364351D01*
Y361757D01*
X1517233Y361340D01*
Y352879D01*
X1519319Y350793D01*
Y348946D01*
X1523629Y344636D01*
X1528425D01*
X1535326Y337735D01*
Y327465D01*
X1536518Y326273D01*
Y321927D01*
X1536074Y321483D01*
Y313105D01*
X1538400Y310779D01*
Y309299D01*
X1543012Y304687D01*
Y299598D01*
X1544688Y297922D01*
Y289646D01*
X1544051Y289009D01*
Y286083D01*
X1545744Y284390D01*
Y280090D01*
X1553512Y272322D01*
Y257180D01*
X1553511Y257179D01*
Y255309D01*
X1553512Y255308D01*
Y251265D01*
X1553511Y251264D01*
Y250642D01*
X1556496Y247657D01*
Y247516D01*
X1556497Y247515D01*
Y215433D01*
X1556498Y215432D01*
Y209194D01*
X1555671Y208367D01*
Y207745D01*
X1555672Y207744D01*
Y204135D01*
X1556176Y203631D01*
Y203614D01*
X1556177Y203613D01*
Y202367D01*
X1556176Y202366D01*
Y193918D01*
X1555459Y193201D01*
Y188071D01*
X1556657Y186873D01*
Y179418D01*
X1559210Y176865D01*
Y173597D01*
X1565230Y167577D01*
Y157691D01*
X1564519Y156980D01*
Y139097D01*
X1563688Y138266D01*
Y131765D01*
X1567271Y128182D01*
Y123886D01*
X1564872Y121487D01*
Y95524D01*
X1564871Y95523D01*
Y94901D01*
X1571108Y88664D01*
X1577825D01*
X1581270Y92109D01*
X1586522D01*
X1587148Y91483D01*
X1620484D01*
X1626450Y85517D01*
G01X1629297Y79480D02*
X1630916Y77861D01*
X1646938D01*
X1648324Y79247D01*
Y79253D01*
X1649247Y80176D01*
X1649253D01*
X1649579Y80502D01*
X1654849D01*
X1658244Y77107D01*
X1660294D01*
X1660549Y76852D01*
X1679979D01*
X1684827Y81700D01*
X1703163D01*
X1705400Y79463D01*
X1711688D01*
X1715159Y82934D01*
X1722089D01*
X1724600Y85445D01*
X1735195D01*
X1738958Y89208D01*
X1752538D01*
X1759406Y96076D01*
X1769329D01*
X1791082Y74323D01*
X1796654D01*
X1800952Y70025D01*
Y59245D01*
X1799788Y58081D01*
Y54532D01*
X1814270Y40050D01*
Y36698D01*
X1817796Y33172D01*
X1820765D01*
X1823079Y35486D01*
X1826414D01*
G01X1661563Y72028D02*
X1640970D01*
X1637586Y75412D01*
X1629266D01*
X1627126Y77552D01*
X1619619D01*
X1608117Y89054D01*
X1585459D01*
X1584926Y89587D01*
X1582280D01*
X1578468Y85775D01*
X1567208D01*
X1566751Y86232D01*
X1566697D01*
X1562613Y90316D01*
Y123100D01*
X1561380Y124333D01*
Y130286D01*
X1561370Y130296D01*
Y132156D01*
X1561380Y132166D01*
Y137353D01*
X1558839Y139894D01*
X1556709D01*
X1555433Y141170D01*
Y148490D01*
X1559482Y152539D01*
Y161577D01*
X1559483Y161578D01*
Y167598D01*
X1555011Y172070D01*
Y173351D01*
X1553203Y175159D01*
Y194137D01*
X1553917Y194851D01*
Y197948D01*
X1550487Y201378D01*
Y207439D01*
X1553490Y210442D01*
Y214184D01*
X1553489Y214185D01*
Y214807D01*
X1553488Y214808D01*
Y246268D01*
X1550086Y249670D01*
Y250916D01*
X1550087Y250917D01*
Y271421D01*
X1542596Y278912D01*
Y283282D01*
X1541043Y284835D01*
Y290257D01*
X1541680Y290894D01*
Y296318D01*
X1538206Y299792D01*
Y303741D01*
G01X1557981Y141470D02*
X1558434D01*
X1562184Y137720D01*
Y129619D01*
X1564684Y127119D01*
Y124319D01*
X1563365Y123000D01*
Y90628D01*
X1567009Y86984D01*
X1567063D01*
X1567520Y86527D01*
X1578156D01*
X1581969Y90340D01*
X1582591D01*
X1582592Y90339D01*
X1585238D01*
X1585771Y89806D01*
X1612057D01*
X1616834Y85029D01*
Y82078D01*
X1620525Y78387D01*
X1627497D01*
X1629616Y76268D01*
X1647550D01*
X1648590Y75228D01*
X1659715D01*
X1660769Y74174D01*
X1665899D01*
X1667755Y72318D01*
X1681301D01*
X1682946Y72665D01*
X1683972Y73691D01*
Y74997D01*
X1682893Y76076D01*
X1678274D01*
X1676844Y74646D01*
X1676428D01*
G01X1610853Y63861D02*
Y66683D01*
X1607036Y70500D01*
X1601501D01*
X1597924Y74077D01*
Y75755D01*
X1593963Y79716D01*
X1588971D01*
X1584238Y74983D01*
X1583935D01*
X1582704Y73752D01*
X1569526D01*
X1546226Y97052D01*
Y98006D01*
X1546227Y98007D01*
Y104497D01*
X1546405Y104675D01*
Y109556D01*
X1545603Y110358D01*
Y129427D01*
X1545283Y129747D01*
Y141021D01*
X1549369Y145107D01*
Y151006D01*
X1549462Y151099D01*
Y157507D01*
X1550772Y158817D01*
Y164650D01*
X1549506Y165916D01*
X1545915Y169508D01*
Y180713D01*
X1547139Y181937D01*
Y186910D01*
X1544199Y189850D01*
Y203028D01*
X1546727Y205556D01*
Y208999D01*
X1549728Y212000D01*
Y237603D01*
X1547869Y239462D01*
Y243356D01*
G01X1567981Y139607D02*
X1566930Y138556D01*
X1566106D01*
X1565192Y137642D01*
Y132389D01*
X1568775Y128806D01*
Y123262D01*
X1566376Y120863D01*
Y95524D01*
X1569332Y92568D01*
X1571300D01*
X1571309Y92559D01*
X1573863D01*
X1573872Y92568D01*
X1575688D01*
X1575992Y92264D01*
X1579297D01*
X1580647Y93614D01*
X1581269D01*
X1581270Y93615D01*
X1582516D01*
X1582518Y93613D01*
X1583392D01*
X1585985Y96206D01*
X1589300D01*
X1589984Y95522D01*
X1596013D01*
X1596604Y96113D01*
X1598184D01*
X1598897Y95400D01*
X1611395D01*
X1612574Y96579D01*
X1619404D01*
X1620682Y95301D01*
Y93413D01*
X1627955Y86140D01*
Y86139D01*
X1629521Y84573D01*
Y81950D01*
X1631283Y80188D01*
X1631905D01*
X1631906Y80189D01*
X1639889D01*
X1641950Y82250D01*
X1655229D01*
X1658868Y78611D01*
X1660918D01*
X1661173Y78356D01*
X1679355D01*
X1684203Y83204D01*
X1704154D01*
X1706391Y80967D01*
X1707013D01*
X1707014Y80968D01*
X1711065D01*
X1714535Y84438D01*
X1721465D01*
X1723977Y86950D01*
X1725223D01*
X1725224Y86949D01*
X1734571D01*
X1738334Y90712D01*
X1751914D01*
X1762300Y101098D01*
X1768055D01*
X1786848Y82305D01*
X1794158D01*
X1798821Y77642D01*
X1800735D01*
X1816725Y61652D01*
Y55863D01*
X1815637Y54775D01*
G01X1567968Y136682D02*
X1566881Y137769D01*
X1566383D01*
X1565944Y137330D01*
Y132701D01*
X1569527Y129118D01*
Y122950D01*
X1567337Y120760D01*
Y95627D01*
X1569644Y93320D01*
X1576000D01*
X1576304Y93016D01*
X1578985D01*
X1580335Y94366D01*
X1580957D01*
X1580958Y94367D01*
X1582828D01*
X1582830Y94365D01*
X1583080D01*
X1585673Y96958D01*
X1589612D01*
X1590296Y96274D01*
X1595702D01*
X1596292Y96864D01*
X1598496D01*
X1599209Y96151D01*
X1611083D01*
X1612262Y97330D01*
X1619716D01*
X1621434Y95612D01*
Y94990D01*
X1621433Y94989D01*
Y93725D01*
X1622181Y92977D01*
X1622182D01*
X1628706Y86453D01*
Y86452D01*
X1630273Y84885D01*
Y82262D01*
X1631594Y80941D01*
X1639441D01*
X1641502Y83002D01*
X1655541D01*
X1659180Y79363D01*
X1661230D01*
X1661485Y79108D01*
X1679043D01*
X1683891Y83956D01*
X1704466D01*
X1706702Y81720D01*
X1710753D01*
X1714223Y85190D01*
X1716422D01*
X1716423Y85191D01*
X1717045D01*
X1717046Y85190D01*
X1721153D01*
X1723763Y87800D01*
X1734358D01*
X1737811Y91253D01*
X1737812D01*
X1738022Y91463D01*
X1751450D01*
X1757700Y97713D01*
X1757701D01*
X1762038Y102050D01*
X1768450D01*
X1787108Y83392D01*
X1794295D01*
X1799248Y78439D01*
Y78394D01*
X1801330D01*
X1817677Y62047D01*
Y55471D01*
X1818396Y54752D01*
G01X1596900Y84500D02*
X1594937Y82537D01*
X1589098D01*
X1585462Y78901D01*
X1567176D01*
X1550947Y95130D01*
Y116844D01*
X1547521Y120270D01*
Y130203D01*
X1547187Y130537D01*
Y135067D01*
X1547521Y135401D01*
Y139053D01*
X1550438Y141970D01*
Y142061D01*
X1551273Y142896D01*
Y150216D01*
X1551421Y150364D01*
Y152170D01*
X1555322Y156071D01*
Y163303D01*
X1555323Y163304D01*
Y165872D01*
X1553374Y167821D01*
X1550296D01*
X1547819Y170298D01*
Y179923D01*
X1549043Y181147D01*
Y190015D01*
X1548178Y190880D01*
G01X1545910Y199977D02*
X1547576Y198311D01*
Y194926D01*
X1549795Y192707D01*
Y180835D01*
X1548571Y179611D01*
Y170610D01*
X1550608Y168573D01*
X1553686D01*
X1556075Y166184D01*
Y162992D01*
X1556074Y162991D01*
Y155693D01*
X1552342Y151961D01*
Y150221D01*
X1552025Y149904D01*
Y142584D01*
X1551190Y141749D01*
Y141658D01*
X1548346Y138814D01*
Y135162D01*
X1547939Y134755D01*
Y130849D01*
X1548346Y130442D01*
Y120509D01*
X1551699Y117156D01*
Y95442D01*
X1567488Y79653D01*
X1585150D01*
X1587359Y81862D01*
Y84348D01*
G01X1602000Y84500D02*
X1599242Y81742D01*
X1589367D01*
X1585591Y77966D01*
X1566942D01*
X1547379Y97529D01*
Y104019D01*
X1547557Y104197D01*
Y110034D01*
X1546761Y110830D01*
Y129899D01*
X1546435Y130225D01*
Y135379D01*
X1546761Y135705D01*
Y140789D01*
X1550521Y144549D01*
Y150528D01*
X1550669Y150676D01*
Y157084D01*
X1551924Y158339D01*
Y165128D01*
X1550669Y166383D01*
Y166384D01*
X1547067Y169986D01*
Y180235D01*
X1548291Y181459D01*
Y187388D01*
X1546000Y189679D01*
Y197400D01*
G01X1591600Y75700D02*
X1590100Y74200D01*
X1584249D01*
X1583049Y73000D01*
X1568390D01*
X1557226Y84164D01*
X1546386D01*
X1546370Y84180D01*
G01X1536027Y305048D02*
Y300907D01*
X1540928Y296006D01*
Y291206D01*
X1540291Y290569D01*
Y284523D01*
X1541844Y282970D01*
Y278600D01*
X1549334Y271110D01*
Y249358D01*
X1552736Y245956D01*
Y210752D01*
X1549735Y207751D01*
Y201066D01*
X1553092Y197709D01*
Y195090D01*
X1552451Y194449D01*
Y174847D01*
X1554259Y173039D01*
Y171758D01*
X1558731Y167286D01*
Y161890D01*
X1558730Y161889D01*
Y152851D01*
X1554681Y148802D01*
Y140910D01*
X1553424Y139653D01*
Y136482D01*
X1550595Y133653D01*
Y132347D01*
X1551518Y131424D01*
X1552824D01*
X1552854Y131454D01*
X1559148D01*
X1560628Y129974D01*
Y123729D01*
X1561581Y122776D01*
Y90284D01*
X1569321Y82544D01*
X1576597D01*
X1582842Y88789D01*
X1584562D01*
X1585049Y88302D01*
X1607232D01*
X1614866Y80668D01*
Y78485D01*
X1620080Y73271D01*
X1625800D01*
X1627489Y74960D01*
G01X1562850Y73642D02*
X1561886D01*
X1555693Y79835D01*
X1546350D01*
X1543985Y82200D01*
Y85097D01*
X1545668Y86780D01*
X1545900D01*
X1546830Y87710D01*
Y89010D01*
X1546674Y89166D01*
Y93910D01*
X1544323Y96261D01*
Y105287D01*
X1544501Y105465D01*
Y108380D01*
X1543386Y109495D01*
Y117914D01*
X1542100Y119200D01*
G01X1542900Y121700D02*
Y120976D01*
X1544360Y119516D01*
Y109971D01*
X1545253Y109078D01*
Y105153D01*
X1545075Y104975D01*
Y96573D01*
X1546978Y94670D01*
X1546990D01*
X1547430Y94230D01*
Y89480D01*
X1547590Y89320D01*
Y87400D01*
X1546210Y86020D01*
X1545980D01*
X1544737Y84777D01*
Y82512D01*
X1546528Y80721D01*
X1556073D01*
X1560563Y76231D01*
X1562575D01*
G01X1555676Y123283D02*
Y105849D01*
X1559912Y101613D01*
Y97783D01*
X1556929Y94800D01*
X1556200D01*
G01X1535065Y164300D02*
X1535308Y164057D01*
Y162337D01*
X1537562Y160083D01*
Y151268D01*
X1535037Y148743D01*
Y131169D01*
X1529061Y125193D01*
Y122569D01*
X1529752Y121878D01*
Y118411D01*
X1541421Y106742D01*
G01X1533719Y362783D02*
X1532214Y361278D01*
Y359630D01*
X1533943Y357901D01*
Y355615D01*
X1533894Y355566D01*
Y348793D01*
X1546775Y335912D01*
X1547538D01*
X1549596Y333854D01*
Y329902D01*
X1551932Y327566D01*
Y324890D01*
X1554330Y322492D01*
Y318294D01*
X1553157Y317121D01*
Y305095D01*
X1557924Y300328D01*
Y282873D01*
X1563080Y277717D01*
Y270329D01*
X1563079Y270328D01*
Y267210D01*
X1563080Y267209D01*
Y266949D01*
X1569526Y260503D01*
Y259347D01*
X1569527Y259346D01*
Y258724D01*
X1569526Y258723D01*
Y254807D01*
X1571788Y252545D01*
Y247305D01*
X1577228Y241865D01*
Y231706D01*
X1570744Y225222D01*
Y224772D01*
X1570743Y224771D01*
Y216037D01*
X1570744Y216036D01*
Y186825D01*
X1580471Y177098D01*
Y173100D01*
X1583593Y169978D01*
Y156903D01*
X1590193Y150303D01*
X1598740D01*
X1600148Y151711D01*
G01X1596427Y157975D02*
X1593525Y155073D01*
X1592749D01*
X1592748Y155072D01*
X1592437D01*
X1592436Y155071D01*
X1587553D01*
X1585470Y157154D01*
Y170229D01*
X1581975Y173724D01*
Y177722D01*
X1572248Y187449D01*
Y216660D01*
X1572247Y216661D01*
Y224147D01*
X1572248Y224148D01*
Y224598D01*
X1578732Y231082D01*
Y241241D01*
X1578733Y241242D01*
Y242488D01*
X1573452Y247769D01*
Y258965D01*
X1564583Y267834D01*
Y269704D01*
X1564584Y269705D01*
Y278341D01*
X1562197Y280728D01*
Y286803D01*
X1561144Y287856D01*
Y291385D01*
X1559156Y293373D01*
Y300160D01*
X1553909Y305407D01*
Y316809D01*
X1555082Y317982D01*
Y322804D01*
X1552684Y325202D01*
Y327878D01*
X1550348Y330214D01*
Y334166D01*
X1547850Y336664D01*
X1547087D01*
X1534646Y349105D01*
Y355254D01*
X1534695Y355303D01*
Y359378D01*
X1533790Y360283D01*
G01X1604169Y156407D02*
X1599799D01*
X1598733Y157473D01*
Y157891D01*
X1597174Y159450D01*
X1595816D01*
X1594203Y157837D01*
Y157354D01*
X1594177Y157328D01*
Y157326D01*
X1592874Y156023D01*
X1592872D01*
X1592673Y155824D01*
X1592437D01*
X1592436Y155823D01*
X1587865D01*
X1586222Y157466D01*
Y170613D01*
X1582727Y174108D01*
Y178034D01*
X1573000Y187761D01*
Y216972D01*
X1572999Y216973D01*
Y223835D01*
X1573000Y223836D01*
Y224286D01*
X1579484Y230770D01*
Y240929D01*
X1579485Y240930D01*
Y242800D01*
X1574204Y248081D01*
Y259277D01*
X1565335Y268146D01*
Y269392D01*
X1565336Y269393D01*
Y278653D01*
X1562949Y281040D01*
Y287176D01*
X1561896Y288229D01*
Y292150D01*
X1559908Y294138D01*
Y300472D01*
X1554661Y305719D01*
Y316497D01*
X1555834Y317670D01*
Y323116D01*
X1553436Y325514D01*
Y328190D01*
X1551100Y330526D01*
Y334478D01*
X1548162Y337416D01*
X1547399D01*
X1535398Y349417D01*
Y354942D01*
X1536085Y355629D01*
Y359549D01*
X1538397Y361861D01*
G01X1579290Y131104D02*
X1576946Y128760D01*
Y115651D01*
X1574690Y113395D01*
Y105091D01*
X1573320Y103721D01*
X1573153D01*
G01X1576606Y104392D02*
X1575642Y105356D01*
Y113000D01*
X1577898Y115256D01*
Y128061D01*
X1578441Y128604D01*
X1579310D01*
G01X1543100Y184128D02*
X1544411Y182817D01*
Y168884D01*
X1548848Y164444D01*
X1549255Y164037D01*
Y159734D01*
X1547730Y158209D01*
Y146106D01*
X1543779Y142155D01*
Y134415D01*
X1542685Y133321D01*
G01X1574197Y127915D02*
X1573525D01*
X1573098Y128342D01*
Y146098D01*
X1572424Y146772D01*
Y160603D01*
X1575145Y163324D01*
Y170875D01*
X1568861Y177159D01*
X1567304D01*
X1564158Y180305D01*
Y190268D01*
X1565205Y191315D01*
Y230459D01*
X1566440Y231694D01*
Y239435D01*
X1566441Y239436D01*
Y242554D01*
X1566440Y242555D01*
Y242834D01*
X1565028Y244246D01*
Y252810D01*
X1563942Y253896D01*
X1563921D01*
X1563913Y253888D01*
X1563291D01*
X1563290Y253887D01*
X1562668D01*
X1562660Y253895D01*
X1562513D01*
X1559969Y256439D01*
Y273538D01*
X1554476Y279031D01*
Y282353D01*
X1553535Y283294D01*
Y288480D01*
X1552447Y289568D01*
Y297879D01*
X1548291Y302035D01*
Y307021D01*
X1547572Y307740D01*
Y310061D01*
X1546306Y311327D01*
Y327886D01*
X1542990Y331202D01*
Y332058D01*
X1542576Y332472D01*
Y337939D01*
X1532390Y348125D01*
Y353498D01*
X1528104Y357784D01*
Y380523D01*
X1528475Y380894D01*
G01X1574197Y127915D02*
X1574819D01*
X1575540Y128636D01*
Y132340D01*
X1576512Y133312D01*
X1580241D01*
X1590109Y123444D01*
X1616298D01*
X1616501Y123241D01*
X1627259D01*
X1630974Y119526D01*
Y117900D01*
X1631874Y117000D01*
X1633700D01*
X1635150Y115550D01*
Y112350D01*
X1637463Y110037D01*
Y106537D01*
X1641000Y103000D01*
X1652351D01*
X1653111Y102240D01*
G01X1545802Y233529D02*
X1543319Y231046D01*
Y206970D01*
X1540584Y204235D01*
Y186535D01*
X1539620Y185571D01*
Y180665D01*
X1541708Y178577D01*
Y177623D01*
X1541707Y177622D01*
Y168582D01*
X1541706Y168581D01*
Y167627D01*
X1541707Y167626D01*
Y167388D01*
X1546599Y162496D01*
Y160836D01*
X1545074Y159311D01*
Y148156D01*
X1538072Y141154D01*
Y130146D01*
X1531726Y123800D01*
G01X1607441Y153286D02*
X1603859D01*
X1603038Y154107D01*
X1587453D01*
X1584346Y157214D01*
Y170289D01*
X1581223Y173412D01*
Y177410D01*
X1571496Y187137D01*
Y216348D01*
X1571495Y216349D01*
Y224459D01*
X1571496Y224460D01*
Y224910D01*
X1577980Y231394D01*
Y241553D01*
X1577981Y241554D01*
Y242176D01*
X1572540Y247617D01*
Y252857D01*
X1570278Y255119D01*
Y258411D01*
X1570279Y258412D01*
Y259034D01*
X1570280Y259035D01*
Y259657D01*
X1570278Y259659D01*
Y260831D01*
X1563832Y267277D01*
Y267521D01*
X1563831Y267522D01*
Y270016D01*
X1563832Y270017D01*
Y278029D01*
X1561376Y280485D01*
Y286268D01*
X1559500Y288144D01*
Y290300D01*
G01X1570272Y234889D02*
Y230704D01*
X1568213Y228645D01*
Y186164D01*
X1573479Y180898D01*
Y176028D01*
X1579213Y170294D01*
Y156537D01*
X1602916Y132834D01*
X1609036D01*
X1610591Y134389D01*
G01X1613741Y140688D02*
X1612266Y142163D01*
X1611204D01*
X1611203Y142164D01*
X1609979D01*
X1609978Y142163D01*
X1609155D01*
X1607639Y140647D01*
X1597006D01*
X1581450Y156203D01*
Y169739D01*
X1578567Y172622D01*
Y176874D01*
X1569239Y186202D01*
Y226411D01*
X1572730Y229902D01*
Y235931D01*
G01X1551250Y320303D02*
X1550600Y319653D01*
Y313182D01*
X1548324Y310906D01*
Y308052D01*
X1549044Y307332D01*
Y304284D01*
X1549043Y304283D01*
Y302367D01*
X1553199Y298211D01*
Y289880D01*
X1554287Y288792D01*
Y283742D01*
X1555300Y282729D01*
Y279271D01*
X1560721Y273850D01*
Y256751D01*
X1562824Y254648D01*
X1562971D01*
X1562979Y254640D01*
X1563601D01*
X1563609Y254648D01*
X1564254D01*
X1565780Y253122D01*
Y244558D01*
X1567192Y243146D01*
Y242867D01*
X1567193Y242866D01*
Y239124D01*
X1567192Y239123D01*
Y231382D01*
X1565957Y230147D01*
Y184871D01*
X1564910Y183824D01*
Y180617D01*
X1566413Y179114D01*
X1567970D01*
X1575897Y171187D01*
Y148622D01*
X1581905Y142614D01*
Y133344D01*
X1590310Y124939D01*
X1604975D01*
X1606450Y126414D01*
X1612266D01*
X1613690Y124990D01*
G01X1547398Y333823D02*
X1546424Y332849D01*
Y330705D01*
X1551180Y325949D01*
Y324313D01*
X1553578Y321915D01*
Y318606D01*
X1552150Y317178D01*
Y312437D01*
X1549828Y310115D01*
Y308676D01*
X1552280Y306224D01*
Y304908D01*
X1557172Y300016D01*
Y282561D01*
X1562309Y277424D01*
Y266532D01*
X1568774Y260067D01*
Y254495D01*
X1571036Y252233D01*
Y246993D01*
X1576476Y241553D01*
Y232018D01*
X1569992Y225534D01*
Y225084D01*
X1569991Y225083D01*
Y215725D01*
X1569992Y215724D01*
Y186513D01*
X1579719Y176786D01*
Y172788D01*
X1582669Y169838D01*
Y156763D01*
X1594033Y145399D01*
X1609003D01*
X1610591Y146987D01*
G01X1558700Y252000D02*
X1560257Y250443D01*
Y245546D01*
X1564185Y241618D01*
Y240372D01*
X1564184Y240371D01*
Y232656D01*
X1561200Y229672D01*
Y194504D01*
X1560349Y193653D01*
Y178918D01*
X1563384Y175883D01*
Y171966D01*
X1566912Y168438D01*
Y147652D01*
X1570279Y144285D01*
Y122447D01*
X1568657Y120825D01*
Y112720D01*
X1568363Y112426D01*
Y102680D01*
X1572497Y98546D01*
X1572634D01*
G01X1589592Y252472D02*
Y250925D01*
X1587838Y249171D01*
Y226970D01*
X1581272Y220404D01*
Y197664D01*
X1585020Y193916D01*
Y188112D01*
X1590224Y182908D01*
G01X1591642Y181490D02*
Y178876D01*
X1595273Y175245D01*
X1601513D01*
X1604348Y172410D01*
Y169910D01*
X1609883Y164375D01*
X1612101D01*
X1613741Y162735D01*
G01X1572336Y287063D02*
X1570791D01*
X1569717Y285989D01*
Y283848D01*
X1572278Y281287D01*
Y270779D01*
X1580972Y262085D01*
Y250889D01*
X1586254Y245607D01*
Y239993D01*
X1586253Y239992D01*
Y237808D01*
X1586252Y237807D01*
Y227512D01*
X1579767Y221027D01*
Y219781D01*
X1579768Y219780D01*
Y197040D01*
X1579921Y196887D01*
G01X1590138Y180104D02*
Y176763D01*
X1592877Y174024D01*
Y174023D01*
X1593240Y173660D01*
X1598252D01*
X1599666Y172246D01*
Y170510D01*
X1607441Y162735D01*
G01X1613741Y146987D02*
X1612100Y148628D01*
Y153863D01*
X1611003Y154960D01*
X1609981D01*
X1608924Y156017D01*
Y157039D01*
X1607854Y158109D01*
X1606830D01*
X1604631Y160308D01*
X1603768D01*
X1595768Y168308D01*
X1594706D01*
X1590955Y172059D01*
Y172754D01*
X1587239Y176470D01*
Y179906D01*
X1577512Y189633D01*
Y218844D01*
X1577511Y218845D01*
Y221963D01*
X1577512Y221964D01*
Y222414D01*
X1583996Y228898D01*
Y239057D01*
X1583997Y239058D01*
Y240928D01*
X1583998Y240929D01*
Y244671D01*
X1578716Y249953D01*
Y261149D01*
X1570021Y269844D01*
Y271714D01*
X1570022Y271715D01*
Y280351D01*
X1567461Y282912D01*
Y287126D01*
X1569362Y289027D01*
Y293268D01*
X1567461Y295169D01*
Y303737D01*
X1565317Y305881D01*
X1563609D01*
X1561976Y307514D01*
Y323924D01*
X1558448Y327452D01*
Y334159D01*
X1552472Y340135D01*
Y342328D01*
X1545900Y348900D01*
Y352800D01*
X1547800Y354700D01*
Y356768D01*
X1543668Y360900D01*
X1543300D01*
G01X1532367Y356530D02*
X1533142Y355755D01*
Y348437D01*
X1543328Y338251D01*
Y333355D01*
X1543742Y332941D01*
Y332084D01*
X1547605Y328221D01*
X1547839D01*
X1550428Y325632D01*
Y324001D01*
X1552826Y321603D01*
Y319381D01*
X1551398Y317953D01*
Y312916D01*
X1549076Y310594D01*
Y308364D01*
X1551192Y306248D01*
Y304932D01*
X1556376Y299748D01*
Y279398D01*
X1561473Y274301D01*
Y257063D01*
X1563136Y255400D01*
X1564566D01*
X1566540Y253426D01*
Y244862D01*
X1567944Y243458D01*
Y243179D01*
X1567945Y243178D01*
Y238812D01*
X1567944Y238811D01*
Y231070D01*
X1566709Y229835D01*
Y185540D01*
X1567601Y184648D01*
Y182385D01*
X1566486Y181270D01*
G01X1600490Y167459D02*
X1597891Y170058D01*
X1595082D01*
X1593628Y171512D01*
Y171513D01*
X1592877Y172264D01*
Y172265D01*
X1592642Y172500D01*
Y173195D01*
X1589125Y176712D01*
Y180148D01*
X1579016Y190257D01*
Y219468D01*
X1579015Y219469D01*
Y221339D01*
X1585500Y227824D01*
Y238119D01*
X1585501Y238120D01*
Y240304D01*
X1585502Y240305D01*
Y245295D01*
X1580220Y250577D01*
Y261773D01*
X1571525Y270468D01*
Y271090D01*
X1571526Y271091D01*
Y280975D01*
X1568965Y283536D01*
Y286502D01*
X1572750Y290287D01*
Y299585D01*
X1569855Y302480D01*
Y304559D01*
X1566078Y308336D01*
Y312018D01*
X1564411Y313685D01*
Y315210D01*
G01X1571501Y180031D02*
X1568601Y182931D01*
Y184712D01*
X1567461Y185852D01*
Y229388D01*
X1568696Y230623D01*
Y238499D01*
X1568697Y238500D01*
Y243490D01*
X1568696Y243491D01*
Y244788D01*
X1570071Y246163D01*
Y252060D01*
X1567524Y254607D01*
Y259036D01*
X1567000Y259560D01*
G01X1538500Y359363D02*
X1536902Y357765D01*
Y355382D01*
X1536150Y354630D01*
Y349729D01*
X1547711Y338168D01*
X1548474D01*
X1551852Y334790D01*
Y330838D01*
X1554188Y328502D01*
Y325826D01*
X1556586Y323428D01*
Y317358D01*
X1555413Y316185D01*
Y306031D01*
X1560660Y300784D01*
Y294909D01*
X1562648Y292921D01*
Y288541D01*
X1563701Y287488D01*
Y281352D01*
X1566088Y278965D01*
Y269081D01*
X1566087Y269080D01*
Y268458D01*
X1574956Y259589D01*
Y248393D01*
X1580238Y243111D01*
Y242489D01*
X1580237Y242488D01*
Y240618D01*
X1580236Y240617D01*
Y230458D01*
X1573752Y223974D01*
Y223524D01*
X1573751Y223523D01*
Y217285D01*
X1573752Y217284D01*
Y188073D01*
X1583479Y178346D01*
Y174516D01*
X1586974Y171021D01*
Y161140D01*
X1590474Y157640D01*
Y157638D01*
X1591338Y156774D01*
X1591340D01*
X1591539Y156575D01*
X1592361D01*
X1592560Y156774D01*
X1592562D01*
X1593426Y157638D01*
Y157640D01*
X1593450Y157664D01*
Y158147D01*
X1595504Y160201D01*
X1598299D01*
X1600490Y158010D01*
G01X1538478Y350694D02*
Y349593D01*
X1547447Y340624D01*
X1548646D01*
X1553356Y335914D01*
Y331518D01*
X1555693Y329181D01*
Y326449D01*
X1559578Y322564D01*
Y314382D01*
X1556917Y311721D01*
Y306655D01*
X1562164Y301408D01*
Y296097D01*
X1566870Y291391D01*
Y289727D01*
X1565205Y288062D01*
Y281976D01*
X1567766Y279415D01*
Y272651D01*
X1567765Y272650D01*
Y268908D01*
X1576460Y260213D01*
Y249017D01*
X1581742Y243735D01*
Y241865D01*
X1581741Y241864D01*
Y239994D01*
X1581740Y239993D01*
Y229834D01*
X1575256Y223350D01*
Y222900D01*
X1575255Y222899D01*
Y217909D01*
X1575256Y217908D01*
Y188697D01*
X1584983Y178970D01*
Y175384D01*
X1588478Y171889D01*
Y163251D01*
X1590395Y161334D01*
X1600384D01*
X1603806Y157912D01*
X1604750D01*
X1605768Y156894D01*
Y156023D01*
X1607030Y154761D01*
X1609116D01*
X1610591Y153286D01*
G01X1538478Y353294D02*
X1540100Y351672D01*
Y349200D01*
X1542364Y346936D01*
X1545664D01*
X1550932Y341668D01*
Y339402D01*
X1556900Y333434D01*
Y326306D01*
X1560330Y322876D01*
Y314070D01*
X1557669Y311409D01*
Y306967D01*
X1562916Y301720D01*
Y296845D01*
X1567622Y292139D01*
Y289415D01*
X1565957Y287750D01*
Y282288D01*
X1568518Y279727D01*
Y272339D01*
X1568517Y272338D01*
Y269220D01*
X1577212Y260525D01*
Y249329D01*
X1582494Y244047D01*
Y241553D01*
X1582493Y241552D01*
Y239682D01*
X1582492Y239681D01*
Y229522D01*
X1576008Y223038D01*
Y222588D01*
X1576007Y222587D01*
Y218221D01*
X1576008Y218220D01*
Y189009D01*
X1585735Y179282D01*
Y175760D01*
X1589272Y172223D01*
Y164728D01*
X1590676Y163324D01*
X1599458D01*
X1603847Y158935D01*
X1604863D01*
X1607362Y156436D01*
X1607441D01*
G01X1538478Y355894D02*
X1536902Y354318D01*
Y350041D01*
X1548023Y338920D01*
X1548786D01*
X1552604Y335102D01*
Y331206D01*
X1554941Y328869D01*
Y326137D01*
X1558826Y322252D01*
Y314694D01*
X1556165Y312033D01*
Y306343D01*
X1561412Y301096D01*
Y295389D01*
X1563400Y293401D01*
Y288853D01*
X1564453Y287800D01*
Y281664D01*
X1566840Y279277D01*
Y268769D01*
X1575708Y259901D01*
Y248705D01*
X1580990Y243423D01*
Y242177D01*
X1580989Y242176D01*
Y240306D01*
X1580988Y240305D01*
Y230146D01*
X1574504Y223662D01*
Y223212D01*
X1574503Y223211D01*
Y217597D01*
X1574504Y217596D01*
Y188385D01*
X1584231Y178658D01*
Y174828D01*
X1587726Y171333D01*
Y162474D01*
X1591950Y158250D01*
G01X1595291Y166423D02*
X1590024Y171690D01*
Y172597D01*
X1586487Y176134D01*
Y179594D01*
X1576760Y189321D01*
Y218532D01*
X1576759Y218533D01*
Y222275D01*
X1576760Y222276D01*
Y222726D01*
X1583244Y229210D01*
Y239369D01*
X1583245Y239370D01*
Y241240D01*
X1583246Y241241D01*
Y244359D01*
X1577964Y249641D01*
Y260837D01*
X1569269Y269532D01*
Y272026D01*
X1569270Y272027D01*
Y280039D01*
X1566709Y282600D01*
Y287438D01*
X1568405Y289134D01*
Y292845D01*
X1563668Y297582D01*
Y302032D01*
X1558421Y307279D01*
Y311053D01*
X1561082Y313714D01*
Y323188D01*
X1557670Y326600D01*
Y333873D01*
X1551720Y339823D01*
Y341980D01*
X1546012Y347688D01*
X1542712D01*
X1540900Y349500D01*
Y364221D01*
X1528855Y376266D01*
Y378165D01*
X1530045Y379355D01*
Y382183D01*
X1528855Y383373D01*
Y387274D01*
X1528475Y387654D01*
G01X1566910Y315117D02*
X1566830Y315037D01*
Y308648D01*
X1569190Y306288D01*
X1569252D01*
X1571040Y304500D01*
Y302560D01*
X1574080Y299520D01*
Y289417D01*
X1575393Y288104D01*
Y278531D01*
X1593289Y260635D01*
Y260634D01*
X1593304Y260619D01*
Y259229D01*
X1593289Y259214D01*
Y258275D01*
X1593305Y258259D01*
X1593304Y258258D01*
Y256136D01*
X1593305Y256135D01*
Y256097D01*
X1591360Y254152D01*
Y251629D01*
X1588590Y248859D01*
Y226658D01*
X1582298Y220366D01*
Y208422D01*
X1582024Y208148D01*
Y197976D01*
X1585973Y194027D01*
Y189016D01*
X1592629Y182360D01*
Y178953D01*
X1595586Y175996D01*
X1601976D01*
X1605100Y172872D01*
Y171940D01*
X1610591Y166449D01*
Y165885D01*
G01X1573790Y284895D02*
Y275868D01*
X1584701Y264957D01*
Y260870D01*
X1584754Y260817D01*
Y257825D01*
X1584723Y257794D01*
Y256427D01*
X1584701Y256405D01*
Y250959D01*
X1587086Y248571D01*
Y227282D01*
X1580519Y220715D01*
Y220093D01*
X1580520Y220092D01*
Y197352D01*
X1580673Y197199D01*
Y190727D01*
X1590224Y181176D01*
G01X1590890Y180510D02*
Y178364D01*
X1594764Y174490D01*
X1601176D01*
X1603369Y172297D01*
Y168894D01*
X1608052Y164211D01*
X1608053D01*
X1608917Y163347D01*
Y163346D01*
X1609021Y163242D01*
Y162219D01*
X1609115Y162125D01*
Y162123D01*
X1609979Y161259D01*
X1611004D01*
X1611202Y161061D01*
X1611203D01*
X1612067Y160197D01*
Y159032D01*
X1613187Y157912D01*
X1614353D01*
X1615217Y157048D01*
Y157047D01*
X1615300Y156964D01*
Y151696D01*
X1613741Y150137D01*
G01X1536275Y394414D02*
X1535484D01*
X1531995Y390925D01*
Y390383D01*
X1530805Y389193D01*
Y386115D01*
X1531995Y384925D01*
Y382895D01*
X1530805Y381705D01*
Y379355D01*
X1531995Y378165D01*
Y376560D01*
X1538340Y370215D01*
X1540554D01*
X1545696Y365073D01*
Y360447D01*
X1549106Y357037D01*
Y354706D01*
X1546700Y352300D01*
Y349200D01*
X1553224Y342676D01*
Y340447D01*
X1555119Y338552D01*
X1555501D01*
X1562801Y331252D01*
Y307753D01*
X1563921Y306633D01*
X1565629D01*
X1568806Y303456D01*
Y302156D01*
X1571800Y299162D01*
Y290401D01*
X1568213Y286814D01*
Y283224D01*
X1570774Y280663D01*
Y271403D01*
X1570773Y271402D01*
Y270156D01*
X1579468Y261461D01*
Y250265D01*
X1584750Y244983D01*
Y240617D01*
X1584749Y240616D01*
Y238746D01*
X1584748Y238745D01*
Y228136D01*
X1578263Y221651D01*
Y219157D01*
X1578264Y219156D01*
Y189945D01*
X1587991Y180218D01*
Y176782D01*
X1591890Y172883D01*
Y172188D01*
X1592877Y171201D01*
Y171200D01*
X1595017Y169060D01*
X1596080D01*
X1604079Y161061D01*
X1608052D01*
X1609115Y159998D01*
Y158975D01*
X1609981Y158109D01*
X1611148D01*
X1612821Y156436D01*
X1613741D01*
G01X1591865Y237407D02*
Y234363D01*
X1592950Y233278D01*
Y222484D01*
X1587511Y217045D01*
Y211691D01*
X1595022Y204180D01*
Y188080D01*
X1594133Y187191D01*
Y179738D01*
X1596373Y177498D01*
X1603826D01*
X1607358Y173966D01*
Y172757D01*
X1609001Y171114D01*
X1612963D01*
X1616677Y167400D01*
X1617663D01*
X1618564Y166499D01*
Y162123D01*
X1619428Y161259D01*
X1619429D01*
X1619482Y161206D01*
X1621427D01*
X1623048Y159585D01*
X1623189D01*
G01X1587549Y192000D02*
Y189652D01*
X1593381Y183820D01*
Y179265D01*
X1595899Y176747D01*
X1602917D01*
X1605902Y173762D01*
Y173150D01*
X1606606Y172446D01*
Y172445D01*
X1608689Y170362D01*
X1608690D01*
X1609553Y169499D01*
X1613101D01*
X1615286Y167314D01*
Y162009D01*
X1616890Y160405D01*
Y159585D01*
G01X1607441Y134389D02*
X1607889D01*
X1609116Y135616D01*
Y138350D01*
X1609979Y139213D01*
X1614353D01*
X1615216Y140076D01*
Y148216D01*
X1615662Y148662D01*
X1617503D01*
X1618366Y149525D01*
Y150703D01*
X1619488Y151825D01*
X1620712D01*
X1621575Y152688D01*
Y154075D01*
X1624864Y157364D01*
Y169364D01*
X1626500Y171000D01*
Y173500D01*
X1625288Y174712D01*
X1622288D01*
X1618397Y178603D01*
X1617223D01*
X1614826Y181000D01*
X1611000D01*
X1609000Y179000D01*
X1601666D01*
X1600610Y180056D01*
Y181890D01*
X1598961Y183539D01*
Y187461D01*
X1601500Y190000D01*
Y194787D01*
X1600500Y195787D01*
Y204000D01*
X1596204Y208296D01*
Y232016D01*
X1593786Y234434D01*
Y238608D01*
X1590562Y241832D01*
Y249124D01*
X1592512Y251074D01*
Y253674D01*
X1594457Y255619D01*
Y256613D01*
X1594456Y256614D01*
Y257780D01*
X1594458Y257782D01*
Y258736D01*
X1594450Y258745D01*
X1594456Y258751D01*
Y261097D01*
X1594441Y261112D01*
Y261113D01*
X1584568Y270986D01*
Y281339D01*
G01X1645237Y159585D02*
X1643762Y161060D01*
X1642700D01*
X1642699Y161061D01*
X1641475D01*
X1641474Y161060D01*
X1639551D01*
X1639550Y161061D01*
X1638460D01*
X1637264Y162257D01*
Y163347D01*
X1636400Y164211D01*
X1635068D01*
X1630056Y169223D01*
Y173128D01*
X1623830Y179354D01*
X1617535D01*
X1614544Y182345D01*
X1602154D01*
X1600369Y184130D01*
Y186877D01*
X1602909Y189417D01*
Y195370D01*
X1602266Y196013D01*
Y204226D01*
X1597612Y208880D01*
Y232600D01*
X1595425Y234787D01*
Y240201D01*
X1591970Y243656D01*
Y248540D01*
X1593920Y250490D01*
Y253090D01*
X1595865Y255035D01*
Y257197D01*
X1595866Y257198D01*
Y259320D01*
X1595864Y259322D01*
Y261681D01*
X1595849Y261696D01*
Y261697D01*
X1586344Y271202D01*
Y282075D01*
X1585304Y283115D01*
X1583832D01*
X1582558Y281841D01*
X1579023D01*
X1576801Y284063D01*
Y288688D01*
X1575646Y289843D01*
Y301886D01*
X1571263Y306269D01*
Y306727D01*
X1569926Y308064D01*
G01X1578790Y290920D02*
X1581619D01*
X1597351Y275188D01*
Y264364D01*
X1598778Y262937D01*
Y262034D01*
X1598776Y262032D01*
Y260530D01*
X1601308Y257998D01*
Y253494D01*
X1600379Y252565D01*
Y250537D01*
X1600380Y250536D01*
Y246938D01*
X1599752Y246310D01*
X1599270D01*
G01X1568524Y312885D02*
X1572742Y308667D01*
Y306782D01*
X1577648Y301876D01*
Y294677D01*
X1577054Y294083D01*
Y290427D01*
X1578878Y288603D01*
Y287023D01*
X1581076Y284825D01*
X1581077D01*
G01X1627326Y182759D02*
X1625066D01*
X1623823Y184004D01*
Y185713D01*
X1622901Y186635D01*
X1619645D01*
X1612280Y194000D01*
Y197268D01*
X1599772Y209776D01*
Y238910D01*
X1595019Y243663D01*
Y247015D01*
X1595978Y247974D01*
X1597673D01*
X1598923Y249224D01*
Y252173D01*
X1600556Y253806D01*
Y257686D01*
X1598024Y260218D01*
Y262344D01*
X1598026Y262346D01*
Y262577D01*
X1596263Y264340D01*
Y275212D01*
X1586200Y285275D01*
X1581527D01*
X1581077Y284825D01*
G01X1550639Y350200D02*
X1550726Y350113D01*
X1553010D01*
X1561424Y341699D01*
Y340347D01*
X1566950Y334821D01*
Y331574D01*
X1568558Y329966D01*
X1568572D01*
X1577250Y321288D01*
Y316690D01*
X1579258Y314682D01*
Y309242D01*
X1581294Y307206D01*
Y300426D01*
X1584633Y297087D01*
Y293226D01*
X1601922Y275937D01*
Y274127D01*
X1607219Y268830D01*
Y266050D01*
X1612623Y260646D01*
Y240836D01*
X1611816Y240029D01*
Y220123D01*
X1631561Y200378D01*
X1638362D01*
X1640802Y197938D01*
Y196601D01*
X1642668Y194735D01*
X1647505D01*
X1648615Y193625D01*
X1652386D01*
X1659819Y186192D01*
X1663720D01*
X1667140Y182772D01*
Y182300D01*
G01X1610554Y184877D02*
X1608773Y183096D01*
X1602704D01*
X1601556Y184244D01*
Y186072D01*
X1604317Y188833D01*
Y195954D01*
X1603674Y196597D01*
Y204810D01*
X1599020Y209464D01*
Y238598D01*
X1594267Y243351D01*
Y247327D01*
X1595666Y248726D01*
X1597361D01*
X1598171Y249536D01*
Y252485D01*
X1599804Y254118D01*
Y257374D01*
X1597272Y259906D01*
Y262265D01*
X1597257Y262280D01*
Y262282D01*
X1595510Y264029D01*
Y264651D01*
X1595511Y264652D01*
Y274900D01*
X1585888Y284523D01*
X1583248D01*
X1581974Y283249D01*
X1580424D01*
X1578874Y284799D01*
X1578577D01*
G01X1553825Y397794D02*
X1552081Y396050D01*
X1547390D01*
X1546405Y395065D01*
Y393763D01*
X1548150Y392018D01*
Y390588D01*
X1549338Y389400D01*
X1552350D01*
X1553445Y388305D01*
Y379355D01*
X1552255Y378165D01*
Y376863D01*
X1553174Y375944D01*
X1553216D01*
X1565100Y364060D01*
Y363017D01*
X1566470Y361647D01*
X1567185D01*
X1586914Y341918D01*
Y340800D01*
X1596190Y331524D01*
Y310542D01*
X1595246Y309598D01*
Y295109D01*
X1613785Y276570D01*
X1616589D01*
X1618406Y274753D01*
X1618407D01*
X1619082Y274078D01*
Y270288D01*
X1621415Y267955D01*
Y267888D01*
X1621455Y267848D01*
Y262453D01*
X1623345Y260563D01*
Y249442D01*
X1623346Y249441D01*
Y248819D01*
X1623347Y248818D01*
Y248196D01*
X1621455Y246304D01*
Y237172D01*
X1620864Y236581D01*
Y229870D01*
X1623773Y226961D01*
Y224308D01*
X1625261Y222820D01*
X1630423D01*
X1630851Y222392D01*
X1632598D01*
X1638348Y216642D01*
Y213785D01*
X1643675Y208458D01*
X1649584D01*
X1654070Y203972D01*
X1661125D01*
X1662814Y202283D01*
Y199642D01*
X1663899Y198557D01*
X1669043D01*
X1673310Y194290D01*
X1682200D01*
X1683864Y195954D01*
X1704744D01*
X1712198Y188500D01*
X1722807D01*
X1727815Y183492D01*
X1771600D01*
X1774048Y181044D01*
Y175524D01*
X1774100Y175472D01*
Y175300D01*
X1775927Y173473D01*
X1781564D01*
X1782680Y172357D01*
X1787063D01*
X1790624Y168796D01*
X1796021D01*
X1798688Y166129D01*
Y143136D01*
X1799924Y141900D01*
X1807357D01*
X1815883Y133374D01*
Y133277D01*
G01X1542300Y376717D02*
X1544679D01*
X1555243Y366153D01*
Y360667D01*
X1557380Y358530D01*
X1558177D01*
X1576320Y340387D01*
Y330670D01*
X1580296Y326694D01*
Y319282D01*
X1580258Y319244D01*
Y317938D01*
X1581181Y317015D01*
X1583655D01*
X1584826Y318186D01*
X1586132D01*
X1587450Y316868D01*
Y313687D01*
X1590164Y310973D01*
Y293015D01*
X1605682Y277497D01*
Y276445D01*
X1616383Y265744D01*
Y239276D01*
X1615576Y238469D01*
Y221683D01*
X1633121Y204138D01*
X1647013D01*
X1659091Y192060D01*
X1665688D01*
X1669878Y187870D01*
X1681780D01*
X1687992Y181658D01*
Y180376D01*
X1689210Y179158D01*
X1690376D01*
X1690377Y179159D01*
X1701183D01*
X1707149Y173193D01*
X1715923D01*
X1720001Y169115D01*
X1778878D01*
X1781800Y166193D01*
Y165260D01*
X1784889Y162171D01*
X1788889D01*
X1794632Y156428D01*
Y141454D01*
X1798830Y137256D01*
X1802266D01*
X1809085Y130437D01*
Y127675D01*
X1806589Y125179D01*
Y125166D01*
X1804619Y123196D01*
Y117300D01*
X1806500Y115419D01*
Y113518D01*
X1808313Y111705D01*
G01X1807509Y128500D02*
X1806600Y129409D01*
Y130800D01*
X1800896Y136504D01*
X1798518D01*
X1793880Y141142D01*
Y156116D01*
X1788577Y161419D01*
X1784577D01*
X1781047Y164949D01*
Y165571D01*
X1781048Y165572D01*
Y165881D01*
X1778566Y168363D01*
X1719689D01*
X1715611Y172441D01*
X1706837D01*
X1701354Y177924D01*
X1686416D01*
X1682770Y181570D01*
X1679758D01*
X1676218Y185110D01*
X1671146D01*
X1664948Y191308D01*
X1659403D01*
X1659402Y191307D01*
X1658780D01*
X1646701Y203386D01*
X1632809D01*
X1614824Y221371D01*
Y238781D01*
X1615631Y239588D01*
Y265432D01*
X1604930Y276133D01*
Y277185D01*
X1589412Y292703D01*
Y309917D01*
X1583691Y315638D01*
X1581494D01*
X1579506Y317626D01*
Y319556D01*
X1579544Y319594D01*
Y326196D01*
X1575567Y330173D01*
Y340076D01*
X1558013Y357630D01*
X1556930D01*
X1554193Y360367D01*
Y366139D01*
X1551552Y368780D01*
X1546754D01*
X1540730Y374804D01*
Y378130D01*
X1542505Y379905D01*
Y382405D01*
X1545645Y385545D01*
Y388355D01*
X1544455Y389545D01*
Y391960D01*
X1545645Y393150D01*
Y397414D01*
X1546025Y397794D01*
G01X1814900Y116900D02*
X1812698Y119102D01*
Y123087D01*
X1814015Y124404D01*
X1816139D01*
X1818746Y127011D01*
Y128941D01*
X1817383Y130304D01*
X1816627D01*
X1814307Y132624D01*
Y133886D01*
X1807045Y141148D01*
X1799612D01*
X1797936Y142824D01*
Y164235D01*
X1794127Y168044D01*
X1790312D01*
X1786869Y171487D01*
X1782486D01*
X1781252Y172721D01*
X1775615D01*
X1773296Y175040D01*
Y179480D01*
X1770036Y182740D01*
X1727503D01*
X1722495Y187748D01*
X1711722D01*
X1704268Y195202D01*
X1684182D01*
X1682510Y193530D01*
X1672770D01*
X1668495Y197805D01*
X1663587D01*
X1662062Y199330D01*
Y201971D01*
X1660813Y203220D01*
X1653758D01*
X1649272Y207706D01*
X1643363D01*
X1637595Y213474D01*
Y216331D01*
X1632286Y221640D01*
X1630539D01*
X1630283Y221896D01*
X1625121D01*
X1623020Y223997D01*
Y226650D01*
X1620112Y229558D01*
Y236893D01*
X1620703Y237484D01*
Y246616D01*
X1622594Y248507D01*
Y249129D01*
X1622593Y249130D01*
Y260251D01*
X1620703Y262141D01*
Y267536D01*
X1620662Y267577D01*
Y267644D01*
X1614243Y274063D01*
Y275048D01*
X1594494Y294797D01*
Y309910D01*
X1595438Y310854D01*
Y323578D01*
X1586162Y332854D01*
Y341102D01*
X1569159Y358105D01*
X1566269D01*
X1563650Y360724D01*
Y364447D01*
X1552905Y375192D01*
X1552863D01*
X1551504Y376551D01*
Y378643D01*
X1550305Y379842D01*
Y381673D01*
X1551875Y383243D01*
Y387654D01*
G01X1552500Y358500D02*
X1555280Y355720D01*
X1558859D01*
X1572374Y342205D01*
Y336974D01*
X1574152Y335196D01*
Y330524D01*
X1578792Y325884D01*
Y319906D01*
X1578754Y319868D01*
Y317314D01*
X1581182Y314886D01*
X1583310D01*
X1585250Y312946D01*
Y308269D01*
X1588330Y305189D01*
Y292721D01*
X1604178Y276873D01*
Y275821D01*
X1614879Y265120D01*
Y239900D01*
X1614072Y239093D01*
Y221059D01*
X1632497Y202634D01*
X1646295D01*
X1658373Y190556D01*
X1658467D01*
X1658468Y190555D01*
X1659714D01*
X1659715Y190556D01*
X1664636D01*
X1671700Y183492D01*
Y182925D01*
X1671688D01*
G01X1641800Y184400D02*
Y184160D01*
X1638865Y181225D01*
X1633739D01*
X1631285Y183679D01*
Y185577D01*
X1628288Y188574D01*
X1626392D01*
X1624961Y190005D01*
X1621843D01*
X1616577Y195271D01*
Y198802D01*
X1606777Y208602D01*
Y214815D01*
X1603387Y218205D01*
Y243995D01*
X1604966Y245578D01*
Y260922D01*
X1601714Y264174D01*
X1600043D01*
X1598999Y265218D01*
Y275668D01*
X1581500Y293167D01*
Y294031D01*
X1579362Y296169D01*
Y302827D01*
X1575120Y307069D01*
Y313041D01*
X1565074Y323087D01*
Y332172D01*
X1564505Y332742D01*
X1557550Y339697D01*
Y341100D01*
G01X1644433Y185415D02*
Y184633D01*
X1640123Y180323D01*
X1633240D01*
X1630406Y183157D01*
Y185393D01*
X1629684Y186115D01*
X1629683D01*
X1627976Y187822D01*
X1626080D01*
X1624649Y189253D01*
X1621011D01*
X1615447Y194817D01*
Y198403D01*
X1606025Y207825D01*
Y214141D01*
X1602635Y217531D01*
Y244932D01*
X1604214Y246511D01*
Y260610D01*
X1601494Y263330D01*
X1599823D01*
X1598151Y265002D01*
Y275452D01*
X1580600Y293003D01*
Y293867D01*
X1578410Y296057D01*
Y302351D01*
X1574073Y306688D01*
Y312741D01*
X1564322Y322492D01*
Y331582D01*
X1563882Y332022D01*
X1563878D01*
X1554800Y341100D01*
G01X1778900Y165800D02*
X1777089Y167611D01*
X1719377D01*
X1715299Y171689D01*
X1706525D01*
X1701239Y176975D01*
X1695075D01*
X1695074Y176974D01*
X1685512D01*
X1681668Y180818D01*
X1678438D01*
X1677915Y181341D01*
X1670859D01*
X1664100Y188100D01*
X1659700D01*
X1645918Y201882D01*
X1632185D01*
X1613320Y220747D01*
Y239405D01*
X1614127Y240212D01*
Y264808D01*
X1603426Y275509D01*
Y276561D01*
X1587550Y292437D01*
Y304850D01*
X1584376Y308024D01*
Y312753D01*
X1582995Y314134D01*
X1580870D01*
X1578002Y317002D01*
Y324298D01*
X1573000Y329300D01*
Y334500D01*
X1569000Y338500D01*
Y340229D01*
X1564129Y345100D01*
X1563171D01*
X1547200Y361071D01*
Y366200D01*
X1536655Y376745D01*
Y379053D01*
X1537845Y380243D01*
Y382433D01*
X1536655Y383623D01*
Y385813D01*
X1537845Y387003D01*
Y388145D01*
X1541745Y392045D01*
Y394775D01*
X1544040Y397070D01*
Y398030D01*
X1545570Y399560D01*
X1552482D01*
X1553445Y400523D01*
Y408756D01*
X1551752Y410449D01*
Y412118D01*
X1550305Y413565D01*
Y416814D01*
X1554029Y420538D01*
Y424229D01*
X1557790Y427990D01*
Y429980D01*
X1560974Y433164D01*
X1581736D01*
X1583961Y430939D01*
X1592139D01*
X1593400Y432200D01*
G01X1626935Y217775D02*
X1626568Y218142D01*
X1620181D01*
X1616543Y221780D01*
Y222865D01*
X1616544Y222866D01*
Y238373D01*
X1617135Y238964D01*
Y266056D01*
X1606434Y276757D01*
Y277809D01*
X1590916Y293327D01*
Y313900D01*
X1591788Y314772D01*
Y316078D01*
X1590865Y317001D01*
X1590809D01*
X1588790Y319020D01*
X1582263D01*
X1581834Y318591D01*
G01X1660985Y165885D02*
X1658387Y168483D01*
X1649153D01*
X1646094Y171542D01*
Y179805D01*
X1646774Y180485D01*
Y185933D01*
X1646775Y185934D01*
Y186556D01*
X1646774Y186557D01*
Y186558D01*
X1644056Y189276D01*
X1637410D01*
X1636608Y190078D01*
X1627016D01*
X1621858Y195236D01*
Y196980D01*
X1608281Y210557D01*
Y216282D01*
X1607795Y216768D01*
Y237752D01*
X1605073Y240474D01*
Y242788D01*
X1606604Y244319D01*
Y261882D01*
X1602386Y266100D01*
Y267520D01*
X1600192Y269714D01*
Y275539D01*
X1582854Y292877D01*
Y294906D01*
X1581940Y295820D01*
G01X1644290Y196383D02*
Y197960D01*
X1641120Y201130D01*
X1631873D01*
X1612568Y220435D01*
Y239717D01*
X1613375Y240524D01*
Y264496D01*
X1602674Y275197D01*
Y276249D01*
X1585828Y293095D01*
Y304972D01*
X1582800Y308000D01*
Y312100D01*
G01X1660440Y200789D02*
X1658903Y202326D01*
X1653325D01*
X1648697Y206954D01*
X1642298D01*
X1636843Y212409D01*
Y216019D01*
X1631974Y220888D01*
X1630227D01*
X1630156Y220959D01*
X1621348D01*
X1619360Y222947D01*
Y237205D01*
X1619951Y237796D01*
Y246928D01*
X1621841Y248818D01*
Y259939D01*
X1619951Y261829D01*
Y267224D01*
X1613491Y273684D01*
Y274736D01*
X1593742Y294485D01*
Y312742D01*
X1594686Y313686D01*
Y323266D01*
X1585370Y332582D01*
Y340830D01*
X1583331Y342869D01*
X1580441D01*
X1561250Y362060D01*
Y365784D01*
X1554857Y372177D01*
X1553041D01*
X1547604Y377614D01*
Y378896D01*
X1546405Y380095D01*
Y381905D01*
X1547975Y383475D01*
Y387654D01*
G01X1534325Y391034D02*
Y387383D01*
X1532755Y385813D01*
Y382735D01*
X1533945Y381545D01*
Y380243D01*
X1532755Y379053D01*
Y376863D01*
X1537772Y371846D01*
X1540180D01*
X1546448Y365578D01*
Y360759D01*
X1549881Y357326D01*
Y354081D01*
X1547900Y352100D01*
Y349400D01*
X1553600Y343700D01*
X1557179D01*
X1560672Y340207D01*
Y340035D01*
X1566198Y334509D01*
Y323891D01*
X1577425Y312664D01*
Y310011D01*
X1580415Y307021D01*
Y300241D01*
X1583881Y296775D01*
Y292914D01*
X1601170Y275625D01*
Y273815D01*
X1606467Y268518D01*
Y265655D01*
X1611871Y260251D01*
Y241387D01*
X1611064Y240580D01*
Y219811D01*
X1613337Y217538D01*
Y212854D01*
X1626965Y199226D01*
X1632297D01*
X1634069Y197454D01*
G01X1558980Y360130D02*
X1578589Y340521D01*
Y337372D01*
X1586310Y329640D01*
Y321839D01*
X1587721Y320428D01*
X1589374D01*
X1591393Y318409D01*
X1591449D01*
X1593196Y316662D01*
Y314188D01*
X1592334Y313326D01*
Y293901D01*
X1607842Y278393D01*
Y277341D01*
X1618543Y266640D01*
Y238380D01*
X1617952Y237789D01*
Y222363D01*
X1620765Y219550D01*
X1621850D01*
X1621851Y219551D01*
X1627671D01*
X1627742Y219480D01*
X1630069D01*
X1635435Y214114D01*
Y211825D01*
X1641714Y205546D01*
X1647784D01*
X1653060Y200270D01*
X1656783D01*
X1663585Y193468D01*
X1666272D01*
X1670350Y189390D01*
X1682470D01*
X1689400Y182460D01*
Y180960D01*
X1689793Y180567D01*
X1708567D01*
X1713000Y185000D01*
G01X1654015Y217239D02*
X1652445Y218809D01*
X1646834D01*
X1634258Y231385D01*
Y236856D01*
X1634828Y237426D01*
Y242972D01*
X1634258Y243542D01*
Y251074D01*
X1633449Y251883D01*
Y266081D01*
X1631218Y268312D01*
Y277781D01*
X1629000Y279999D01*
Y282000D01*
X1629737Y282737D01*
Y309451D01*
X1612357Y326831D01*
Y338698D01*
X1609258Y341797D01*
X1608521D01*
X1601285Y349033D01*
Y352545D01*
X1587291Y366539D01*
Y380738D01*
X1584347Y383682D01*
Y383683D01*
X1575186Y392844D01*
X1570724D01*
X1569425Y394143D01*
Y397794D01*
G01X1563575Y401174D02*
X1562784D01*
X1559538Y397928D01*
Y396498D01*
X1558105Y395065D01*
Y393763D01*
X1559295Y392573D01*
Y391051D01*
X1561642Y388704D01*
Y387366D01*
X1563164Y385844D01*
X1566176D01*
X1567500Y384520D01*
Y384094D01*
X1578894Y372700D01*
X1581621D01*
X1585387Y368934D01*
Y367317D01*
X1597857Y354847D01*
Y344608D01*
X1603752Y338713D01*
Y332748D01*
X1628000Y308500D01*
Y285500D01*
X1627000Y284500D01*
Y279000D01*
X1629714Y276286D01*
Y267685D01*
X1630420Y266979D01*
Y266975D01*
X1631945Y265450D01*
Y251259D01*
X1632754Y250450D01*
Y242918D01*
X1633324Y242348D01*
Y238050D01*
X1632754Y237480D01*
Y230761D01*
X1646210Y217305D01*
X1650354D01*
X1653235Y214424D01*
X1654570D01*
X1660173Y208821D01*
X1666474D01*
X1670019Y205276D01*
X1675140D01*
X1678859Y201557D01*
X1714435D01*
X1717679Y198313D01*
Y198006D01*
X1729181Y186504D01*
X1791469D01*
X1798245Y179728D01*
Y176784D01*
X1799576Y175453D01*
Y169976D01*
X1801224Y168328D01*
Y160704D01*
X1805590Y156338D01*
Y146748D01*
X1815238Y137100D01*
X1818211D01*
X1821037Y134274D01*
Y126167D01*
X1816348Y121478D01*
X1815026D01*
G01X1787000Y175500D02*
Y179439D01*
X1780691Y185748D01*
X1728751D01*
X1716927Y197572D01*
Y198001D01*
X1714123Y200805D01*
X1678547D01*
X1674828Y204524D01*
X1668643D01*
X1665850Y207317D01*
X1660345D01*
X1655188Y212474D01*
X1645047D01*
X1641356Y216165D01*
Y217890D01*
X1634456Y224790D01*
Y227055D01*
X1634457Y227056D01*
Y227678D01*
X1632002Y230133D01*
Y237792D01*
X1632572Y238362D01*
Y242036D01*
X1632002Y242606D01*
Y250138D01*
X1631193Y250947D01*
Y265138D01*
X1629657Y266674D01*
Y266678D01*
X1628962Y267373D01*
Y275538D01*
X1623000Y281500D01*
X1613788D01*
X1598254Y297034D01*
Y308350D01*
X1601200Y311296D01*
Y338279D01*
X1596090Y343389D01*
Y351082D01*
X1590537Y356635D01*
X1584991D01*
X1583503Y358123D01*
Y366620D01*
X1582349Y367774D01*
X1581082D01*
X1572858Y375998D01*
X1569367D01*
X1565525Y379840D01*
Y384274D01*
G01X1588551Y341410D02*
X1573930Y356031D01*
Y361229D01*
X1567559Y367600D01*
X1564355D01*
X1555404Y376551D01*
Y379044D01*
X1554205Y380243D01*
Y381545D01*
X1556155Y383495D01*
Y384925D01*
X1557345Y386115D01*
Y389193D01*
X1556155Y390383D01*
Y391255D01*
X1554580Y392830D01*
X1550820D01*
X1550225Y393425D01*
X1548964D01*
X1547975Y394414D01*
G01X1664390Y201163D02*
Y202059D01*
X1661725Y204724D01*
X1654382D01*
X1649896Y209210D01*
X1643987D01*
X1639100Y214097D01*
Y216954D01*
X1632910Y223144D01*
X1631163D01*
X1630687Y223620D01*
X1625525D01*
X1624548Y224597D01*
Y227250D01*
X1621616Y230182D01*
Y236269D01*
X1622207Y236860D01*
Y245992D01*
X1624100Y247885D01*
Y248507D01*
X1624099Y248508D01*
Y249130D01*
X1624098Y249131D01*
Y249753D01*
X1624097Y249754D01*
Y260875D01*
X1623994Y260978D01*
Y260996D01*
X1622207Y262783D01*
Y268160D01*
X1622167Y268200D01*
Y268267D01*
X1622166Y268268D01*
Y268525D01*
X1619839Y270852D01*
Y274396D01*
X1616912Y277323D01*
X1614096D01*
X1595998Y295421D01*
Y309286D01*
X1596942Y310230D01*
Y333019D01*
X1588551Y341410D01*
G01X1559675Y387654D02*
X1560055Y387274D01*
Y383623D01*
X1561245Y382433D01*
Y379355D01*
X1560055Y378165D01*
Y376863D01*
X1563967Y372951D01*
X1570071D01*
X1580303Y362719D01*
Y355496D01*
X1599482Y336317D01*
Y310642D01*
X1597502Y308662D01*
Y296722D01*
X1615397Y278827D01*
X1617913D01*
X1621514Y275226D01*
Y271305D01*
X1623909Y268910D01*
Y263432D01*
X1625601Y261740D01*
Y261499D01*
X1625602Y261498D01*
Y260921D01*
X1625601Y260920D01*
Y259614D01*
X1625602Y259613D01*
Y259511D01*
X1626637Y258476D01*
X1627696D01*
X1628619Y257553D01*
Y249212D01*
X1631240Y246591D01*
Y242304D01*
X1631820Y241724D01*
Y238674D01*
X1631240Y238094D01*
Y226360D01*
X1632128Y225472D01*
G01X1637269Y264421D02*
X1635993Y265697D01*
Y267446D01*
X1634380Y269059D01*
Y282667D01*
X1631993Y285054D01*
Y310387D01*
X1629378Y313002D01*
Y313006D01*
X1627946Y314438D01*
Y329243D01*
X1627194Y329995D01*
X1619525D01*
X1616317Y333203D01*
Y339205D01*
X1609711Y345811D01*
X1606134D01*
X1602127Y349818D01*
Y352767D01*
X1588043Y366851D01*
Y381050D01*
X1585411Y383682D01*
X1585410D01*
X1585098Y383994D01*
Y383995D01*
X1575342Y393751D01*
X1574259D01*
X1570995Y397015D01*
Y398445D01*
X1570076Y399364D01*
X1567064D01*
X1566619Y399809D01*
X1564582D01*
X1563302Y398529D01*
Y396997D01*
X1560719Y394414D01*
X1559675D01*
G01X1557725Y391034D02*
X1558096Y390663D01*
Y386842D01*
X1559304Y385634D01*
Y382901D01*
X1557971Y381568D01*
Y379844D01*
X1559321Y378494D01*
X1559304Y378477D01*
Y375783D01*
X1564119Y370968D01*
X1570991D01*
X1579088Y362871D01*
Y354804D01*
X1596227Y337665D01*
Y337135D01*
X1598730Y334632D01*
Y310954D01*
X1596750Y308974D01*
Y295733D01*
X1614408Y278075D01*
X1617601D01*
X1620631Y275045D01*
Y271124D01*
X1623000Y268755D01*
Y263070D01*
X1624747Y261323D01*
Y261289D01*
X1624849Y261187D01*
Y259302D01*
X1624850Y259301D01*
Y258692D01*
X1624849Y258691D01*
Y250066D01*
X1624850Y250065D01*
Y249443D01*
X1624851Y249442D01*
Y248820D01*
X1624852Y248819D01*
Y247573D01*
X1623222Y245943D01*
Y236811D01*
X1622368Y235957D01*
Y232950D01*
X1628624Y226694D01*
Y225318D01*
G01X1630276Y449517D02*
X1629859Y449100D01*
X1619601D01*
X1612251Y456450D01*
X1602050D01*
X1600600Y457900D01*
X1591279D01*
X1588258Y454879D01*
X1585902D01*
X1583208Y452185D01*
G01X1561625Y446926D02*
X1563251Y445300D01*
X1569197D01*
G03X1570670Y445910I0J2083D01*
G01X1571160Y446400D01*
X1578630D01*
X1580558Y448328D01*
X1584070D01*
G01X1559595Y450631D02*
X1561233Y452269D01*
X1564453D01*
X1564606Y452116D01*
X1571766D01*
X1574730Y455080D01*
Y460030D01*
X1579900Y465200D01*
X1597800D01*
X1602700Y460300D01*
X1616050D01*
X1617190Y459160D01*
Y452611D01*
X1619901Y449900D01*
X1628100D01*
X1630300Y452100D01*
G01X1585920Y452368D02*
X1587279Y453727D01*
X1588736D01*
X1592085Y457076D01*
X1600072D01*
X1604428Y452720D01*
X1613880D01*
X1618659Y447941D01*
X1632941D01*
X1636395Y451395D01*
X1640644D01*
X1643415Y454166D01*
X1647104D01*
X1648340Y452930D01*
Y439930D01*
X1645625Y437215D01*
Y436308D01*
X1645624Y436307D01*
Y425075D01*
X1640290Y419741D01*
Y388710D01*
X1659865Y369135D01*
Y309135D01*
X1663261Y305739D01*
Y255775D01*
X1666179Y252857D01*
X1673863D01*
X1675270Y254264D01*
X1827313D01*
X1833644Y247933D01*
X1842300D01*
X1854999Y235234D01*
Y215754D01*
X1855508Y215245D01*
Y210477D01*
X1853929Y208898D01*
Y201858D01*
X1861243Y194544D01*
Y183100D01*
G01X1715078Y250231D02*
X1696584D01*
X1693241Y246888D01*
X1685481D01*
X1685162Y247207D01*
X1668287D01*
X1660757Y254737D01*
Y304701D01*
X1657361Y308097D01*
Y367702D01*
X1647567Y377496D01*
X1645489D01*
X1637786Y385199D01*
Y420779D01*
X1643120Y426113D01*
Y437204D01*
X1643057Y437267D01*
Y445607D01*
X1640858Y447806D01*
X1637723D01*
X1632017Y442100D01*
X1617326D01*
X1615263Y444163D01*
Y447559D01*
X1612990Y449832D01*
X1612368D01*
X1612367Y449831D01*
X1596718D01*
X1592839Y453710D01*
X1590349D01*
X1588790Y452151D01*
X1588632D01*
G01X1571600Y459785D02*
Y460209D01*
X1580010Y468619D01*
X1608817D01*
X1611636Y465800D01*
G01X1624700Y460150D02*
X1626050Y458800D01*
X1634162D01*
X1639822Y453140D01*
G01X1579537Y443191D02*
X1580972D01*
X1586019Y438144D01*
X1596120D01*
X1596204Y438228D01*
X1611902D01*
X1612302Y437828D01*
X1613316D01*
X1620394Y430750D01*
X1633650D01*
X1638600Y435700D01*
X1639500D01*
G01X1640625Y429460D02*
X1640185Y429900D01*
X1620180D01*
X1613004Y437076D01*
X1596682D01*
X1596598Y436992D01*
X1585541D01*
X1583563Y438970D01*
X1581545D01*
X1576969Y443546D01*
X1571375D01*
G01X1630120Y418887D02*
X1629938D01*
X1628753Y417702D01*
X1621552D01*
X1613207Y426047D01*
X1605828D01*
X1602899Y428976D01*
X1601086D01*
X1595055Y435007D01*
X1586855D01*
X1586211Y434363D01*
X1581556D01*
X1581116Y434803D01*
X1568966D01*
X1567475Y436294D01*
Y436786D01*
G01X1621000Y452000D02*
Y458440D01*
X1618070Y461370D01*
X1614530D01*
X1612419Y463481D01*
X1607885D01*
X1606372Y461968D01*
X1602477D01*
X1597801Y466644D01*
X1580257D01*
X1573900Y460287D01*
Y455887D01*
X1573064Y455051D01*
X1570212D01*
G01X1586700Y620100D02*
X1591002Y624402D01*
X1692722D01*
X1699106Y618018D01*
G01X1693900Y73300D02*
X1691124Y76076D01*
X1688154D01*
X1684249Y72171D01*
X1683320Y71975D01*
X1681380Y71566D01*
X1668725D01*
X1665545Y68386D01*
X1642386D01*
X1640900Y66900D01*
G01X1632615Y109215D02*
X1634167Y107663D01*
Y91428D01*
X1630826Y88087D01*
G01X1598300Y116477D02*
X1601950Y120127D01*
X1627373D01*
X1628000Y119500D01*
Y117700D01*
X1628700Y117000D01*
X1630100D01*
X1631000Y116100D01*
Y111891D01*
X1632026Y110865D01*
X1633160D01*
X1635500Y108525D01*
Y95000D01*
X1640000Y90500D01*
X1659498D01*
X1666999Y82999D01*
Y82601D01*
X1668000Y81600D01*
G01X1708610Y85121D02*
X1710600Y87111D01*
Y87998D01*
X1710728Y88126D01*
Y88337D01*
X1710826Y88435D01*
Y89741D01*
X1710600Y89967D01*
Y92200D01*
X1706123Y96677D01*
X1679881D01*
X1676375Y100183D01*
Y103753D01*
X1676365Y103763D01*
Y117776D01*
X1667607Y126534D01*
X1650040D01*
X1649367Y127207D01*
Y131383D01*
X1648150Y132600D01*
Y144190D01*
X1649430Y145470D01*
X1658750D01*
X1659480Y146200D01*
Y160292D01*
X1660448Y161260D01*
X1661597D01*
X1661634Y161297D01*
X1661746D01*
X1663450Y163001D01*
Y170995D01*
X1665063Y172608D01*
G01X1660985Y112341D02*
X1659364Y113962D01*
X1657139D01*
X1656180Y114921D01*
X1654191D01*
X1653011Y116101D01*
Y116103D01*
X1652148Y116966D01*
X1652146D01*
X1652012Y117100D01*
X1648450D01*
X1646867Y118683D01*
Y129820D01*
X1644333Y132354D01*
Y153246D01*
X1645907Y154820D01*
X1649285D01*
X1649927Y155462D01*
Y157149D01*
X1650846Y158068D01*
X1652166D01*
X1653100Y159002D01*
Y163237D01*
X1654239Y164376D01*
X1661775D01*
X1662637Y165238D01*
Y167645D01*
X1660124Y170158D01*
X1648541D01*
X1646845Y171854D01*
Y178544D01*
X1649924Y181623D01*
Y182929D01*
X1648560Y184293D01*
Y185049D01*
X1648274Y185335D01*
Y185989D01*
X1647873Y186390D01*
Y186523D01*
X1644368Y190028D01*
X1638260D01*
X1637458Y190830D01*
X1627328D01*
X1622611Y195547D01*
Y197663D01*
X1609033Y211241D01*
Y218376D01*
X1608631Y218778D01*
Y242995D01*
X1609051Y243415D01*
G01X1670500Y81600D02*
X1668645Y83455D01*
Y88691D01*
X1666298Y91038D01*
Y92536D01*
X1666300Y92538D01*
Y101000D01*
X1659509Y107791D01*
Y109783D01*
X1658626Y110666D01*
X1658448D01*
X1658447Y110667D01*
X1657265D01*
X1656351Y111581D01*
Y113249D01*
X1655584Y114016D01*
X1639434D01*
X1637463Y115987D01*
Y123687D01*
X1630964Y130186D01*
Y158110D01*
X1629489Y159585D01*
G01X1709184Y88811D02*
X1709152D01*
Y88779D01*
X1708875Y89056D01*
Y90498D01*
X1706196Y93177D01*
X1702882D01*
X1702211Y92506D01*
X1685394D01*
X1681975Y95925D01*
X1679569D01*
X1678497Y96997D01*
Y96998D01*
X1675624Y99871D01*
Y100187D01*
X1674500Y101311D01*
X1673736D01*
X1672666Y102381D01*
Y109443D01*
X1673775Y110552D01*
Y117628D01*
X1668038Y123365D01*
X1650181D01*
X1648517Y125029D01*
Y131133D01*
X1647399Y132251D01*
Y146001D01*
X1649868Y148470D01*
X1655640D01*
X1656161Y148991D01*
Y158162D01*
X1654638Y159685D01*
G01X1626339Y118651D02*
X1626349Y118641D01*
Y117751D01*
X1627900Y116200D01*
Y102100D01*
X1632020Y97980D01*
Y97871D01*
G01X1626300Y112300D02*
X1624600Y110600D01*
Y101988D01*
X1628788Y97800D01*
G01X1654686Y156436D02*
X1649960Y151710D01*
X1647891D01*
X1646648Y150467D01*
Y131105D01*
X1647667Y130086D01*
Y122510D01*
X1650001Y120176D01*
X1667680D01*
X1668844Y119012D01*
Y111980D01*
X1669363Y111461D01*
Y101998D01*
X1674363Y96998D01*
X1676696D01*
X1677697Y95997D01*
Y95602D01*
X1678926Y94373D01*
X1679321D01*
X1682740Y90954D01*
X1702854D01*
X1703525Y91625D01*
X1705477D01*
X1707000Y90102D01*
Y89448D01*
X1706969Y89417D01*
Y87945D01*
X1707000Y87914D01*
Y84502D01*
X1707957Y83545D01*
X1709263D01*
X1711352Y85634D01*
Y87581D01*
X1715911Y92140D01*
X1731350D01*
G01X1645237Y165884D02*
X1643589Y167532D01*
X1638799D01*
X1622962Y183369D01*
X1618847D01*
X1618274Y183941D01*
Y183942D01*
X1617925Y184291D01*
Y185878D01*
X1616528Y187275D01*
X1605475D01*
X1603300Y185100D01*
G01X1629489Y162735D02*
X1634211Y158013D01*
X1645753D01*
X1646800Y159060D01*
Y163703D01*
X1647341Y164244D01*
X1649186D01*
X1649961Y165019D01*
Y166612D01*
X1645343Y171230D01*
Y180577D01*
X1646023Y181257D01*
Y186143D01*
X1643642Y188524D01*
X1637098D01*
X1636296Y189326D01*
X1626704D01*
X1624945Y191085D01*
X1622256D01*
X1618257Y195084D01*
Y198999D01*
X1607529Y209727D01*
Y215127D01*
X1607459Y215197D01*
Y215217D01*
X1605073Y217603D01*
Y239410D01*
X1604321Y240162D01*
Y243508D01*
X1605852Y245039D01*
Y261340D01*
X1601186Y266006D01*
X1600810D01*
G01X1673800Y201070D02*
X1669130D01*
X1664600Y205600D01*
X1654600D01*
X1650500Y209700D01*
X1650470D01*
X1650208Y209962D01*
X1644538D01*
X1639852Y214648D01*
Y217266D01*
X1633222Y223896D01*
X1631475D01*
X1630450Y224921D01*
Y238368D01*
X1631068Y238986D01*
Y241412D01*
X1626408Y246072D01*
Y252771D01*
X1627024Y253387D01*
G01X1645151Y162649D02*
X1643392Y164408D01*
X1638326D01*
X1638325Y164409D01*
X1638226D01*
X1637463Y165172D01*
Y165271D01*
X1637462Y165272D01*
Y166496D01*
X1637463Y166497D01*
Y167593D01*
X1624952Y180104D01*
X1624143D01*
X1624142Y180105D01*
X1617847D01*
X1616925Y181027D01*
Y184052D01*
X1617174Y184301D01*
Y185566D01*
X1616216Y186524D01*
X1609809D01*
X1608056Y184771D01*
G01X1655031Y184505D02*
Y185675D01*
X1649339Y191367D01*
X1648301D01*
X1648300Y191366D01*
X1647678D01*
X1647677Y191367D01*
X1647444D01*
X1646422Y192389D01*
X1639237D01*
X1638491Y193135D01*
X1628602D01*
X1627214Y194523D01*
Y194568D01*
X1627174Y194608D01*
Y196468D01*
X1611761Y211881D01*
Y213507D01*
G01X1810245Y104500D02*
X1808669Y102924D01*
X1807092D01*
X1798872Y111144D01*
Y118513D01*
X1805837Y125478D01*
Y130083D01*
X1800168Y135752D01*
X1798206D01*
X1793128Y140830D01*
Y155804D01*
X1788479Y160453D01*
X1780799D01*
X1774393Y166859D01*
X1719065D01*
X1714987Y170937D01*
X1706213D01*
X1700928Y176222D01*
X1685200D01*
X1681356Y180066D01*
X1678127D01*
X1677663Y180530D01*
X1665970D01*
X1661060Y185440D01*
X1658274D01*
X1650841Y192873D01*
X1648927D01*
X1648926Y192872D01*
X1648304D01*
X1647193Y193983D01*
X1642356D01*
X1640049Y196290D01*
Y197594D01*
X1640050Y197595D01*
Y197626D01*
X1638323Y199353D01*
X1636053D01*
X1634154Y197454D01*
X1634069D01*
G01X1800792Y122691D02*
X1805085Y126984D01*
Y129771D01*
X1799856Y135000D01*
X1797894D01*
X1792376Y140518D01*
Y154282D01*
X1789912Y156746D01*
X1786460D01*
X1781723Y152009D01*
X1776253D01*
X1774607Y153655D01*
Y158573D01*
X1769052Y164128D01*
X1715152D01*
X1710860Y168420D01*
X1704898D01*
X1702111Y171207D01*
X1689515D01*
X1688019Y172703D01*
X1687005D01*
X1680394Y179314D01*
X1677816D01*
X1677394Y179736D01*
X1667498D01*
X1665388Y177626D01*
X1662846D01*
X1659050Y181422D01*
Y183600D01*
X1650529Y192121D01*
X1649239D01*
X1649238Y192120D01*
X1648616D01*
X1648615Y192119D01*
X1647993D01*
X1647991Y192121D01*
X1647989Y192119D01*
X1646967Y193141D01*
X1639806D01*
X1637870Y195077D01*
G01X1648320Y172690D02*
X1650078Y174448D01*
X1663434D01*
X1666380Y177394D01*
X1668177D01*
X1669254Y178471D01*
X1675937D01*
X1680550Y173858D01*
X1681156D01*
X1686531Y168483D01*
Y168277D01*
X1687512Y167296D01*
X1687718D01*
X1688157Y166857D01*
X1710095D01*
X1714289Y162663D01*
X1765197D01*
X1765253Y162607D01*
X1768581D01*
X1773199Y157989D01*
Y152876D01*
X1775976Y150099D01*
X1786199D01*
X1790100Y154000D01*
G01X1600552Y261281D02*
X1600567D01*
X1602716Y259132D01*
Y252048D01*
X1601788Y251120D01*
Y246211D01*
X1601180Y245603D01*
Y210360D01*
X1613688Y197852D01*
Y194584D01*
X1620583Y187689D01*
X1624221D01*
X1625496Y186414D01*
X1627485D01*
X1629100Y184799D01*
Y182602D01*
X1643419Y168283D01*
X1645988D01*
X1648386Y165885D01*
G01X1623250Y162611D02*
X1621801Y164060D01*
Y171291D01*
X1620467Y172625D01*
Y175470D01*
X1618085Y177852D01*
X1616911D01*
X1615388Y179375D01*
X1610438D01*
X1609311Y178248D01*
X1604189D01*
X1604188Y178249D01*
X1598773D01*
X1597375Y179647D01*
Y188367D01*
X1600092Y191084D01*
Y194203D01*
X1599091Y195204D01*
Y203417D01*
X1594796Y207712D01*
Y215865D01*
X1592870Y217791D01*
Y217900D01*
G01X1655209Y181761D02*
X1654502D01*
X1652296Y183967D01*
X1650823D01*
X1650065Y184725D01*
X1649947D01*
X1649025Y185647D01*
Y188133D01*
X1645978Y191180D01*
X1638738D01*
X1637936Y191982D01*
X1627806D01*
X1624304Y195484D01*
Y197658D01*
X1610185Y211777D01*
Y218941D01*
X1609912Y219214D01*
Y241058D01*
X1610627Y241773D01*
Y259529D01*
X1604222Y265934D01*
Y268107D01*
G01X1608850Y343835D02*
X1615144Y337541D01*
Y333312D01*
X1619213Y329243D01*
X1626053D01*
X1627079Y328217D01*
Y314241D01*
X1628626Y312694D01*
Y312690D01*
X1631241Y310075D01*
Y284742D01*
X1633628Y282355D01*
Y268739D01*
X1634954Y267413D01*
Y266791D01*
X1634953Y266790D01*
Y252507D01*
X1635762Y251698D01*
Y244166D01*
X1636332Y243596D01*
Y236802D01*
X1635762Y236232D01*
Y232121D01*
X1646990Y220893D01*
X1653654D01*
X1657242Y217305D01*
X1668427D01*
X1672454Y213278D01*
X1677466D01*
X1684675Y206069D01*
X1716307D01*
X1716411Y205965D01*
X1727148D01*
X1729821Y203292D01*
X1826437D01*
X1831991Y197738D01*
Y191794D01*
X1830795Y190598D01*
Y173626D01*
X1824852Y167683D01*
Y155305D01*
X1818400Y148853D01*
Y141252D01*
X1824093Y135559D01*
Y113007D01*
X1831892Y105208D01*
Y94281D01*
X1824240Y86629D01*
Y83680D01*
G01X1830415Y196567D02*
Y194243D01*
X1828476Y192304D01*
X1729155D01*
X1716353Y205106D01*
X1716206D01*
X1715995Y205317D01*
X1684363D01*
X1677154Y212526D01*
X1672142D01*
X1668131Y216537D01*
X1656946D01*
X1653922Y219561D01*
X1647253D01*
X1635010Y231804D01*
Y236544D01*
X1635580Y237114D01*
Y243284D01*
X1635010Y243854D01*
Y251386D01*
X1634201Y252195D01*
Y267102D01*
X1632876Y268427D01*
Y282043D01*
X1630489Y284430D01*
Y309763D01*
X1627874Y312378D01*
Y312382D01*
X1625400Y314856D01*
Y327667D01*
G01X1845469Y135500D02*
X1825602D01*
X1822206Y138896D01*
Y138897D01*
X1819200Y141903D01*
Y148585D01*
X1825441Y154826D01*
Y154830D01*
X1825604Y154993D01*
Y166995D01*
X1831812Y173203D01*
Y190500D01*
X1834195Y192883D01*
Y199257D01*
X1829408Y204044D01*
X1730133D01*
X1727460Y206717D01*
X1716723D01*
X1716619Y206821D01*
X1684987D01*
X1677777Y214031D01*
X1676531D01*
X1676530Y214030D01*
X1672766D01*
X1668691Y218105D01*
X1657506D01*
X1653822Y221789D01*
X1647158D01*
X1636514Y232433D01*
Y235920D01*
X1637084Y236490D01*
Y243908D01*
X1636514Y244478D01*
Y252010D01*
X1635705Y252819D01*
Y262857D01*
X1637269Y264421D01*
G01X1609172Y339630D02*
Y328952D01*
X1628985Y309139D01*
Y284485D01*
X1628000Y283500D01*
Y279499D01*
X1630466Y277033D01*
Y267997D01*
X1632697Y265766D01*
Y251571D01*
X1633506Y250762D01*
Y243230D01*
X1634076Y242660D01*
Y237738D01*
X1633506Y237168D01*
Y231073D01*
X1646522Y218057D01*
X1650903D01*
X1653349Y215611D01*
X1667993D01*
X1671960Y211644D01*
X1676972D01*
X1684051Y204565D01*
X1715683D01*
X1715894Y204354D01*
X1716041D01*
X1728843Y191552D01*
X1814512D01*
X1825776Y180288D01*
Y171193D01*
X1823005Y168422D01*
X1819949D01*
X1816219Y172152D01*
X1812148D01*
X1810694Y173606D01*
X1801707D01*
X1801080Y172979D01*
Y170600D01*
X1802728Y168952D01*
Y161328D01*
X1807918Y156138D01*
Y155330D01*
X1813400Y149848D01*
Y142975D01*
X1821789Y134586D01*
Y112051D01*
X1824990Y108850D01*
Y103620D01*
G01X1634400Y412900D02*
X1636200Y411100D01*
Y384657D01*
X1644865Y375992D01*
X1644932D01*
X1655837Y365087D01*
Y256498D01*
X1658197Y254138D01*
Y250720D01*
X1658196Y250719D01*
Y245047D01*
X1665997Y237246D01*
X1678051D01*
X1679770Y235528D01*
X1684773D01*
X1697110Y247865D01*
X1717653D01*
X1718820Y249032D01*
G01X1854942Y181655D02*
Y182105D01*
X1852500Y184547D01*
Y192035D01*
X1851000Y193535D01*
Y207599D01*
X1854356Y210955D01*
Y214767D01*
X1853847Y215276D01*
Y232241D01*
X1844685Y241403D01*
X1843229D01*
X1841725Y242907D01*
Y245078D01*
X1840802Y246001D01*
X1825078D01*
X1821857Y249222D01*
Y251519D01*
X1821016Y252360D01*
X1734291D01*
X1730570Y248639D01*
X1721681D01*
X1720701Y249619D01*
X1720699D01*
X1719710Y250608D01*
X1717684D01*
X1715731Y248655D01*
X1715523D01*
X1715485Y248617D01*
X1696034D01*
X1684014Y236597D01*
X1680523D01*
X1679122Y237998D01*
X1666309D01*
X1658948Y245359D01*
Y250407D01*
X1660005Y251464D01*
Y304389D01*
X1656608Y307786D01*
Y308408D01*
X1656609Y308409D01*
Y367390D01*
X1647255Y376744D01*
X1645177D01*
X1637034Y384887D01*
Y421091D01*
X1642368Y426425D01*
Y436892D01*
X1639774Y439486D01*
G01X1596500Y455500D02*
X1600873Y451127D01*
X1613466D01*
X1617993Y446600D01*
X1620571D01*
X1620573Y446602D01*
X1621879D01*
X1621881Y446600D01*
X1623500D01*
X1625676Y444424D01*
X1631424D01*
X1636458Y449458D01*
X1640409D01*
X1640410Y449459D01*
X1641446D01*
X1644309Y446596D01*
Y438197D01*
X1644373Y438133D01*
Y436827D01*
X1644372Y436826D01*
Y425594D01*
X1639038Y420260D01*
Y385718D01*
X1646008Y378748D01*
X1648481D01*
X1658613Y368616D01*
Y308616D01*
X1662009Y305220D01*
Y255256D01*
X1668806Y248459D01*
X1687479D01*
X1687798Y248140D01*
X1692722D01*
X1696442Y251860D01*
X1720923D01*
X1722251Y250532D01*
G01X1639774Y439486D02*
X1641326Y441038D01*
Y446274D01*
X1640546Y447054D01*
X1638264D01*
X1630134Y438924D01*
X1619438D01*
X1614511Y443851D01*
Y447247D01*
X1612679Y449079D01*
X1594399D01*
X1591344Y452134D01*
G01X1680133Y535489D02*
X1678825Y536797D01*
X1673380D01*
X1649661Y513078D01*
X1648683D01*
X1646604Y510999D01*
Y502413D01*
X1641963Y497772D01*
Y495964D01*
G01X1722500Y562000D02*
X1722000Y561500D01*
Y537500D01*
X1718500Y534000D01*
X1686942D01*
X1677871Y524929D01*
X1677112Y524423D01*
X1676788Y524288D01*
X1675500Y523000D01*
X1666266D01*
X1648330Y505064D01*
Y504544D01*
G01X1738088Y551000D02*
X1737581D01*
X1729193Y542612D01*
Y534196D01*
X1721469Y526472D01*
X1693687D01*
X1683480Y516265D01*
X1672014D01*
X1651371Y495622D01*
Y492062D01*
X1650178Y490869D01*
Y476026D01*
X1666536Y459668D01*
Y446001D01*
X1668190Y444347D01*
Y442507D01*
X1669962Y440735D01*
G01X1710389Y577787D02*
X1715460Y572716D01*
Y561836D01*
X1706354Y552730D01*
X1699984D01*
X1699983Y552731D01*
X1697117D01*
X1688857Y544471D01*
X1682949D01*
X1677579Y539101D01*
X1668020D01*
X1645969Y517050D01*
Y514870D01*
G01X1639271Y491135D02*
X1635929Y494477D01*
Y511723D01*
X1635961Y511755D01*
Y514226D01*
X1636892Y515157D01*
Y515376D01*
X1647381Y525865D01*
Y542139D01*
X1658542Y553300D01*
X1663908D01*
X1668741Y558133D01*
X1696266D01*
X1699951Y561818D01*
Y575905D01*
X1699600Y576256D01*
Y578100D01*
G01X1649336Y511502D02*
X1649715D01*
X1673791Y535578D01*
X1677815D01*
X1679480Y533913D01*
X1680786D01*
X1681709Y534836D01*
Y536142D01*
X1681285Y536566D01*
Y536915D01*
X1682196Y537826D01*
Y537871D01*
X1682195Y537872D01*
Y538826D01*
X1684384Y541015D01*
X1690291D01*
X1698550Y549274D01*
X1707788D01*
X1718923Y560409D01*
Y575433D01*
X1718916Y575440D01*
Y576738D01*
X1703950Y591704D01*
Y601838D01*
X1701088Y604700D01*
X1696293D01*
X1691047Y609946D01*
Y615512D01*
G01X1694000Y580079D02*
X1695205Y581284D01*
X1702526D01*
X1712958Y570852D01*
Y564896D01*
X1703368Y555306D01*
X1671850D01*
X1667297Y550753D01*
Y541797D01*
X1641016Y515516D01*
Y506857D01*
X1641470Y506403D01*
G01X1691047Y600551D02*
Y594843D01*
X1694290Y591600D01*
X1700794D01*
X1716612Y575782D01*
Y561358D01*
X1706832Y551578D01*
X1699506D01*
X1699505Y551579D01*
X1697595D01*
X1689335Y543319D01*
X1683427D01*
X1678057Y537949D01*
X1672700D01*
X1668396Y533645D01*
X1664194D01*
X1647859Y517310D01*
Y513884D01*
X1644651Y510676D01*
Y505500D01*
G01X1633359Y472859D02*
Y482850D01*
X1639868Y489359D01*
X1640007D01*
X1641104Y490456D01*
Y490783D01*
X1642144Y491823D01*
X1643630D01*
X1646099Y494292D01*
Y497809D01*
X1669882Y521592D01*
X1671048D01*
X1671049Y521591D01*
X1680000D01*
X1691000Y532591D01*
X1719083D01*
X1723408Y536916D01*
Y560396D01*
X1724276Y561264D01*
Y565214D01*
X1720908Y568582D01*
Y596012D01*
X1726080Y601184D01*
X1750160D01*
X1759289Y592055D01*
X1762062D01*
G01X1633075Y470174D02*
X1633186D01*
X1635175Y472163D01*
Y479642D01*
X1644656Y489123D01*
Y490857D01*
X1647507Y493708D01*
Y497225D01*
X1670465Y520183D01*
X1680584D01*
X1691584Y531183D01*
X1719667D01*
X1724816Y536332D01*
Y559812D01*
X1725684Y560680D01*
Y565944D01*
X1722316Y569312D01*
Y595428D01*
X1726664Y599776D01*
X1749576D01*
X1759797Y589555D01*
X1762062D01*
G01X1590530Y610620D02*
X1591786Y609364D01*
X1598282D01*
X1601414Y612496D01*
X1602886D01*
X1607330Y608052D01*
X1607341Y608050D01*
X1615880D01*
X1616243Y608048D01*
X1616818Y607473D01*
X1639473D01*
X1649566Y617566D01*
X1659971D01*
X1666774Y610763D01*
Y599466D01*
X1666744Y599436D01*
Y595456D01*
X1667800Y594400D01*
Y582264D01*
X1672512Y577552D01*
X1696319D01*
X1698643Y579876D01*
X1701942D01*
X1711550Y570268D01*
Y565480D01*
X1702784Y556714D01*
X1671266D01*
X1665889Y551337D01*
Y542381D01*
X1638300Y514792D01*
Y514573D01*
X1637369Y513642D01*
Y511171D01*
X1637337Y511139D01*
Y495998D01*
X1640035Y493300D01*
X1643115D01*
X1644691Y494876D01*
Y498393D01*
X1650944Y504646D01*
Y505166D01*
G01X1742381Y588530D02*
X1748306Y582605D01*
Y573008D01*
X1747626Y572328D01*
X1741501D01*
X1734635Y565462D01*
Y549451D01*
X1729880Y544696D01*
Y544646D01*
X1728105Y542871D01*
Y534455D01*
X1721074Y527424D01*
X1693292D01*
X1683085Y517217D01*
X1671619D01*
X1650419Y496017D01*
Y492457D01*
X1649226Y491264D01*
Y475631D01*
X1665584Y459273D01*
Y445606D01*
X1666643Y444547D01*
Y441554D01*
X1667462Y440735D01*
G01X1730774Y579960D02*
X1728400Y577586D01*
Y560340D01*
X1727224Y559164D01*
Y534638D01*
X1720762Y528176D01*
X1692980D01*
X1682773Y517969D01*
X1671307D01*
X1649667Y496329D01*
Y492769D01*
X1647768Y490870D01*
Y487792D01*
X1645124Y485148D01*
Y478669D01*
X1664161Y459632D01*
Y444336D01*
X1664762Y443735D01*
G01X1725694Y571814D02*
X1727500Y570008D01*
Y560504D01*
X1726472Y559476D01*
Y534950D01*
X1720450Y528928D01*
X1692668D01*
X1682461Y518721D01*
X1670995D01*
X1648915Y496641D01*
Y493081D01*
X1647016Y491182D01*
Y488104D01*
X1644372Y485460D01*
Y478357D01*
X1663125Y459604D01*
Y442372D01*
X1664762Y440735D01*
G01X1619700Y617300D02*
X1622126Y619726D01*
X1689840D01*
X1693800Y615766D01*
Y613836D01*
X1701088Y606548D01*
X1719501D01*
X1720379Y607426D01*
X1729944D01*
X1732847Y610329D01*
X1756397D01*
X1761063Y605663D01*
Y598244D01*
X1765500Y593807D01*
Y587600D01*
X1757850Y579950D01*
Y569150D01*
X1762496Y564504D01*
Y554198D01*
X1765200Y551494D01*
Y537374D01*
X1760887Y533061D01*
X1750379D01*
X1723392Y506074D01*
X1723079D01*
X1723075Y506070D01*
X1723059D01*
X1722193Y505204D01*
X1716910D01*
X1707041Y495335D01*
X1678876D01*
X1676911Y497300D01*
X1672313D01*
G01X1617600Y619800D02*
X1620853D01*
X1621531Y620478D01*
X1690152D01*
X1694752Y615878D01*
Y614983D01*
X1701982Y607753D01*
X1711731D01*
X1715609Y611631D01*
X1756159D01*
X1761895Y605895D01*
Y598476D01*
X1766476Y593895D01*
Y586300D01*
X1759296Y579120D01*
Y569204D01*
X1763248Y565252D01*
Y554510D01*
X1765952Y551806D01*
Y537062D01*
X1760999Y532109D01*
X1750491D01*
X1723704Y505322D01*
X1723391D01*
X1723387Y505318D01*
X1723371D01*
X1722505Y504452D01*
X1717222D01*
X1707257Y494487D01*
X1672604D01*
X1672159Y494042D01*
G01X1678000Y81600D02*
X1677856D01*
X1672740Y86716D01*
Y91543D01*
X1667197Y97086D01*
Y102424D01*
X1662660Y106961D01*
Y113816D01*
X1660985Y115491D01*
G01X1696655Y77991D02*
X1697209D01*
X1699308Y75892D01*
X1708004D01*
X1709891Y77779D01*
X1711996D01*
X1715743Y81526D01*
X1722673D01*
X1725184Y84037D01*
X1735779D01*
X1737699Y85957D01*
X1750244D01*
X1753928Y82273D01*
X1760285D01*
X1764112Y86100D01*
X1769252D01*
X1786420Y68932D01*
Y65910D01*
X1790210Y62120D01*
Y53682D01*
X1796592Y47300D01*
X1802334D01*
X1806009Y43625D01*
Y32041D01*
X1801000Y27032D01*
Y17546D01*
X1796900Y13446D01*
Y8319D01*
X1794078Y5497D01*
X1782939D01*
X1776351Y-1091D01*
X1767454D01*
X1761872Y-6673D01*
Y-7220D01*
G01X1680139Y99073D02*
X1681882D01*
X1684209Y101400D01*
X1704150D01*
X1711250Y94300D01*
X1742237D01*
X1743208Y93329D01*
X1750454D01*
X1757000Y99875D01*
Y118000D01*
X1758100Y119100D01*
G01X1664135Y112341D02*
Y106549D01*
X1667948Y102736D01*
Y101242D01*
X1673812Y95378D01*
X1675922D01*
X1681498Y89802D01*
X1701314D01*
X1701370Y89746D01*
X1704521D01*
X1704824Y90049D01*
G01X1664500Y99000D02*
X1656162Y107338D01*
Y110288D01*
X1654685Y111765D01*
Y112341D01*
G01X1761300Y119100D02*
X1759524Y120876D01*
X1757364D01*
X1756249Y119761D01*
Y100187D01*
X1750142Y94080D01*
X1743520D01*
X1742549Y95051D01*
X1713399D01*
X1704900Y103550D01*
X1678950D01*
X1678400Y103000D01*
G01X1821261Y170012D02*
X1816950Y174323D01*
X1814933D01*
X1812600Y176656D01*
Y177972D01*
X1802276Y188296D01*
X1729824D01*
X1715059Y203061D01*
X1683427D01*
X1678757Y207731D01*
X1673914D01*
X1672986Y206803D01*
X1670903D01*
X1667998Y209708D01*
X1663211D01*
X1659643Y213276D01*
Y213505D01*
G01X1824200Y176900D02*
Y180800D01*
X1814200Y190800D01*
X1728531D01*
X1715729Y203602D01*
X1715582D01*
X1715371Y203813D01*
X1683739D01*
X1677578Y209974D01*
X1673530D01*
G01X1707100Y188300D02*
Y187871D01*
X1709247Y185724D01*
X1711424D01*
X1712276Y186576D01*
X1722603D01*
X1727191Y181988D01*
X1758190D01*
X1762100Y178078D01*
Y176901D01*
X1767283Y171718D01*
X1781191D01*
X1782454Y170455D01*
X1786837D01*
X1790000Y167292D01*
X1793815D01*
X1797184Y163923D01*
Y142512D01*
X1799301Y140395D01*
X1806734D01*
X1813553Y133576D01*
Y132474D01*
X1813555Y132472D01*
Y132312D01*
X1816315Y129552D01*
X1817071D01*
X1817994Y128629D01*
Y127323D01*
X1815903Y125232D01*
X1813779D01*
X1811946Y123399D01*
Y117535D01*
X1819600Y109881D01*
Y82700D01*
X1818779Y81879D01*
Y76634D01*
X1820513Y74900D01*
X1823991D01*
X1827500Y71391D01*
Y69000D01*
X1833582Y62918D01*
Y44168D01*
X1835876Y41874D01*
Y40397D01*
X1833620Y38141D01*
Y36961D01*
X1827972Y31313D01*
X1825591D01*
X1817109Y22831D01*
Y18891D01*
X1820872Y15128D01*
Y3172D01*
X1819800Y2100D01*
G01X1660985Y159585D02*
X1661945Y160545D01*
X1662057D01*
X1664201Y162689D01*
Y162801D01*
X1669700Y168300D01*
Y175486D01*
X1671722Y177508D01*
X1673309D01*
X1673366Y177565D01*
X1674672D01*
X1674729Y177508D01*
X1675040D01*
X1677841Y174707D01*
Y174575D01*
X1678141Y174275D01*
X1678253D01*
X1679175Y173353D01*
Y173241D01*
X1679966Y172450D01*
X1680098D01*
X1687606Y164942D01*
X1691467D01*
X1693643Y162766D01*
X1696865D01*
X1697202Y163103D01*
X1710403D01*
X1712307Y161199D01*
X1767997D01*
X1771791Y157405D01*
Y152292D01*
X1795583Y128500D01*
X1803509D01*
G01X1705666Y198055D02*
Y196097D01*
X1710302Y191461D01*
X1711600D01*
X1711606Y191460D01*
X1713565D01*
X1713571Y191461D01*
X1714186Y192076D01*
X1720295D01*
X1728127Y184244D01*
X1771912D01*
X1774800Y181356D01*
Y176800D01*
X1777364Y174236D01*
X1781865D01*
X1782601Y173500D01*
X1788048D01*
X1792000Y169548D01*
X1796333D01*
X1799484Y166397D01*
Y159900D01*
X1804007Y155377D01*
Y146314D01*
X1814311Y136010D01*
X1818224D01*
X1820285Y133949D01*
Y127486D01*
X1816309Y123510D01*
X1814369D01*
X1813450Y122591D01*
Y120615D01*
X1817800Y116265D01*
Y114000D01*
X1821350Y110450D01*
Y98270D01*
G01X1688046Y174447D02*
X1690034Y172459D01*
X1702630D01*
X1705417Y169672D01*
X1712566D01*
X1716858Y165380D01*
X1769716D01*
X1776828Y158268D01*
Y155211D01*
G01X1674455Y172658D02*
X1675088D01*
X1676030Y171716D01*
Y167470D01*
X1680838Y162662D01*
X1685046D01*
X1689208Y158500D01*
X1710130D01*
X1712112Y156518D01*
X1761160D01*
X1762711Y158069D01*
X1769497D01*
X1770639Y156927D01*
Y151814D01*
X1789593Y132860D01*
Y132782D01*
X1798076Y124299D01*
Y119347D01*
X1797720Y118991D01*
Y107980D01*
X1801600Y104100D01*
Y86100D01*
X1815300Y72400D01*
Y69709D01*
X1821109Y63900D01*
X1826030D01*
X1829728Y60202D01*
Y40999D01*
X1826943Y38214D01*
X1824870D01*
X1824783Y38127D01*
X1821458D01*
X1820457Y39128D01*
G01X1807166Y147401D02*
Y155826D01*
X1801976Y161016D01*
Y168640D01*
X1800328Y170288D01*
Y175765D01*
X1798997Y177096D01*
Y182441D01*
X1793897Y187541D01*
X1729208D01*
X1718431Y198318D01*
Y198625D01*
X1714747Y202309D01*
X1681268D01*
X1677527Y206050D01*
X1676750D01*
G01X1688451Y249716D02*
X1688691Y249476D01*
X1692176D01*
X1695812Y253112D01*
X1821571D01*
X1822724Y251959D01*
Y249419D01*
X1825362Y246781D01*
X1841093D01*
X1843449Y244425D01*
G01X1860969Y136369D02*
X1860312Y137026D01*
Y139625D01*
X1864471Y143784D01*
Y150775D01*
X1860552Y154694D01*
Y172405D01*
X1870812Y182665D01*
Y200240D01*
X1861652Y209400D01*
X1860524D01*
X1857996Y211928D01*
Y215310D01*
X1863578Y220892D01*
X1868877D01*
X1876356Y228371D01*
Y245550D01*
X1858238Y263668D01*
X1681849D01*
X1674556Y270961D01*
Y298809D01*
X1677847Y302100D01*
X1679100D01*
G01Y304700D02*
X1673604Y299204D01*
Y270849D01*
X1681537Y262916D01*
X1857643D01*
X1875404Y245155D01*
Y228766D01*
X1868482Y221844D01*
X1863391D01*
X1857494Y215947D01*
Y215872D01*
X1857244Y215622D01*
Y211616D01*
X1860212Y208648D01*
X1861057D01*
X1869860Y199845D01*
Y183060D01*
X1859800Y173000D01*
Y154100D01*
X1863519Y150381D01*
Y144179D01*
X1859352Y140012D01*
Y135386D01*
X1860969Y133769D01*
G01X1670140Y257547D02*
Y256241D01*
X1669499Y255600D01*
X1665564D01*
X1664765Y256399D01*
Y301717D01*
X1667200Y309439D01*
Y309647D01*
X1664765Y319934D01*
Y372581D01*
X1662516Y374830D01*
Y377040D01*
X1663124Y377648D01*
X1663952D01*
X1664905Y376695D01*
G01X1670822Y254691D02*
X1670816Y254697D01*
Y254717D01*
X1670464Y255069D01*
X1670032D01*
X1669811Y254848D01*
X1665252D01*
X1664013Y256087D01*
Y301836D01*
X1666448Y309558D01*
X1664013Y319828D01*
Y372269D01*
X1661741Y374541D01*
Y377409D01*
X1662732Y378400D01*
X1664035D01*
X1664829Y379194D01*
G01X1859604Y213206D02*
X1859550Y213260D01*
Y214594D01*
X1862589Y217633D01*
X1867187D01*
X1877847Y228293D01*
Y252909D01*
X1866336Y264420D01*
X1682161D01*
X1675907Y270674D01*
Y296318D01*
X1678364Y298775D01*
X1678375D01*
X1679100Y299500D01*
G01X1861497Y211481D02*
Y215197D01*
X1862983Y216683D01*
X1867772D01*
X1878797Y227708D01*
Y253303D01*
X1866928Y265172D01*
X1682473D01*
X1676857Y270788D01*
Y295924D01*
X1677933Y297000D01*
X1679100D01*
G01X1660890Y397300D02*
X1659359D01*
X1657120Y395061D01*
X1654208D01*
X1653194Y396075D01*
Y402802D01*
X1656806Y406414D01*
Y410699D01*
X1674204Y428097D01*
Y430698D01*
X1681866Y438360D01*
X1866260D01*
X1878100Y450200D01*
G01X1654861Y396637D02*
X1656387D01*
X1658310Y398560D01*
Y406610D01*
X1662200Y410500D01*
X1670001D01*
X1677298Y417797D01*
Y430600D01*
X1682802Y436104D01*
X1895076D01*
X1900162Y441190D01*
X1934550D01*
X1938862Y436878D01*
X1959132D01*
X1971728Y449474D01*
Y468662D01*
X1965650Y474740D01*
Y500450D01*
X1971728Y506528D01*
Y523736D01*
X1968128Y527336D01*
Y610272D01*
X1961700Y616700D01*
G01X1885100Y584300D02*
Y579083D01*
X1900674Y563509D01*
X1919683D01*
X1927610Y555582D01*
Y544812D01*
X1927609Y544811D01*
Y543857D01*
X1940366Y531100D01*
X1949424D01*
X1955742Y524782D01*
X1967308D01*
X1970176Y521914D01*
Y507456D01*
X1963940Y501220D01*
Y473316D01*
X1970176Y467080D01*
Y450270D01*
X1958363Y438457D01*
X1939640D01*
X1935291Y442806D01*
X1899650D01*
X1894452Y437608D01*
X1682178D01*
X1674956Y430386D01*
Y427561D01*
X1667671Y420276D01*
X1667447D01*
X1657558Y410387D01*
Y401808D01*
X1654895Y399145D01*
X1654770D01*
G01X1660934Y387883D02*
X1661283D01*
X1663500Y390100D01*
Y402238D01*
X1662438Y403300D01*
X1660200D01*
X1659100Y404400D01*
Y405500D01*
X1663348Y409748D01*
X1670549D01*
X1678450Y417649D01*
Y430688D01*
X1683114Y435352D01*
X1895388D01*
X1900074Y440038D01*
X1934072D01*
X1938384Y435726D01*
X1959610D01*
X1972480Y448596D01*
Y524752D01*
X1969972Y527260D01*
Y611228D01*
X1961700Y619500D01*
G01X1660834Y404934D02*
X1663934Y408034D01*
X1670334D01*
X1679700Y417400D01*
Y430874D01*
X1683426Y434600D01*
X1895700D01*
X1899986Y438886D01*
X1933594D01*
X1937906Y434574D01*
X1960088D01*
X1973240Y447726D01*
Y525760D01*
X1971124Y527876D01*
Y613776D01*
X1965400Y619500D01*
G01X1681154Y449286D02*
X1681669D01*
X1687652Y455269D01*
Y461305D01*
X1685305Y463652D01*
X1685304D01*
X1683661Y465295D01*
Y468719D01*
X1686701Y471759D01*
Y479570D01*
X1685867Y480404D01*
Y487856D01*
X1687259Y489248D01*
X1724040D01*
X1730069Y495277D01*
X1731343D01*
X1735649Y499583D01*
Y503185D01*
X1758028Y525564D01*
X1763037D01*
X1770622Y533149D01*
X1785351D01*
X1798709Y519791D01*
X1804571D01*
X1808774Y523994D01*
Y526303D01*
X1809697Y527226D01*
X1812774D01*
X1813500Y526500D01*
G01X1757319Y606953D02*
Y607079D01*
X1754662Y604422D01*
Y602338D01*
X1764000Y593000D01*
Y588500D01*
X1756500Y581000D01*
Y573482D01*
X1751929Y568911D01*
Y550675D01*
X1751930Y550674D01*
Y549638D01*
X1749696Y547404D01*
X1748404D01*
X1739000Y538000D01*
Y523453D01*
X1725940Y510393D01*
X1714107D01*
X1708052Y504338D01*
Y499435D01*
X1705204Y496587D01*
X1680327D01*
X1675518Y501396D01*
X1671953D01*
X1669683Y499126D01*
Y494289D01*
X1671546Y492426D01*
X1671703D01*
X1674830Y489299D01*
Y476676D01*
X1674031Y475877D01*
Y460874D01*
X1673213Y460056D01*
Y455800D01*
X1674389Y454624D01*
X1676397D01*
X1679145Y457372D01*
Y461950D01*
G01X1667809Y427809D02*
X1668936Y426682D01*
X1669816D01*
X1672700Y429566D01*
Y431322D01*
X1683752Y442374D01*
X1705529D01*
X1721956Y458801D01*
X1820201D01*
X1823519Y462119D01*
X1823549D01*
X1838730Y477300D01*
X1842174D01*
X1843750Y475724D01*
G01X1667729Y424621D02*
X1667809D01*
X1668918Y425730D01*
X1670211D01*
X1673452Y428971D01*
Y431010D01*
X1684064Y441622D01*
X1705841D01*
X1722068Y457849D01*
X1820596D01*
X1823914Y461167D01*
X1823944D01*
X1838877Y476100D01*
X1840398D01*
X1840750Y475748D01*
Y475724D01*
G01X1884100Y493000D02*
Y497000D01*
X1883500Y497600D01*
X1879797D01*
X1869505Y487308D01*
X1869485D01*
X1868562Y486385D01*
Y486365D01*
X1865697Y483500D01*
X1843017D01*
X1820317Y460800D01*
X1719353D01*
X1711001Y469152D01*
X1695578D01*
X1695577Y469153D01*
X1694323D01*
X1691317Y466147D01*
Y451003D01*
X1672388Y432074D01*
X1668874D01*
X1667649Y430849D01*
G01X1904100Y493000D02*
X1898300Y498800D01*
X1879433D01*
X1865232Y484599D01*
X1842769D01*
X1819922Y461752D01*
X1719748D01*
X1711396Y470104D01*
X1695973D01*
X1695972Y470105D01*
X1695018D01*
X1695017Y470106D01*
X1694882D01*
X1694881Y470105D01*
X1693928D01*
X1690365Y466542D01*
Y451115D01*
X1672276Y433026D01*
X1668711D01*
X1667588Y434149D01*
G01X1668100Y418700D02*
X1668812D01*
X1675708Y425596D01*
Y430074D01*
X1682490Y436856D01*
X1894764D01*
X1899962Y442054D01*
X1934979D01*
X1939328Y437705D01*
X1958675D01*
X1970976Y450006D01*
Y467984D01*
X1964810Y474150D01*
Y500790D01*
X1970976Y506956D01*
Y522790D01*
X1966976Y526790D01*
Y596334D01*
X1948810Y614500D01*
X1927000D01*
G01X1809309Y555713D02*
X1809513Y555917D01*
X1816092D01*
X1822467Y549542D01*
Y526180D01*
X1817764Y521477D01*
X1813675D01*
X1804070Y511872D01*
X1788532D01*
X1775309Y498649D01*
Y489827D01*
X1765630Y480148D01*
X1734114D01*
X1724201Y470235D01*
X1718729D01*
X1713675Y475289D01*
X1710683D01*
X1703193Y482779D01*
Y483359D01*
X1702270Y484282D01*
X1700964D01*
X1685965Y469283D01*
Y465365D01*
X1689225Y462105D01*
Y451039D01*
X1680951Y442765D01*
X1678303D01*
G01X1743200Y567300D02*
X1742800D01*
X1741000Y565500D01*
Y561500D01*
X1745528Y556972D01*
Y550602D01*
X1735498Y540572D01*
Y533642D01*
X1723624Y521768D01*
X1695682D01*
X1682701Y508787D01*
X1671902D01*
X1664423Y501308D01*
Y476328D01*
X1670419Y470332D01*
Y462725D01*
X1669594Y461900D01*
Y449175D01*
X1669816Y448953D01*
G01X1673064Y446022D02*
X1671430Y447656D01*
Y450400D01*
X1670546Y451284D01*
Y461505D01*
X1671371Y462330D01*
Y470727D01*
X1669737Y472361D01*
Y474878D01*
X1672626Y477767D01*
Y484253D01*
X1671461Y485418D01*
X1670403D01*
X1667479Y488342D01*
Y500040D01*
X1672051Y504612D01*
X1677700D01*
X1679583Y502729D01*
X1689128D01*
X1689438Y502419D01*
X1690900D01*
X1691467Y502986D01*
X1693837D01*
X1707271Y516420D01*
X1728849D01*
X1736500Y524071D01*
Y540227D01*
X1746480Y550207D01*
Y561348D01*
X1746128Y561700D01*
X1743100D01*
G01X1681500Y482000D02*
X1681369Y481869D01*
Y476761D01*
X1682364Y475766D01*
Y472874D01*
X1680721Y471231D01*
Y456222D01*
X1677880Y453381D01*
Y444797D01*
X1671364Y438281D01*
X1669076D01*
G01X1795200Y525700D02*
X1785006Y535894D01*
X1771737D01*
X1762559Y526716D01*
X1756847D01*
X1735753Y505622D01*
X1727762D01*
X1724806Y502666D01*
X1724493D01*
X1724489Y502662D01*
X1724473D01*
X1712211Y490400D01*
X1686781D01*
X1684484Y488103D01*
Y479746D01*
X1685549Y478681D01*
Y472237D01*
X1682509Y469197D01*
Y464818D01*
X1682735Y464592D01*
Y464591D01*
X1684827Y462499D01*
X1684828D01*
X1686500Y460827D01*
Y455747D01*
X1682539Y451786D01*
X1681215D01*
G01X1754897Y578750D02*
X1750677Y574530D01*
Y550156D01*
X1749177Y548656D01*
X1747485D01*
X1737500Y538671D01*
Y523724D01*
X1729244Y515468D01*
X1708575D01*
X1699446Y506339D01*
Y502637D01*
X1695063Y498254D01*
X1682269D01*
X1677595Y502928D01*
X1671714D01*
X1668431Y499645D01*
Y491240D01*
X1670528Y489143D01*
X1671136D01*
X1673578Y486701D01*
Y477372D01*
X1670689Y474483D01*
Y472756D01*
X1672323Y471122D01*
Y461935D01*
X1671498Y461110D01*
Y452158D01*
X1673068Y450588D01*
Y448522D01*
G01X1738434Y588986D02*
X1740002D01*
X1740755Y589739D01*
Y592415D01*
X1741779Y593439D01*
X1743246D01*
X1749058Y587627D01*
Y572696D01*
X1747938Y571576D01*
X1741813D01*
X1736294Y566057D01*
Y556917D01*
X1737380Y555831D01*
X1739151D01*
X1740286Y554696D01*
Y547771D01*
X1733794Y541279D01*
Y534349D01*
X1722965Y523520D01*
X1694911D01*
X1684704Y513313D01*
X1674017D01*
X1662719Y502015D01*
Y464847D01*
X1667488Y460078D01*
Y446396D01*
X1669816Y444068D01*
Y443953D01*
G01X1737958Y560500D02*
X1739608D01*
X1744576Y555532D01*
Y550997D01*
X1734546Y540967D01*
Y534037D01*
X1723277Y522768D01*
X1695223D01*
X1685016Y512561D01*
X1674329D01*
X1663471Y501703D01*
Y465159D01*
X1668240Y460390D01*
Y448029D01*
X1669816Y446453D01*
G01X1671050Y483600D02*
X1670226Y482776D01*
X1668811D01*
X1666327Y485260D01*
Y500518D01*
X1672692Y506883D01*
X1688050D01*
X1698914Y517747D01*
Y519245D01*
X1699861Y520192D01*
G01X1697261D02*
X1698162Y519291D01*
Y518059D01*
X1687738Y507635D01*
X1672380D01*
X1665575Y500830D01*
Y484948D01*
X1668499Y482024D01*
X1670026D01*
X1671050Y481000D01*
G01X1687741Y466988D02*
X1692410Y471657D01*
X1712038D01*
X1720391Y463304D01*
X1733474D01*
X1739115Y468945D01*
X1809528D01*
X1812872Y472289D01*
X1824139D01*
X1824224Y472204D01*
X1828382D01*
X1836396Y480218D01*
Y481349D01*
G01X1698354Y486873D02*
X1699190Y487709D01*
X1724131D01*
X1730547Y494125D01*
X1734149D01*
X1750800Y510776D01*
Y516100D01*
G01X1701617Y482706D02*
Y478574D01*
X1706287Y473904D01*
X1711986D01*
X1718590Y467300D01*
X1731000D01*
X1734824Y471124D01*
X1769324D01*
X1770600Y472400D01*
Y474769D01*
X1781700Y485869D01*
Y492110D01*
X1783050Y493460D01*
X1795260D01*
X1801900Y500100D01*
X1808100D01*
X1812391Y504391D01*
Y507291D01*
X1838600Y533500D01*
Y544700D01*
X1842100Y548200D01*
X1848900D01*
G01X1701291Y602268D02*
Y592733D01*
X1717764Y576260D01*
Y560880D01*
X1707310Y550426D01*
X1699028D01*
X1699027Y550427D01*
X1698073D01*
X1689813Y542167D01*
X1683906D01*
X1680133Y538394D01*
Y535489D01*
G01X1757772Y90174D02*
X1759096Y91498D01*
X1771213D01*
X1789913Y72798D01*
X1796051D01*
X1799448Y69401D01*
Y59899D01*
X1798228Y58679D01*
Y53398D01*
X1810020Y41606D01*
Y32480D01*
X1811398Y31102D01*
Y25932D01*
X1809800Y24334D01*
Y15800D01*
X1807219Y13219D01*
Y10684D01*
X1808603Y9300D01*
G01X1816723Y9781D02*
X1813950D01*
X1810700Y13031D01*
Y24170D01*
X1812150Y25620D01*
Y31414D01*
X1810772Y32792D01*
Y41294D01*
X1810773Y41295D01*
Y41917D01*
X1798980Y53710D01*
Y58367D01*
X1800200Y59587D01*
Y69713D01*
X1796363Y73550D01*
X1790225D01*
X1771525Y92250D01*
X1757501D01*
X1755662Y90411D01*
Y86527D01*
X1757395Y84794D01*
G01X1824130Y39703D02*
Y41384D01*
X1823756Y41758D01*
Y47341D01*
X1828576Y52161D01*
Y59724D01*
X1825552Y62748D01*
X1820631D01*
X1813393Y69986D01*
Y71907D01*
X1795018Y90282D01*
Y102467D01*
X1793015Y104470D01*
Y126379D01*
X1788441Y130953D01*
Y132382D01*
X1768886Y151937D01*
Y156173D01*
G01X1719089Y472104D02*
X1720008D01*
X1731252Y483348D01*
X1756186D01*
X1762500Y489662D01*
Y491650D01*
X1767843Y496993D01*
Y508733D01*
X1773486Y514376D01*
X1793748D01*
X1795500Y512624D01*
X1803192D01*
X1812797Y522229D01*
X1817452D01*
X1821715Y526492D01*
Y533440D01*
X1810052Y545103D01*
G01X1825900Y523500D02*
X1825076Y522676D01*
Y522657D01*
X1811519Y509100D01*
X1786824D01*
X1781020Y503296D01*
Y496137D01*
X1779788Y494905D01*
Y485587D01*
X1772332Y478131D01*
X1760674D01*
X1759939Y477396D01*
X1736896D01*
X1729700Y470200D01*
X1728700D01*
G01X1722347Y471811D02*
X1722365D01*
Y472185D01*
X1732376Y482196D01*
X1756664D01*
X1763653Y489185D01*
Y490139D01*
X1763652Y490140D01*
Y491172D01*
X1768595Y496115D01*
Y504540D01*
X1776695Y512640D01*
G01X1816800Y525700D02*
X1816024Y524924D01*
X1812058D01*
X1805558Y518424D01*
X1775962D01*
X1770158Y524228D01*
X1758928D01*
X1750800Y516100D01*
G01X1770600Y600800D02*
Y574083D01*
X1770719Y573964D01*
G01X1772578Y575993D02*
Y602123D01*
X1768374Y606327D01*
Y615256D01*
X1764912Y618718D01*
G01X1808226Y136171D02*
Y136011D01*
X1814694Y129543D01*
Y127323D01*
X1813771Y126400D01*
X1812857D01*
X1810794Y124337D01*
Y116961D01*
X1818300Y109455D01*
Y83040D01*
X1817604Y82344D01*
Y70665D01*
X1820934Y67335D01*
X1826266D01*
X1832430Y61171D01*
Y37401D01*
X1827494Y32465D01*
X1825113D01*
X1825112Y32464D01*
X1824823D01*
X1815309Y22950D01*
Y18791D01*
X1819720Y14380D01*
Y4514D01*
X1815806Y600D01*
X1806564D01*
X1806411Y753D01*
X1805840D01*
X1805765Y828D01*
X1803835D01*
X1803759Y752D01*
X1787588D01*
X1787436Y600D01*
X1785104D01*
X1779504Y-5000D01*
G01X1807818Y124179D02*
Y114682D01*
X1816768Y105732D01*
Y83138D01*
X1816452Y82822D01*
Y70187D01*
X1820739Y65900D01*
X1825660D01*
X1830953Y60607D01*
Y39947D01*
X1831230Y39670D01*
Y37831D01*
X1827016Y33617D01*
X1824346D01*
X1814157Y23428D01*
Y19269D01*
X1814156Y19268D01*
Y18314D01*
X1814157Y18313D01*
Y18193D01*
X1818568Y13782D01*
Y6950D01*
X1813913Y2295D01*
Y2287D01*
G01X1825870Y21587D02*
X1827983Y23700D01*
X1838200D01*
X1844245Y29745D01*
Y44515D01*
X1844222Y44538D01*
Y49230D01*
X1846736Y51744D01*
X1854196D01*
X1873252Y70800D01*
Y82390D01*
X1878662Y87800D01*
X1881581D01*
X1899873Y106092D01*
Y107820D01*
X1897796Y109897D01*
X1894939D01*
X1891594Y113242D01*
Y131933D01*
X1881568Y141959D01*
Y148150D01*
X1884404Y150986D01*
Y157243D01*
X1881509Y160138D01*
Y173479D01*
X1879752Y175236D01*
Y192590D01*
X1878730Y193612D01*
Y201730D01*
X1883850Y206850D01*
X1887050D01*
X1890500Y210300D01*
Y229800D01*
X1893159Y232459D01*
X1901342D01*
X1902507Y231294D01*
X1902907D01*
G01X1823300Y21700D02*
Y22573D01*
X1828983Y28256D01*
X1829320D01*
X1830064Y29000D01*
X1838171D01*
X1843470Y34299D01*
Y41334D01*
X1843471Y41335D01*
Y41957D01*
X1843470Y41958D01*
Y49542D01*
X1846424Y52496D01*
X1853624D01*
X1872500Y71372D01*
Y82702D01*
X1878698Y88900D01*
X1880700D01*
X1893063Y101263D01*
Y109645D01*
X1889831Y112877D01*
Y131568D01*
X1880064Y141335D01*
Y148774D01*
X1882900Y151610D01*
Y156619D01*
X1880005Y159514D01*
Y172855D01*
X1878248Y174612D01*
Y191142D01*
X1875360Y194030D01*
Y206260D01*
X1876700Y207600D01*
G01X1837900Y9700D02*
X1836700Y8500D01*
X1828864D01*
X1827100Y10264D01*
Y12793D01*
X1830066Y15759D01*
X1838091D01*
X1843196Y20864D01*
Y27297D01*
X1847924Y32025D01*
X1866524D01*
X1874699Y40200D01*
X1878800D01*
G01X1927064Y207564D02*
X1932465D01*
X1940976Y199053D01*
Y183646D01*
X1940515Y183185D01*
Y175095D01*
X1946038Y169572D01*
Y164655D01*
X1946732Y163961D01*
Y157273D01*
X1940106Y150647D01*
Y144906D01*
X1936400Y141200D01*
Y115800D01*
X1927377Y106777D01*
Y95877D01*
X1922576Y91076D01*
Y79617D01*
X1912459Y69500D01*
X1901500D01*
X1899470Y67470D01*
X1890189D01*
X1885260Y62541D01*
Y39753D01*
X1881315Y35808D01*
X1871467D01*
X1866932Y31273D01*
X1848786D01*
X1843948Y26435D01*
Y23347D01*
X1843949Y23346D01*
Y20281D01*
X1838675Y15007D01*
X1834349D01*
X1832842Y13500D01*
G01X1824564Y3441D02*
X1822024Y5981D01*
Y16353D01*
X1818261Y20116D01*
Y22353D01*
X1826069Y30161D01*
X1828531D01*
X1834772Y36402D01*
Y37131D01*
X1836094Y38453D01*
X1837348D01*
X1837349Y38452D01*
X1838781D01*
X1840076Y39747D01*
Y41336D01*
X1835100Y46312D01*
Y64306D01*
X1829584Y69822D01*
Y76107D01*
X1822664Y83027D01*
Y87674D01*
X1828726Y93736D01*
Y106744D01*
X1822941Y112529D01*
Y135081D01*
X1817248Y140774D01*
Y154208D01*
X1817924Y154884D01*
Y157847D01*
X1814772Y160999D01*
Y168139D01*
X1816125Y169492D01*
G01X1854900Y175900D02*
Y172100D01*
X1856800Y170200D01*
Y166000D01*
X1855300Y164500D01*
Y162300D01*
X1856301Y161299D01*
Y154713D01*
X1851868Y150280D01*
Y140000D01*
X1851258Y139390D01*
Y125342D01*
X1860300Y116300D01*
Y108900D01*
X1870723Y98477D01*
Y71723D01*
X1853000Y54000D01*
X1845800D01*
X1841800Y50000D01*
Y38900D01*
X1840200Y37300D01*
X1836571D01*
X1835924Y36653D01*
Y35924D01*
X1829008Y29008D01*
X1827808D01*
X1821700Y22900D01*
Y19400D01*
X1825700Y15400D01*
Y10300D01*
X1828500Y7500D01*
X1832000D01*
X1835600Y3900D01*
G01X1824509Y143653D02*
X1824064D01*
X1822950Y142539D01*
Y140970D01*
X1824748Y139172D01*
G01X1822198Y140602D02*
Y142587D01*
X1821348Y143437D01*
G01X1939845Y445055D02*
X1944733Y449943D01*
Y467300D01*
X1953800Y476367D01*
Y488071D01*
X1949330Y492541D01*
Y514040D01*
X1943270Y520100D01*
X1930570D01*
X1924648Y514178D01*
X1921078D01*
X1914700Y507800D01*
X1902647D01*
X1897897Y503050D01*
X1882430D01*
X1876761Y497381D01*
X1848319D01*
X1845324Y500376D01*
X1827975D01*
X1822359Y505992D01*
Y515428D01*
X1825931Y519000D01*
X1828200D01*
G01X1800378Y593527D02*
X1801474D01*
X1811200Y583801D01*
Y581668D01*
X1803752Y574220D01*
Y529301D01*
G01X1809600Y582800D02*
X1801170Y574370D01*
Y568080D01*
X1793660Y560570D01*
G01X1829176Y584287D02*
X1832472Y587583D01*
Y594984D01*
X1835118Y597630D01*
X1840555D01*
X1844123Y594062D01*
X1882683D01*
X1886500Y597879D01*
Y607519D01*
X1891086Y612105D01*
G01Y592105D02*
X1890081Y593110D01*
X1843364D01*
X1839653Y596821D01*
X1836952D01*
X1833224Y593093D01*
Y587271D01*
X1832472Y586519D01*
Y585002D01*
X1829550Y582080D01*
X1818073D01*
X1816052Y584101D01*
G01X1876792Y18461D02*
X1878179Y19848D01*
X1879205D01*
X1880491Y18562D01*
X1887421D01*
X1892400Y23541D01*
Y56400D01*
X1902448Y66448D01*
X1913848D01*
X1925500Y78100D01*
Y90100D01*
X1930106Y94706D01*
Y104326D01*
X1938884Y113104D01*
Y140020D01*
X1947277Y148413D01*
Y152801D01*
X1949588Y155112D01*
Y165146D01*
X1948894Y165840D01*
Y200482D01*
X1937426Y211950D01*
X1933711D01*
X1922552Y223109D01*
Y230652D01*
X1923800Y231900D01*
X1925400D01*
X1926100Y231200D01*
G01X1876881Y22181D02*
X1878262Y20800D01*
X1879600D01*
X1880886Y19514D01*
X1887026D01*
X1891448Y23936D01*
Y56512D01*
X1902336Y67400D01*
X1913453D01*
X1924548Y78495D01*
Y90495D01*
X1929272Y95219D01*
Y104672D01*
X1938050Y113450D01*
Y140250D01*
X1946525Y148725D01*
Y153396D01*
X1948636Y155507D01*
Y164751D01*
X1947942Y165445D01*
Y200087D01*
X1937031Y210998D01*
X1933316D01*
X1921800Y222514D01*
Y231000D01*
X1923500Y232700D01*
X1924800D01*
X1925835Y233735D01*
G01X1930500Y209464D02*
X1931648Y208316D01*
X1932777D01*
X1941728Y199365D01*
Y183334D01*
X1941507Y183113D01*
Y175473D01*
X1946790Y170190D01*
Y164967D01*
X1947484Y164273D01*
Y156941D01*
X1940858Y150315D01*
Y144594D01*
X1937152Y140888D01*
Y115488D01*
X1928129Y106465D01*
Y95429D01*
X1923328Y90628D01*
Y79305D01*
X1912623Y68600D01*
X1902300D01*
X1900338Y66638D01*
X1890421D01*
X1886260Y62477D01*
Y43489D01*
X1886012Y43241D01*
Y39441D01*
X1881627Y35056D01*
X1877827D01*
X1877775Y35004D01*
X1871727D01*
X1867243Y30520D01*
X1866621D01*
X1866620Y30521D01*
X1849098D01*
X1844700Y26123D01*
Y23659D01*
X1844702Y23657D01*
Y23035D01*
X1844701Y23034D01*
Y18943D01*
X1841879Y16121D01*
Y11179D01*
X1840400Y9700D01*
G01X1886299Y153928D02*
X1887722Y152505D01*
Y150304D01*
X1886573Y149155D01*
X1884001D01*
X1882321Y147475D01*
Y142270D01*
X1892346Y132245D01*
Y113554D01*
X1895250Y110650D01*
X1898107D01*
X1900625Y108132D01*
Y105780D01*
X1881893Y87048D01*
X1878974D01*
X1874283Y82357D01*
Y60626D01*
X1873956Y60299D01*
G01X1857919Y156123D02*
X1857937D01*
Y155285D01*
X1852620Y149968D01*
Y139688D01*
X1852010Y139078D01*
Y126430D01*
X1861476Y116964D01*
Y108788D01*
X1871475Y98789D01*
Y71411D01*
X1853312Y53248D01*
X1846112D01*
X1842718Y49854D01*
Y34967D01*
X1841551Y33800D01*
X1839400D01*
X1837500Y35700D01*
G01X1878997Y37546D02*
X1884500Y43049D01*
Y62845D01*
X1890255Y68600D01*
X1899000D01*
X1901414Y71014D01*
X1909602D01*
X1919955Y81367D01*
Y123635D01*
X1925426Y129106D01*
Y136874D01*
X1929400Y140848D01*
Y153600D01*
X1928527Y154473D01*
X1926042D01*
X1922674Y157841D01*
Y184545D01*
X1930666Y192537D01*
Y193843D01*
X1925591Y198918D01*
Y202498D01*
X1920744Y207345D01*
Y217391D01*
X1918215Y219920D01*
Y219848D01*
X1918143D01*
G01X1840149Y244425D02*
Y243419D01*
X1842917Y240651D01*
X1844373D01*
X1853095Y231929D01*
Y214964D01*
X1853604Y214455D01*
Y211267D01*
X1850248Y207911D01*
Y192435D01*
X1851747Y190936D01*
Y175117D01*
X1850600Y173970D01*
Y159020D01*
X1852337Y157283D01*
Y152875D01*
X1850366Y150904D01*
Y140624D01*
X1849756Y140014D01*
Y124598D01*
X1857110Y117244D01*
Y113600D01*
G01X1875425Y152925D02*
X1875150Y153200D01*
X1874652D01*
X1874300Y152848D01*
Y139000D01*
X1879600Y133700D01*
X1886352D01*
X1888879Y131173D01*
Y111781D01*
X1890800Y109860D01*
Y105774D01*
X1890974Y105600D01*
G01X1898102Y107325D02*
Y108175D01*
X1897133Y109144D01*
X1894628D01*
X1890654Y113118D01*
Y131809D01*
X1880816Y141647D01*
Y148462D01*
X1883652Y151298D01*
Y156931D01*
X1880757Y159826D01*
Y173167D01*
X1879000Y174924D01*
Y191740D01*
X1877880Y192860D01*
Y203780D01*
G01X1857020Y129619D02*
X1858143Y128496D01*
X1862224D01*
X1863235Y129507D01*
Y136602D01*
X1865499Y138866D01*
Y154560D01*
X1867392Y156453D01*
X1872409D01*
X1874304Y158348D01*
Y172720D01*
X1872164Y174860D01*
Y201076D01*
X1866448Y206792D01*
Y212564D01*
X1883172Y229288D01*
Y231010D01*
X1882345Y231837D01*
G01X1882200Y234400D02*
X1883924Y232676D01*
Y228976D01*
X1867200Y212252D01*
Y207104D01*
X1872916Y201388D01*
Y175172D01*
X1875056Y173032D01*
Y158036D01*
X1872720Y155700D01*
X1867703D01*
X1866251Y154248D01*
Y138554D01*
X1863987Y136290D01*
Y129195D01*
X1862536Y127744D01*
X1858145D01*
X1857020Y126619D01*
G01X1903020Y225776D02*
X1903314D01*
X1904485Y224605D01*
Y221620D01*
X1901574Y218709D01*
Y196238D01*
X1902876Y194936D01*
Y189569D01*
X1892740Y179433D01*
Y165638D01*
X1898714Y159664D01*
Y146114D01*
X1897000Y144400D01*
Y139083D01*
X1899683Y136400D01*
Y121025D01*
X1902704Y118004D01*
X1906414D01*
G01X1883800Y179100D02*
X1885300Y180600D01*
X1887600D01*
X1891332Y176868D01*
Y165275D01*
X1897462Y159145D01*
Y147471D01*
X1893040Y143049D01*
Y135888D01*
X1895850Y133078D01*
Y118950D01*
X1899495Y115305D01*
X1906467D01*
G01X1848100Y134750D02*
Y138690D01*
X1843310Y143480D01*
Y146703D01*
X1843642Y147035D01*
Y149985D01*
X1844193Y150536D01*
Y171163D01*
X1849822Y176792D01*
Y188642D01*
X1849096Y189368D01*
Y208389D01*
X1852452Y211745D01*
Y213977D01*
X1851942Y214487D01*
Y218089D01*
X1850781Y219250D01*
X1850723D01*
G01X1875700Y184800D02*
Y191990D01*
X1874500Y193190D01*
Y207938D01*
X1874852Y208290D01*
X1875161D01*
X1876047Y209176D01*
X1877353D01*
X1878239Y208290D01*
X1887082D01*
X1889401Y210609D01*
Y219499D01*
X1884800Y224100D01*
X1884400D01*
G01X1925000Y192000D02*
Y192329D01*
X1921871Y195458D01*
Y199541D01*
X1916252Y205160D01*
Y207040D01*
X1913884Y209408D01*
Y230016D01*
X1910689Y233211D01*
X1889127D01*
X1886108Y230192D01*
Y228608D01*
X1885000Y227500D01*
G01X1934544Y127957D02*
Y142656D01*
X1931856Y145344D01*
Y151511D01*
X1933715Y153370D01*
Y164789D01*
X1933716Y164790D01*
Y183616D01*
X1937681Y187581D01*
Y193590D01*
X1937624Y193647D01*
Y194953D01*
X1937681Y195010D01*
Y200969D01*
X1933250Y205400D01*
X1926802D01*
X1924200Y208002D01*
Y218432D01*
X1919536Y223096D01*
Y229312D01*
X1919537Y229313D01*
Y230101D01*
X1910788Y238850D01*
X1888526D01*
X1884651Y234975D01*
G01X1927918Y126156D02*
X1927693Y126381D01*
Y132501D01*
X1931019Y135827D01*
Y141555D01*
X1930152Y142422D01*
Y152501D01*
X1931811Y154160D01*
Y164789D01*
X1930531Y166069D01*
X1925056D01*
X1924031Y167094D01*
Y183969D01*
X1932043Y191981D01*
Y194612D01*
X1928370Y198285D01*
Y200783D01*
X1921496Y207657D01*
Y218725D01*
X1917534Y222687D01*
Y229271D01*
X1909802Y237003D01*
X1898452D01*
X1896529Y235080D01*
G01X1929736Y128337D02*
X1929737D01*
Y128355D01*
X1930840D01*
X1931971Y129486D01*
Y141950D01*
X1930904Y143017D01*
Y151906D01*
X1932763Y153765D01*
Y165184D01*
X1930926Y167021D01*
X1925451D01*
X1924983Y167489D01*
Y181842D01*
X1935826Y192685D01*
Y194936D01*
X1934482Y196280D01*
X1931839D01*
X1929405Y198714D01*
Y201212D01*
X1922531Y208086D01*
Y218754D01*
X1918584Y222701D01*
Y229707D01*
X1910393Y237898D01*
X1895092D01*
X1892274Y235080D01*
G01X1873632Y500904D02*
Y501602D01*
X1876430Y504400D01*
X1897900D01*
X1902500Y509000D01*
X1914500D01*
X1920630Y515130D01*
X1924200D01*
X1930570Y521500D01*
X1944206D01*
X1955304Y510402D01*
X1963262D01*
X1964270Y511410D01*
G01X1911000Y556700D02*
Y558870D01*
X1910022Y559848D01*
X1877978D01*
X1869478Y551348D01*
X1863478D01*
X1861086Y548956D01*
X1860456D01*
X1859500Y548000D01*
X1855750D01*
G01X1856040Y588704D02*
Y588720D01*
X1863720D01*
X1866494Y585946D01*
X1891054D01*
X1898900Y578100D01*
Y566913D01*
X1901152Y564661D01*
X1919073D01*
X1919074Y564662D01*
X1920028D01*
X1920029Y564661D01*
X1920161D01*
X1923613Y561209D01*
X1927120D01*
X1928762Y559567D01*
Y544334D01*
X1940796Y532300D01*
X1950444D01*
X1956073Y526671D01*
X1956606D01*
G01X1957212Y479521D02*
Y478909D01*
X1958364Y477757D01*
X1960530D01*
X1961140Y478367D01*
Y502384D01*
X1965850Y507094D01*
Y514250D01*
X1957400Y522700D01*
X1955130D01*
X1948880Y528950D01*
X1939343D01*
X1925500Y542793D01*
Y555000D01*
X1918900Y561600D01*
X1899901D01*
X1886751Y574750D01*
X1874262D01*
X1865868Y583144D01*
X1857671D01*
X1850065Y590750D01*
X1848900D01*
G01X1957063Y474769D02*
Y475159D01*
X1958789Y476885D01*
X1960722D01*
X1961910Y478073D01*
Y502000D01*
X1966650Y506740D01*
Y515350D01*
X1957970Y524030D01*
X1955430D01*
X1949260Y530200D01*
X1939723D01*
X1926500Y543423D01*
Y555628D01*
X1919371Y562757D01*
X1900362D01*
X1887371Y575748D01*
X1874894D01*
X1866746Y583896D01*
X1857983D01*
X1849553Y592326D01*
X1846526D01*
X1845000Y590800D01*
G01X1842764Y528136D02*
X1845536D01*
X1847200Y529800D01*
X1872200D01*
X1879720Y537320D01*
X1906980D01*
X1915750Y528550D01*
X1925841D01*
X1929542Y524849D01*
X1947351D01*
X1956300Y515900D01*
G01X1918489Y212513D02*
X1919749Y211253D01*
Y206451D01*
X1923891Y202309D01*
Y197020D01*
X1923824Y196953D01*
Y195647D01*
X1926576Y192895D01*
Y190276D01*
X1921722Y185422D01*
Y157378D01*
X1925400Y153700D01*
Y143300D01*
X1923200Y141100D01*
Y129418D01*
X1919702Y125920D01*
G01X1910340Y220741D02*
X1912440D01*
X1913045Y220136D01*
Y209183D01*
X1915500Y206728D01*
Y194305D01*
X1915448Y194253D01*
Y192947D01*
X1917900Y190495D01*
Y153700D01*
X1921700Y149900D01*
Y145100D01*
X1917400Y140800D01*
Y114044D01*
X1916656Y113300D01*
X1914500D01*
G01X1918489Y212513D02*
Y216787D01*
X1916100Y219176D01*
Y229147D01*
X1909196Y236051D01*
X1900832D01*
X1899816Y235035D01*
G01X1962800Y149300D02*
X1959661Y152439D01*
Y186100D01*
X1950813Y194948D01*
Y201587D01*
X1943500Y208900D01*
Y209500D01*
G01X1951900Y534900D02*
X1950900Y533900D01*
X1940543D01*
X1929900Y544543D01*
Y559776D01*
X1928216Y561460D01*
Y578280D01*
X1929600Y579664D01*
Y607500D01*
X1931350Y609250D01*
X1934350D01*
G01X1937200Y545100D02*
X1936500D01*
X1933257Y548343D01*
Y560675D01*
X1931224Y562708D01*
Y566224D01*
X1934400Y569400D01*
G01X1937300Y541600D02*
X1937003Y541303D01*
X1936505D01*
X1932505Y545303D01*
Y560363D01*
X1930472Y562396D01*
Y569972D01*
X1934200Y573700D01*
G01X1939700Y540900D02*
Y538852D01*
X1939348Y538500D01*
X1938071D01*
X1931753Y544818D01*
Y560051D01*
X1929720Y562084D01*
Y573220D01*
X1934200Y577700D01*
G01X1940800Y537300D02*
X1940600Y537100D01*
X1938407D01*
X1931000Y544507D01*
Y559740D01*
X1928968Y561772D01*
Y576568D01*
X1935400Y583000D01*
G01Y550800D02*
X1936559Y551959D01*
Y562273D01*
X1934532Y564300D01*
X1932800D01*
G01X1937800Y549700D02*
X1939800Y551700D01*
Y562500D01*
X1936900Y565400D01*
Y568000D01*
G54D28*
G01X117600Y193805D02*
X126445D01*
X130324Y197684D01*
G54D19*
X321061Y65814D03*
X324407D03*
X327754Y73757D03*
X354525Y65822D03*
X351179D03*
X344486D03*
X341140D03*
X347833Y73757D03*
X344486D03*
X337793D03*
X354526D03*
X321061Y529014D03*
X341140Y529022D03*
X337793Y536957D03*
X347833D03*
X351179Y529022D03*
X354526Y536957D03*
X344486Y529022D03*
Y536957D03*
X354525Y529022D03*
X324407Y529014D03*
X401377Y28022D03*
X411416D03*
X404723Y65822D03*
X414763D03*
Y73757D03*
X404723Y529022D03*
X414763Y536957D03*
X428149Y28022D03*
X434842Y28268D03*
X444880Y65822D03*
X438189D03*
X421456Y35957D03*
X444882Y536957D03*
X970669Y65814D03*
Y529014D03*
X990748Y65822D03*
X994094D03*
X1000787D03*
X1004133D03*
X974015Y65814D03*
X987401Y73757D03*
X994094D03*
X997441D03*
X1004134D03*
X977362D03*
X974015Y529014D03*
X990748Y529022D03*
X987401Y536957D03*
X994094D03*
X997441D03*
X1000787Y529022D03*
X1004134Y536957D03*
X994094Y529022D03*
X1004133D03*
X1064371Y65822D03*
X1054331D03*
X1064371Y73757D03*
X1087797Y65822D03*
X1094488D03*
X1064371Y536957D03*
X1054331Y529022D03*
X1094490Y536957D03*
X1461400Y264700D03*
X1442303Y270454D03*
X1445454Y273603D03*
X1454902Y311397D03*
X1463610Y321329D03*
X1445454Y301948D03*
X1464351D03*
X1442304Y311397D03*
X1454902Y298798D03*
X1448603D03*
X1445454D03*
X1448603Y314546D03*
X1461202Y305098D03*
X1440910Y316693D03*
X1454902Y314546D03*
X1451753Y289351D03*
X1470649Y273603D03*
X1480098Y270454D03*
X1473798Y276753D03*
X1480098Y273603D03*
X1476948Y279902D03*
X1486574Y267127D03*
X1496030Y267665D03*
X1470649Y301948D03*
X1486397Y298798D03*
X1476948D03*
X1473798Y308247D03*
X1489546D03*
X1486397D03*
X1483247Y298798D03*
X1476948Y295649D03*
Y308247D03*
X1473798Y314546D03*
X1483247D03*
Y311397D03*
X1495300Y297300D03*
X1478524Y318900D03*
X1480098Y311397D03*
X1483247Y301948D03*
X1486397Y286202D03*
X1480098Y283052D03*
X1486397D03*
X1651532Y137534D03*
X1616890Y112341D03*
X1632615Y109215D03*
X1613741Y146987D03*
X1632639Y118640D03*
X1626300Y112300D03*
X1626339Y118651D03*
X1613741Y156436D03*
Y150137D03*
X1610591Y146987D03*
X1613690Y124990D03*
X1613741Y140688D03*
X1610591Y134389D03*
X1607441Y153286D03*
Y134389D03*
X1616890Y118641D03*
X1613741Y109191D03*
Y106042D03*
X1607441Y156436D03*
X1610591Y153286D03*
X1604169Y156407D03*
X1600148Y151711D03*
X1648320Y172690D03*
X1591950Y158250D03*
X1600490Y158010D03*
X1596427Y157975D03*
X1645237Y165884D03*
X1645151Y162649D03*
X1645237Y159585D03*
X1648386Y165885D03*
X1629489Y159585D03*
Y162735D03*
X1600490Y167459D03*
X1607441Y162735D03*
X1613741D03*
X1616890Y159585D03*
X1623189D03*
X1623250Y162611D03*
X1610591Y165885D03*
X1667348Y156500D03*
X1654685Y112341D03*
X1653111Y102240D03*
X1654686Y156436D03*
X1660985Y115491D03*
Y112341D03*
X1664134Y156436D03*
X1664135Y112341D03*
X1654638Y159685D03*
X1660985Y165885D03*
X1665063Y172608D03*
X1660985Y159585D03*
X1714114Y148950D03*
X1745500Y104500D03*
G54D38*
G01X146299Y-42355D02*
X443146D01*
G02Y-45915I0J-1780D01*
G01X145585D01*
X144200Y-47300D01*
X105550D01*
X100500Y-42250D01*
G01X284050Y569550D02*
X285755Y567845D01*
Y565939D01*
X285016Y565200D01*
X283736D01*
X283096Y564560D01*
Y563140D01*
X283646Y562590D01*
X284226D01*
X284836Y561980D01*
Y560590D01*
X284226Y559980D01*
X283616D01*
X283096Y559460D01*
Y558090D01*
X283686Y557500D01*
X284636D01*
X285736Y556400D01*
Y554812D01*
X284024Y553100D01*
G01X289124Y571949D02*
X287419Y570244D01*
Y565300D01*
X286589Y564470D01*
Y557930D01*
X287419Y557100D01*
Y552131D01*
X288836Y550714D01*
X289124D01*
G01X284024Y572199D02*
X282036Y570211D01*
Y552200D01*
X283736Y550500D01*
X284024D01*
G01X289124Y569340D02*
X290936Y567528D01*
Y565800D01*
X289936Y564800D01*
X288420D01*
X287649Y564029D01*
Y563138D01*
X288189Y562598D01*
X288426D01*
X289136Y561888D01*
Y560800D01*
X288436Y560100D01*
X288101D01*
X287649Y559648D01*
Y558371D01*
X288320Y557700D01*
X289836D01*
X290836Y556700D01*
Y555026D01*
X289124Y553314D01*
G01X280203Y572500D02*
X279037D01*
X275852Y569315D01*
Y557662D01*
X277557Y555957D01*
G01Y566699D02*
X278537D01*
X279136Y566100D01*
Y564900D01*
X278192Y563956D01*
Y562744D01*
X279036Y561900D01*
Y560200D01*
X278192Y559356D01*
Y557936D01*
X279336Y556792D01*
Y555199D01*
X278429Y554292D01*
Y552600D01*
X280115Y550914D01*
X280203D01*
G01X270864Y555957D02*
X269159Y557662D01*
Y567635D01*
X269781Y568257D01*
Y569445D01*
X272836Y572500D01*
X273824D01*
G01X270864Y566699D02*
X271936D01*
X272536Y566099D01*
Y565201D01*
X271499Y564164D01*
Y562936D01*
X272436Y561999D01*
Y560601D01*
X271499Y559664D01*
Y558336D01*
X272636Y557199D01*
Y555300D01*
X272136Y554800D01*
Y552600D01*
X273822Y550914D01*
X273910D01*
G01X294289Y555957D02*
X292584Y557662D01*
Y567849D01*
X297635Y572900D01*
G01X321061Y92757D02*
Y90169D01*
X318992Y88100D01*
Y86598D01*
X319692Y85898D01*
Y76385D01*
X319328Y76021D01*
Y67547D01*
X321061Y65814D01*
G01X327754Y87392D02*
X326892Y86530D01*
Y74619D01*
X327754Y73757D01*
G01X324407Y89964D02*
Y87615D01*
X322092Y85300D01*
Y82347D01*
X322702Y81737D01*
X323767D01*
X324267Y81237D01*
Y79627D01*
X323767Y79127D01*
X322702D01*
X322092Y78517D01*
Y76219D01*
X322795Y75516D01*
Y72832D01*
X323983Y71644D01*
X325743D01*
X326423Y70964D01*
Y69191D01*
X324407Y67175D01*
Y65814D01*
G01X354415Y92757D02*
Y90323D01*
X352557Y88465D01*
Y86035D01*
X353092Y85500D01*
Y75701D01*
X352921Y75530D01*
Y72272D01*
X354526Y70667D01*
Y68492D01*
X354525Y68491D01*
Y65822D01*
G01X354415Y87392D02*
X354427D01*
X354927Y86892D01*
Y74158D01*
X354526Y73757D01*
G01X351179Y89964D02*
X349792Y88577D01*
Y86000D01*
X349334Y85542D01*
Y84023D01*
X351092Y82265D01*
Y76530D01*
X349453Y74891D01*
Y72984D01*
X351179Y71258D01*
Y70453D01*
X350569Y69843D01*
X349066D01*
X348456Y69233D01*
Y67843D01*
X349066Y67233D01*
X350569D01*
X351179Y66623D01*
Y65822D01*
G01X347833Y87392D02*
X347681Y87240D01*
Y80877D01*
X348281Y80277D01*
X348844D01*
X349454Y79667D01*
Y78567D01*
X348954Y78067D01*
X348443D01*
X347833Y77457D01*
Y73757D01*
G01X344486D02*
X345676D01*
X346193Y74274D01*
Y75401D01*
X345677Y75917D01*
X344226D01*
X343616Y76527D01*
Y77517D01*
X344226Y78127D01*
X345617D01*
X346177Y78687D01*
Y79850D01*
X345576Y80451D01*
X344225D01*
X343631Y81045D01*
Y81955D01*
X344257Y82581D01*
X345529D01*
X346029Y83081D01*
Y84189D01*
X345504Y84714D01*
X344486D01*
G01Y89964D02*
X341963Y83875D01*
Y76284D01*
X342851Y74142D01*
Y73002D01*
X344087Y66785D01*
X344486Y65822D01*
G01X337793Y73757D02*
X335850Y75700D01*
X331953D01*
X331402Y76251D01*
Y78007D01*
X331995Y78600D01*
X336208D01*
X336927Y79319D01*
Y80819D01*
X336246Y81500D01*
X333733D01*
X333064Y82169D01*
Y83801D01*
X333862Y84599D01*
X337793D01*
G01X341140Y92757D02*
X340270Y89908D01*
X339268Y88144D01*
Y86224D01*
X339792Y85700D01*
Y77550D01*
X339404Y76241D01*
Y70014D01*
X341140Y65822D01*
G01X321061Y518157D02*
Y529014D01*
G01X324407Y515364D02*
Y529014D01*
G01X354526Y518157D02*
X353944Y518739D01*
Y521191D01*
X354665Y521912D01*
Y525634D01*
X354140Y526159D01*
Y528637D01*
X354525Y529022D01*
G01X354526Y536957D02*
X354525Y536956D01*
Y532199D01*
X356158Y530566D01*
Y527866D01*
X357154Y526870D01*
Y515420D01*
X354526Y512792D01*
X354307D01*
G01X351179Y515364D02*
X352220Y516405D01*
Y527981D01*
X351179Y529022D01*
G01X347833Y512792D02*
X349292Y514251D01*
Y516200D01*
X350526Y517434D01*
Y527323D01*
X349542Y528307D01*
Y532750D01*
X347833Y534459D01*
Y536957D01*
G01X344486D02*
Y532194D01*
X342799Y530507D01*
Y527657D01*
X341692Y526550D01*
Y521824D01*
X342874Y520642D01*
Y516882D01*
X342592Y516600D01*
Y514686D01*
X344486Y510114D01*
G01Y529022D02*
Y527387D01*
X344992Y526881D01*
X348183D01*
X348808Y526256D01*
Y525266D01*
X348213Y524671D01*
X343985D01*
X343330Y524016D01*
Y523026D01*
X343895Y522461D01*
X348259D01*
X348869Y521851D01*
Y520861D01*
X348259Y520251D01*
X345096D01*
X344486Y519641D01*
Y518667D01*
X345719Y517434D01*
Y516597D01*
X344486Y515364D01*
G01X337793Y509999D02*
Y512301D01*
X332625Y517469D01*
Y524837D01*
X336055Y528267D01*
Y535219D01*
X337793Y536957D01*
G01X341140Y518157D02*
Y519396D01*
X340505Y520031D01*
X339034D01*
X338458Y519455D01*
Y518256D01*
X337839Y517637D01*
X336849D01*
X336248Y518238D01*
Y519455D01*
X335672Y520031D01*
X334924D01*
X334424Y520531D01*
Y521510D01*
X335155Y522241D01*
X339199D01*
X339809Y522851D01*
Y523841D01*
X339199Y524451D01*
X336661D01*
X336104Y525008D01*
Y525998D01*
X336767Y526661D01*
X338779D01*
X341140Y529022D01*
G01X304328Y572900D02*
X299277Y567849D01*
Y557662D01*
X300982Y555957D01*
G01X304328Y550914D02*
X304240D01*
X302554Y552600D01*
Y554292D01*
X302729Y554467D01*
Y557100D01*
X301617Y558212D01*
Y559288D01*
X302629Y560300D01*
Y561500D01*
X301617Y562512D01*
Y563588D01*
X302754Y564725D01*
Y565999D01*
X302054Y566699D01*
X300982D01*
G01X294289D02*
X295361D01*
X296061Y565999D01*
Y564725D01*
X294924Y563588D01*
Y562512D01*
X295936Y561500D01*
Y560300D01*
X294924Y559288D01*
Y558212D01*
X296036Y557100D01*
Y554467D01*
X295861Y554292D01*
Y552600D01*
X297547Y550914D01*
X297635D01*
G01X404722Y89964D02*
X403705Y88947D01*
Y86513D01*
X402661Y85469D01*
Y81547D01*
X403109Y81099D01*
Y67436D01*
X404723Y65822D01*
G01X401375Y103116D02*
X403891Y100600D01*
X404292D01*
X416692Y88200D01*
Y86000D01*
X416092Y85400D01*
Y83300D01*
X416379Y83013D01*
Y72487D01*
X414761Y70869D01*
Y65824D01*
X414763Y65822D01*
G01X398029Y89964D02*
Y87482D01*
X399765Y85746D01*
Y67543D01*
X398029Y65807D01*
G01X414761Y87392D02*
X414016Y86647D01*
Y83477D01*
X413264Y82725D01*
X410152D01*
X409470Y82043D01*
Y81053D01*
X410008Y80515D01*
X413648D01*
X414258Y79905D01*
Y78915D01*
X413648Y78305D01*
X409994D01*
X409384Y77695D01*
Y76705D01*
X409994Y76095D01*
X414068D01*
X414763Y75400D01*
Y73757D01*
G01X408068Y92757D02*
X406310Y88513D01*
Y86282D01*
X406546Y85712D01*
Y75803D01*
X406341Y75338D01*
Y69443D01*
X407690Y66186D01*
X408069Y65807D01*
G01X414819Y103116D02*
X416835Y101100D01*
X416992D01*
X430292Y87800D01*
Y86300D01*
X429292Y85300D01*
Y83400D01*
X430192Y82500D01*
Y76163D01*
X429777Y75748D01*
Y69915D01*
X431494Y68198D01*
Y65807D01*
G01X408126Y103116D02*
X410592Y100650D01*
X410742D01*
X423292Y88100D01*
Y86300D01*
X422992Y86000D01*
Y82750D01*
X423792Y81950D01*
X426692D01*
X427492Y81150D01*
Y79550D01*
X426692Y78750D01*
X423792D01*
X423078Y78036D01*
Y71478D01*
X424801Y69755D01*
Y65807D01*
G01X404722Y515364D02*
Y529021D01*
X404723Y529022D01*
G01X398029Y515364D02*
Y529007D01*
G01X414763Y536957D02*
Y534563D01*
X416379Y532947D01*
Y522586D01*
X412892Y519099D01*
Y517202D01*
X414761Y515333D01*
Y512792D01*
G01X408069Y529007D02*
X408068Y529006D01*
Y527369D01*
X408678Y526759D01*
X412935D01*
X413576Y526118D01*
Y525128D01*
X412997Y524549D01*
X409043D01*
X408418Y523924D01*
Y522934D01*
X409013Y522339D01*
X410410D01*
X411020Y521729D01*
Y520739D01*
X410410Y520129D01*
X408678D01*
X408068Y519519D01*
Y518157D01*
G01X394682Y512792D02*
Y515342D01*
X396307Y516967D01*
Y529688D01*
X396683Y530064D01*
Y532558D01*
X394594Y534647D01*
Y537057D01*
X394595Y537058D01*
G01X427696Y103100D02*
X429396Y101400D01*
X430192D01*
X443392Y88200D01*
Y86300D01*
X442992Y85900D01*
Y76400D01*
X443264Y76128D01*
Y67438D01*
X444880Y65822D01*
G01X421512Y103116D02*
X423528Y101100D01*
X423692D01*
X436992Y87800D01*
Y86300D01*
X436192Y85500D01*
Y81822D01*
X436992Y81022D01*
X439149D01*
X439916Y80255D01*
Y78555D01*
X439083Y77722D01*
X436992D01*
X436192Y76922D01*
Y75500D01*
X436500Y75192D01*
Y72608D01*
X435955Y72063D01*
Y70337D01*
X438187Y68105D01*
Y65824D01*
X438189Y65822D01*
G01X435192Y499400D02*
Y503600D01*
X443492Y511900D01*
Y513600D01*
X443092Y514000D01*
Y516500D01*
X443992Y517400D01*
Y526900D01*
X443265Y527627D01*
Y530173D01*
X444880Y531788D01*
Y536955D01*
X444882Y536957D01*
G01X777601Y-43720D02*
X583560D01*
G03Y-46380I0J-1330D01*
G01X777156D01*
G02Y-51160I0J-2390D01*
G01X576040D01*
X572711Y-47831D01*
X531716D01*
X527246Y-52301D01*
G01X777601Y-42660D02*
X583560D01*
G03Y-47440I0J-2390D01*
G01X777156D01*
G02Y-50100I0J-1330D01*
G01X576480D01*
X573151Y-46771D01*
X531716D01*
X527246Y-42301D01*
G01X497723Y572500D02*
X496557D01*
X493372Y569315D01*
Y557662D01*
X495077Y555957D01*
G01Y566699D02*
X496057D01*
X496656Y566100D01*
Y564900D01*
X495712Y563956D01*
Y562744D01*
X496556Y561900D01*
Y560200D01*
X495712Y559356D01*
Y557936D01*
X496856Y556792D01*
Y555199D01*
X495949Y554292D01*
Y552600D01*
X497635Y550914D01*
X497723D01*
G01X518502Y555957D02*
X516797Y557662D01*
Y567849D01*
X521848Y572900D01*
G01X518502Y566699D02*
X519574D01*
X520274Y565999D01*
Y564725D01*
X519137Y563588D01*
Y562512D01*
X520149Y561500D01*
Y560300D01*
X519137Y559288D01*
Y558212D01*
X520249Y557100D01*
Y554467D01*
X520074Y554292D01*
Y552600D01*
X521760Y550914D01*
X521848D01*
G01X488384Y555957D02*
X486679Y557662D01*
Y567635D01*
X487301Y568257D01*
Y569445D01*
X490356Y572500D01*
X491344D01*
G01X488384Y566699D02*
X489456D01*
X490056Y566099D01*
Y565201D01*
X489019Y564164D01*
Y562936D01*
X489956Y561999D01*
Y560601D01*
X489019Y559664D01*
Y558336D01*
X490156Y557199D01*
Y555300D01*
X489656Y554800D01*
Y552600D01*
X491342Y550914D01*
X491430D01*
G01X511809Y555957D02*
X510104Y557662D01*
Y567849D01*
X515155Y572900D01*
G01X511809Y566699D02*
X512881D01*
X513581Y565999D01*
Y564725D01*
X512444Y563588D01*
Y562512D01*
X513456Y561500D01*
Y560300D01*
X512444Y559288D01*
Y558212D01*
X513556Y557100D01*
Y554467D01*
X513381Y554292D01*
Y552600D01*
X515067Y550914D01*
X515155D01*
G01X534534Y572500D02*
X533368D01*
X530183Y569315D01*
Y557662D01*
X531888Y555957D01*
G01Y566699D02*
X532868D01*
X533467Y566100D01*
Y564900D01*
X532523Y563956D01*
Y562744D01*
X533367Y561900D01*
Y560200D01*
X532523Y559356D01*
Y557936D01*
X533667Y556792D01*
Y555199D01*
X532760Y554292D01*
Y552600D01*
X534446Y550914D01*
X534534D01*
G01X525195Y555957D02*
X523490Y557662D01*
Y567635D01*
X524112Y568257D01*
Y569445D01*
X527167Y572500D01*
X528155D01*
G01X525195Y566699D02*
X526267D01*
X526867Y566099D01*
Y565201D01*
X525830Y564164D01*
Y562936D01*
X526767Y561999D01*
Y560601D01*
X525830Y559664D01*
Y558336D01*
X526967Y557199D01*
Y555300D01*
X526467Y554800D01*
Y552600D01*
X528153Y550914D01*
X528241D01*
G01X501570Y569550D02*
Y569549D01*
X503275Y567844D01*
Y565939D01*
X502536Y565200D01*
X501256D01*
X500616Y564560D01*
Y563140D01*
X501166Y562590D01*
X501746D01*
X502356Y561980D01*
Y560590D01*
X501746Y559980D01*
X501136D01*
X500616Y559460D01*
Y558090D01*
X501206Y557500D01*
X502156D01*
X503256Y556400D01*
Y554812D01*
X501544Y553100D01*
G01X538381Y569550D02*
X540086Y567845D01*
Y565939D01*
X539347Y565200D01*
X538067D01*
X537427Y564560D01*
Y563140D01*
X537977Y562590D01*
X538557D01*
X539167Y561980D01*
Y560590D01*
X538557Y559980D01*
X537947D01*
X537427Y559460D01*
Y558090D01*
X538017Y557500D01*
X538967D01*
X540067Y556400D01*
Y554812D01*
X538355Y553100D01*
G01X506644Y550714D02*
X506489D01*
X504938Y552265D01*
Y557101D01*
X504109Y557930D01*
Y564470D01*
X504938Y565299D01*
Y570436D01*
X506451Y571949D01*
X506644D01*
G01X501544Y572199D02*
X501543D01*
X499556Y570212D01*
Y552200D01*
X501256Y550500D01*
X501544D01*
G01X538355Y572199D02*
X536367Y570211D01*
Y552200D01*
X538067Y550500D01*
X538355D01*
G01X506644Y553314D02*
Y553315D01*
X508356Y555027D01*
Y556700D01*
X507356Y557700D01*
X505840D01*
X505169Y558371D01*
Y559648D01*
X505621Y560100D01*
X505956D01*
X506656Y560800D01*
Y561888D01*
X505946Y562598D01*
X505709D01*
X505169Y563138D01*
Y564029D01*
X505940Y564800D01*
X507456D01*
X508456Y565800D01*
Y567528D01*
X506644Y569340D01*
G01X555313Y555957D02*
X553608Y557662D01*
Y567849D01*
X558659Y572900D01*
G01X555313Y566699D02*
X556385D01*
X557085Y565999D01*
Y564725D01*
X555948Y563588D01*
Y562512D01*
X556960Y561500D01*
Y560300D01*
X555948Y559288D01*
Y558212D01*
X557060Y557100D01*
Y554467D01*
X556885Y554292D01*
Y552600D01*
X558571Y550914D01*
X558659D01*
G01X548620Y555957D02*
X546915Y557662D01*
Y567849D01*
X551966Y572900D01*
G01X548620Y566699D02*
X549692D01*
X550392Y565999D01*
Y564725D01*
X549255Y563588D01*
Y562512D01*
X550267Y561500D01*
Y560300D01*
X549255Y559288D01*
Y558212D01*
X550367Y557100D01*
Y554467D01*
X550192Y554292D01*
Y552600D01*
X551878Y550914D01*
X551966D01*
G01X543455Y550714D02*
X543167D01*
X541749Y552132D01*
Y557101D01*
X540920Y557930D01*
Y564470D01*
X541749Y565299D01*
Y570243D01*
X543455Y571949D01*
G01Y569340D02*
X545267Y567528D01*
Y565800D01*
X544267Y564800D01*
X542751D01*
X541980Y564029D01*
Y563138D01*
X542520Y562598D01*
X542757D01*
X543467Y561888D01*
Y560800D01*
X542767Y560100D01*
X542432D01*
X541980Y559648D01*
Y558371D01*
X542651Y557700D01*
X544167D01*
X545167Y556700D01*
Y555026D01*
X543455Y553314D01*
G01X970669Y92757D02*
Y90169D01*
X968600Y88100D01*
Y86598D01*
X969300Y85898D01*
Y76385D01*
X968936Y76021D01*
Y67547D01*
X970669Y65814D01*
G01X974015Y89964D02*
Y87615D01*
X971700Y85300D01*
Y82347D01*
X972310Y81737D01*
X973375D01*
X973875Y81237D01*
Y79627D01*
X973375Y79127D01*
X972310D01*
X971700Y78517D01*
Y76219D01*
X972403Y75516D01*
Y72832D01*
X973591Y71644D01*
X975351D01*
X976031Y70964D01*
Y69191D01*
X974015Y67175D01*
Y65814D01*
G01X970669Y518157D02*
Y529014D01*
G01X933658Y569550D02*
X935363Y567845D01*
Y565939D01*
X934624Y565200D01*
X933344D01*
X932704Y564560D01*
Y563140D01*
X933254Y562590D01*
X933834D01*
X934444Y561980D01*
Y560590D01*
X933834Y559980D01*
X933224D01*
X932704Y559460D01*
Y558090D01*
X933294Y557500D01*
X934244D01*
X935344Y556400D01*
Y554812D01*
X933632Y553100D01*
G01X938732Y571949D02*
X937027Y570244D01*
Y565300D01*
X936197Y564470D01*
Y557930D01*
X937027Y557100D01*
Y552131D01*
X938444Y550714D01*
X938732D01*
G01X933632Y572199D02*
X931644Y570211D01*
Y552200D01*
X933344Y550500D01*
X933632D01*
G01X938732Y569340D02*
X940544Y567528D01*
Y565800D01*
X939544Y564800D01*
X938028D01*
X937257Y564029D01*
Y563138D01*
X937797Y562598D01*
X938034D01*
X938744Y561888D01*
Y560800D01*
X938044Y560100D01*
X937709D01*
X937257Y559648D01*
Y558371D01*
X937928Y557700D01*
X939444D01*
X940444Y556700D01*
Y555026D01*
X938732Y553314D01*
G01X929811Y572500D02*
X928645D01*
X925460Y569315D01*
Y557662D01*
X927165Y555957D01*
G01Y566699D02*
X928145D01*
X928744Y566100D01*
Y564900D01*
X927800Y563956D01*
Y562744D01*
X928644Y561900D01*
Y560200D01*
X927800Y559356D01*
Y557936D01*
X928944Y556792D01*
Y555199D01*
X928037Y554292D01*
Y552600D01*
X929723Y550914D01*
X929811D01*
G01X950590Y555957D02*
X948885Y557662D01*
Y567849D01*
X953936Y572900D01*
G01X950590Y566699D02*
X951662D01*
X952362Y565999D01*
Y564725D01*
X951225Y563588D01*
Y562512D01*
X952237Y561500D01*
Y560300D01*
X951225Y559288D01*
Y558212D01*
X952337Y557100D01*
Y554467D01*
X952162Y554292D01*
Y552600D01*
X953848Y550914D01*
X953936D01*
G01X920472Y555957D02*
X918767Y557662D01*
Y567635D01*
X919389Y568257D01*
Y569445D01*
X922444Y572500D01*
X923432D01*
G01X920472Y566699D02*
X921544D01*
X922144Y566099D01*
Y565201D01*
X921107Y564164D01*
Y562936D01*
X922044Y561999D01*
Y560601D01*
X921107Y559664D01*
Y558336D01*
X922244Y557199D01*
Y555300D01*
X921744Y554800D01*
Y552600D01*
X923430Y550914D01*
X923518D01*
G01X943897Y555957D02*
X942192Y557662D01*
Y567849D01*
X947243Y572900D01*
G01X943897Y566699D02*
X944969D01*
X945669Y565999D01*
Y564725D01*
X944532Y563588D01*
Y562512D01*
X945544Y561500D01*
Y560300D01*
X944532Y559288D01*
Y558212D01*
X945644Y557100D01*
Y554467D01*
X945469Y554292D01*
Y552600D01*
X947155Y550914D01*
X947243D01*
G01X977362Y87392D02*
X976500Y86530D01*
Y74619D01*
X977362Y73757D01*
G01X1004023Y92757D02*
Y90323D01*
X1002165Y88465D01*
Y86035D01*
X1002700Y85500D01*
Y75701D01*
X1002529Y75530D01*
Y72272D01*
X1004134Y70667D01*
Y68492D01*
X1004133Y68491D01*
Y65822D01*
G01X1004023Y87392D02*
X1004035D01*
X1004535Y86892D01*
Y74158D01*
X1004134Y73757D01*
G01X1000787Y89964D02*
X999400Y88577D01*
Y86000D01*
X998942Y85542D01*
Y84023D01*
X1000700Y82265D01*
Y76530D01*
X999061Y74891D01*
Y72984D01*
X1000787Y71258D01*
Y70453D01*
X1000177Y69843D01*
X998674D01*
X998064Y69233D01*
Y67843D01*
X998674Y67233D01*
X1000177D01*
X1000787Y66623D01*
Y65822D01*
G01X997441Y87392D02*
X997289Y87240D01*
Y80877D01*
X997889Y80277D01*
X998452D01*
X999062Y79667D01*
Y78567D01*
X998562Y78067D01*
X998051D01*
X997441Y77457D01*
Y73757D01*
G01X994094D02*
X995284D01*
X995801Y74274D01*
Y75401D01*
X995285Y75917D01*
X993834D01*
X993224Y76527D01*
Y77517D01*
X993834Y78127D01*
X995225D01*
X995785Y78687D01*
Y79850D01*
X995184Y80451D01*
X993833D01*
X993239Y81045D01*
Y81955D01*
X993865Y82581D01*
X995137D01*
X995637Y83081D01*
Y84189D01*
X995112Y84714D01*
X994094D01*
G01Y89964D02*
X991571Y83875D01*
Y76284D01*
X992459Y74142D01*
Y73002D01*
X993695Y66785D01*
X994094Y65822D01*
G01X987401Y73757D02*
X985458Y75700D01*
X981561D01*
X981010Y76251D01*
Y78007D01*
X981603Y78600D01*
X985816D01*
X986535Y79319D01*
Y80819D01*
X985854Y81500D01*
X983341D01*
X982672Y82169D01*
Y83801D01*
X983470Y84599D01*
X987401D01*
G01X990748Y92757D02*
X989878Y89908D01*
X988876Y88144D01*
Y86224D01*
X989400Y85700D01*
Y77550D01*
X989012Y76241D01*
Y70014D01*
X990748Y65822D01*
G01X974015Y515364D02*
Y529014D01*
G01X1004134Y518157D02*
X1003552Y518739D01*
Y521191D01*
X1004273Y521912D01*
Y525634D01*
X1003748Y526159D01*
Y528637D01*
X1004133Y529022D01*
G01X1004134Y536957D02*
X1004133Y536956D01*
Y532199D01*
X1005766Y530566D01*
Y527866D01*
X1006762Y526870D01*
Y515420D01*
X1004134Y512792D01*
X1003915D01*
G01X1000787Y515364D02*
X1001828Y516405D01*
Y527981D01*
X1000787Y529022D01*
G01X997441Y512792D02*
X998900Y514251D01*
Y516200D01*
X1000134Y517434D01*
Y527323D01*
X999150Y528307D01*
Y532750D01*
X997441Y534459D01*
Y536957D01*
G01X994094D02*
Y532194D01*
X992407Y530507D01*
Y527657D01*
X991300Y526550D01*
Y521824D01*
X992482Y520642D01*
Y516882D01*
X992200Y516600D01*
Y514686D01*
X994094Y510114D01*
G01Y529022D02*
Y527387D01*
X994600Y526881D01*
X997791D01*
X998416Y526256D01*
Y525266D01*
X997821Y524671D01*
X993593D01*
X992938Y524016D01*
Y523026D01*
X993503Y522461D01*
X997867D01*
X998477Y521851D01*
Y520861D01*
X997867Y520251D01*
X994704D01*
X994094Y519641D01*
Y518667D01*
X995327Y517434D01*
Y516597D01*
X994094Y515364D01*
G01X987401Y509999D02*
Y512301D01*
X982233Y517469D01*
Y524837D01*
X985663Y528267D01*
Y535219D01*
X987401Y536957D01*
G01X990748Y518157D02*
Y519396D01*
X990113Y520031D01*
X988642D01*
X988066Y519455D01*
Y518256D01*
X987447Y517637D01*
X986457D01*
X985856Y518238D01*
Y519455D01*
X985280Y520031D01*
X984532D01*
X984032Y520531D01*
Y521510D01*
X984763Y522241D01*
X988807D01*
X989417Y522851D01*
Y523841D01*
X988807Y524451D01*
X986269D01*
X985712Y525008D01*
Y525998D01*
X986375Y526661D01*
X988387D01*
X990748Y529022D01*
G01X1054330Y89964D02*
X1053313Y88947D01*
Y86513D01*
X1052269Y85469D01*
Y81547D01*
X1052717Y81099D01*
Y67436D01*
X1054331Y65822D01*
G01X1050983Y103116D02*
X1053499Y100600D01*
X1053900D01*
X1066300Y88200D01*
Y86000D01*
X1065700Y85400D01*
Y83300D01*
X1065987Y83013D01*
Y72487D01*
X1064369Y70869D01*
Y65824D01*
X1064371Y65822D01*
G01X1064427Y103116D02*
X1066443Y101100D01*
X1066600D01*
X1079900Y87800D01*
Y86300D01*
X1078900Y85300D01*
Y83400D01*
X1079800Y82500D01*
Y76163D01*
X1079385Y75748D01*
Y69915D01*
X1081102Y68198D01*
Y65807D01*
G01X1077304Y103100D02*
X1079004Y101400D01*
X1079800D01*
X1093000Y88200D01*
Y86300D01*
X1092600Y85900D01*
Y76400D01*
X1092872Y76128D01*
Y67438D01*
X1094488Y65822D01*
G01X1047637Y89964D02*
Y87482D01*
X1049373Y85746D01*
Y67543D01*
X1047637Y65807D01*
G01X1064369Y87392D02*
X1063624Y86647D01*
Y83477D01*
X1062872Y82725D01*
X1059760D01*
X1059078Y82043D01*
Y81053D01*
X1059616Y80515D01*
X1063256D01*
X1063866Y79905D01*
Y78915D01*
X1063256Y78305D01*
X1059602D01*
X1058992Y77695D01*
Y76705D01*
X1059602Y76095D01*
X1063676D01*
X1064371Y75400D01*
Y73757D01*
G01X1057676Y92757D02*
X1055918Y88513D01*
Y86282D01*
X1056154Y85712D01*
Y75803D01*
X1055949Y75338D01*
Y69443D01*
X1057298Y66186D01*
X1057677Y65807D01*
G01X1057734Y103116D02*
X1060200Y100650D01*
X1060350D01*
X1072900Y88100D01*
Y86300D01*
X1072600Y86000D01*
Y82750D01*
X1073400Y81950D01*
X1076300D01*
X1077100Y81150D01*
Y79550D01*
X1076300Y78750D01*
X1073400D01*
X1072686Y78036D01*
Y71478D01*
X1074409Y69755D01*
Y65807D01*
G01X1071120Y103116D02*
X1073136Y101100D01*
X1073300D01*
X1086600Y87800D01*
Y86300D01*
X1085800Y85500D01*
Y81822D01*
X1086600Y81022D01*
X1088757D01*
X1089524Y80255D01*
Y78555D01*
X1088691Y77722D01*
X1086600D01*
X1085800Y76922D01*
Y75500D01*
X1086108Y75192D01*
Y72608D01*
X1085563Y72063D01*
Y70337D01*
X1087795Y68105D01*
Y65824D01*
X1087797Y65822D01*
G01X1054330Y515364D02*
Y529021D01*
X1054331Y529022D01*
G01X1084800Y499400D02*
Y503600D01*
X1093100Y511900D01*
Y513600D01*
X1092700Y514000D01*
Y516500D01*
X1093600Y517400D01*
Y526900D01*
X1092873Y527627D01*
Y530173D01*
X1094488Y531788D01*
Y536955D01*
X1094490Y536957D01*
G01X1047637Y515364D02*
Y529007D01*
G01X1064371Y536957D02*
Y534563D01*
X1065987Y532947D01*
Y522586D01*
X1062500Y519099D01*
Y517202D01*
X1064369Y515333D01*
Y512792D01*
G01X1057677Y529007D02*
X1057676Y529006D01*
Y527369D01*
X1058286Y526759D01*
X1062543D01*
X1063184Y526118D01*
Y525128D01*
X1062605Y524549D01*
X1058651D01*
X1058026Y523924D01*
Y522934D01*
X1058621Y522339D01*
X1060018D01*
X1060628Y521729D01*
Y520739D01*
X1060018Y520129D01*
X1058286D01*
X1057676Y519519D01*
Y518157D01*
G01X1044290Y512792D02*
Y515342D01*
X1045915Y516967D01*
Y529688D01*
X1046291Y530064D01*
Y532558D01*
X1044202Y534647D01*
Y537057D01*
X1044203Y537058D01*
G01X1147331Y572500D02*
X1146165D01*
X1142980Y569315D01*
Y557662D01*
X1144685Y555957D01*
G01Y566699D02*
X1145665D01*
X1146264Y566100D01*
Y564900D01*
X1145320Y563956D01*
Y562744D01*
X1146164Y561900D01*
Y560200D01*
X1145320Y559356D01*
Y557936D01*
X1146464Y556792D01*
Y555199D01*
X1145557Y554292D01*
Y552600D01*
X1147243Y550914D01*
X1147331D01*
G01X1137992Y555957D02*
X1136287Y557662D01*
Y567635D01*
X1136909Y568257D01*
Y569445D01*
X1139964Y572500D01*
X1140952D01*
G01X1137992Y566699D02*
X1139064D01*
X1139664Y566099D01*
Y565201D01*
X1138627Y564164D01*
Y562936D01*
X1139564Y561999D01*
Y560601D01*
X1138627Y559664D01*
Y558336D01*
X1139764Y557199D01*
Y555300D01*
X1139264Y554800D01*
Y552600D01*
X1140950Y550914D01*
X1141038D01*
G01X1151178Y569550D02*
Y569549D01*
X1152883Y567844D01*
Y565939D01*
X1152144Y565200D01*
X1150864D01*
X1150224Y564560D01*
Y563140D01*
X1150774Y562590D01*
X1151354D01*
X1151964Y561980D01*
Y560590D01*
X1151354Y559980D01*
X1150744D01*
X1150224Y559460D01*
Y558090D01*
X1150814Y557500D01*
X1151764D01*
X1152864Y556400D01*
Y554812D01*
X1151152Y553100D01*
G01X1156252Y550714D02*
X1156097D01*
X1154546Y552265D01*
Y557101D01*
X1153717Y557930D01*
Y564470D01*
X1154546Y565299D01*
Y570436D01*
X1156059Y571949D01*
X1156252D01*
G01X1151152Y572199D02*
X1151151D01*
X1149164Y570212D01*
Y552200D01*
X1150864Y550500D01*
X1151152D01*
G01X1156252Y553314D02*
Y553315D01*
X1157964Y555027D01*
Y556700D01*
X1156964Y557700D01*
X1155448D01*
X1154777Y558371D01*
Y559648D01*
X1155229Y560100D01*
X1155564D01*
X1156264Y560800D01*
Y561888D01*
X1155554Y562598D01*
X1155317D01*
X1154777Y563138D01*
Y564029D01*
X1155548Y564800D01*
X1157064D01*
X1158064Y565800D01*
Y567528D01*
X1156252Y569340D01*
G01X1168110Y555957D02*
X1166405Y557662D01*
Y567849D01*
X1171456Y572900D01*
G01X1168110Y566699D02*
X1169182D01*
X1169882Y565999D01*
Y564725D01*
X1168745Y563588D01*
Y562512D01*
X1169757Y561500D01*
Y560300D01*
X1168745Y559288D01*
Y558212D01*
X1169857Y557100D01*
Y554467D01*
X1169682Y554292D01*
Y552600D01*
X1171368Y550914D01*
X1171456D01*
G01X1161417Y555957D02*
X1159712Y557662D01*
Y567849D01*
X1164763Y572900D01*
G01X1161417Y566699D02*
X1162489D01*
X1163189Y565999D01*
Y564725D01*
X1162052Y563588D01*
Y562512D01*
X1163064Y561500D01*
Y560300D01*
X1162052Y559288D01*
Y558212D01*
X1163164Y557100D01*
Y554467D01*
X1162989Y554292D01*
Y552600D01*
X1164675Y550914D01*
X1164763D01*
G01X1181496Y555957D02*
X1179791Y557662D01*
Y569315D01*
X1182976Y572500D01*
X1184142D01*
G01X1181496Y566699D02*
X1182476D01*
X1183075Y566100D01*
Y564900D01*
X1182131Y563956D01*
Y562744D01*
X1182975Y561900D01*
Y560200D01*
X1182131Y559356D01*
Y557936D01*
X1183275Y556792D01*
Y555199D01*
X1182368Y554292D01*
Y552600D01*
X1184054Y550914D01*
X1184142D01*
G01X1204921Y555957D02*
X1203216Y557662D01*
Y567849D01*
X1208267Y572900D01*
G01X1204921Y566699D02*
X1205993D01*
X1206693Y565999D01*
Y564725D01*
X1205556Y563588D01*
Y562512D01*
X1206568Y561500D01*
Y560300D01*
X1205556Y559288D01*
Y558212D01*
X1206668Y557100D01*
Y554467D01*
X1206493Y554292D01*
Y552600D01*
X1208179Y550914D01*
X1208267D01*
G01X1174803Y555957D02*
X1173098Y557662D01*
Y567635D01*
X1173720Y568257D01*
Y569445D01*
X1176775Y572500D01*
X1177763D01*
G01X1174803Y566699D02*
X1175875D01*
X1176475Y566099D01*
Y565201D01*
X1175438Y564164D01*
Y562936D01*
X1176375Y561999D01*
Y560601D01*
X1175438Y559664D01*
Y558336D01*
X1176575Y557199D01*
Y555300D01*
X1176075Y554800D01*
Y552600D01*
X1177761Y550914D01*
X1177849D01*
G01X1198228Y555957D02*
X1196523Y557662D01*
Y567849D01*
X1201574Y572900D01*
G01X1198228Y566699D02*
X1199300D01*
X1200000Y565999D01*
Y564725D01*
X1198863Y563588D01*
Y562512D01*
X1199875Y561500D01*
Y560300D01*
X1198863Y559288D01*
Y558212D01*
X1199975Y557100D01*
Y554467D01*
X1199800Y554292D01*
Y552600D01*
X1201486Y550914D01*
X1201574D01*
G01X1187989Y569550D02*
X1189694Y567845D01*
Y565939D01*
X1188955Y565200D01*
X1187675D01*
X1187035Y564560D01*
Y563140D01*
X1187585Y562590D01*
X1188165D01*
X1188775Y561980D01*
Y560590D01*
X1188165Y559980D01*
X1187555D01*
X1187035Y559460D01*
Y558090D01*
X1187625Y557500D01*
X1188575D01*
X1189675Y556400D01*
Y554812D01*
X1187963Y553100D01*
G01X1193063Y550714D02*
X1192775D01*
X1191357Y552132D01*
Y557101D01*
X1190528Y557930D01*
Y564470D01*
X1191357Y565299D01*
Y570243D01*
X1193063Y571949D01*
G01X1187963Y572199D02*
X1185975Y570211D01*
Y552200D01*
X1187675Y550500D01*
X1187963D01*
G01X1193063Y569340D02*
X1194875Y567528D01*
Y565800D01*
X1193875Y564800D01*
X1192359D01*
X1191588Y564029D01*
Y563138D01*
X1192128Y562598D01*
X1192365D01*
X1193075Y561888D01*
Y560800D01*
X1192375Y560100D01*
X1192040D01*
X1191588Y559648D01*
Y558371D01*
X1192259Y557700D01*
X1193775D01*
X1194775Y556700D01*
Y555026D01*
X1193063Y553314D01*
G54D29*
G01X79500Y72500D02*
X80000D01*
X88440Y80940D01*
X101780D01*
X112007Y91167D01*
Y93139D01*
G01X157862Y416012D02*
X151710Y409860D01*
X150650D01*
G01X1324707Y545493D02*
X1325006D01*
X1327044Y543455D01*
X1328868D01*
X1329734Y544321D01*
X1349242D01*
X1358164Y553243D01*
X1369708D01*
X1372822Y550129D01*
X1380441D01*
X1381278Y550966D01*
X1386620D01*
X1389156Y553502D01*
X1401318D01*
X1410143Y544677D01*
X1420418D01*
X1421295Y543800D01*
X1432800D01*
X1438310Y549310D01*
X1440573D01*
X1441252Y548631D01*
G01X1730759Y548162D02*
X1730500Y548421D01*
Y565200D01*
X1739800Y574500D01*
X1743000D01*
G54D39*
G01X1900256Y-14760D02*
X1899006Y-16010D01*
X1889891D01*
X1887930Y-14049D01*
Y-605D01*
X1876772Y10553D01*
X1855216D01*
X1851504Y6841D01*
X1848806D01*
X1839626Y-2339D01*
Y-10222D01*
X1829877Y-19971D01*
X1692666D01*
X1678096Y-5401D01*
X1665463D01*
X1662015Y-8849D01*
X1618452D01*
X1617401Y-9900D01*
X1598499D01*
X1591948Y-3349D01*
X1524047D01*
X1523947Y-3249D01*
X1521253D01*
X1521153Y-3349D01*
X1505706D01*
X1501474Y883D01*
Y12526D01*
X1489711Y24289D01*
X1447846D01*
X1439783Y32352D01*
Y42697D01*
X1428941Y53539D01*
Y74938D01*
X1424934Y78945D01*
Y88395D01*
X1414689Y98640D01*
Y119882D01*
X1405533Y129038D01*
Y130667D01*
X1399200Y137000D01*
X1319930D01*
X1313376Y130446D01*
Y60711D01*
X1305250Y52585D01*
Y48407D01*
X1299044Y42201D01*
X1294470D01*
X1292799Y40530D01*
X1284062D01*
X1278993Y35461D01*
Y27251D01*
X1272801Y21059D01*
X1042378D01*
X1041732Y21705D01*
X1033162D01*
X1018408Y6951D01*
X767735D01*
X760657Y14029D01*
X755784D01*
X748371Y21442D01*
X708994D01*
X705936Y24500D01*
X695446D01*
X688346Y31600D01*
X677824D01*
X671744Y37680D01*
X667351D01*
X665368Y35697D01*
Y34207D01*
X660194Y29033D01*
X644842D01*
X639675Y23866D01*
X634217D01*
X616231Y5880D01*
X385393D01*
X380663Y10610D01*
X374111D01*
X369652Y6151D01*
X120649D01*
X114216Y12584D01*
X104557D01*
X97601Y5628D01*
X67281D01*
X59587Y13322D01*
Y15194D01*
X44251Y30530D01*
Y83549D01*
X41488Y86312D01*
Y92146D01*
X38109Y95525D01*
Y119628D01*
X36243Y121494D01*
X-10920D01*
X-11773Y122347D01*
Y122913D01*
X-9843Y124843D01*
G01X1900256Y-18911D02*
X1899006Y-17661D01*
X1889207D01*
X1886279Y-14733D01*
Y-1289D01*
X1876088Y8902D01*
X1855900D01*
X1852188Y5190D01*
X1849490D01*
X1841277Y-3023D01*
Y-10906D01*
X1830561Y-21622D01*
X1691982D01*
X1677412Y-7052D01*
X1666147D01*
X1662699Y-10500D01*
X1619136D01*
X1618085Y-11551D01*
X1597815D01*
X1591264Y-5000D01*
X1523363D01*
X1523263Y-4900D01*
X1521937D01*
X1521837Y-5000D01*
X1505022D01*
X1499823Y199D01*
Y11842D01*
X1489027Y22638D01*
X1447162D01*
X1438132Y31668D01*
Y42013D01*
X1427290Y52855D01*
Y74254D01*
X1423283Y78261D01*
Y87711D01*
X1413038Y97956D01*
Y119198D01*
X1403882Y128354D01*
Y129983D01*
X1398516Y135349D01*
X1320614D01*
X1315027Y129762D01*
Y60027D01*
X1306901Y51901D01*
Y47723D01*
X1299728Y40550D01*
X1295154D01*
X1293483Y38879D01*
X1284746D01*
X1280644Y34777D01*
Y26567D01*
X1273485Y19408D01*
X1041694D01*
X1041048Y20054D01*
X1033846D01*
X1019092Y5300D01*
X767051D01*
X759973Y12378D01*
X755100D01*
X747687Y19791D01*
X708310D01*
X705252Y22849D01*
X694762D01*
X687662Y29949D01*
X677140D01*
X671060Y36029D01*
X668035D01*
X667019Y35013D01*
Y33523D01*
X660878Y27382D01*
X645526D01*
X640359Y22215D01*
X634901D01*
X616915Y4229D01*
X384709D01*
X379979Y8959D01*
X374795D01*
X370336Y4500D01*
X119965D01*
X113532Y10933D01*
X105241D01*
X98285Y3977D01*
X66597D01*
X57936Y12638D01*
Y14510D01*
X42600Y29846D01*
Y82865D01*
X39837Y85628D01*
Y91462D01*
X36458Y94841D01*
Y118944D01*
X35559Y119843D01*
X-11604D01*
X-13424Y121663D01*
Y122914D01*
X-15353Y124843D01*
X-15354D01*
G01X1868286Y12848D02*
Y14656D01*
X1866609Y16333D01*
X1857017D01*
X1850025Y9341D01*
X1848240D01*
X1838799Y-100D01*
X1833235D01*
X1822457Y-10878D01*
X1687108D01*
X1678632Y-2402D01*
X1664927D01*
X1661484Y-5845D01*
X1618155D01*
X1616749Y-7251D01*
X1598915D01*
X1590364Y1300D01*
X1571536D01*
X1569536Y-700D01*
X1506083D01*
X1503650Y1733D01*
Y2152D01*
X1503649Y2153D01*
Y4847D01*
X1503650Y4848D01*
Y14351D01*
X1491546Y26455D01*
X1448881D01*
X1445057Y30279D01*
Y34688D01*
X1442967Y36778D01*
X1442966D01*
Y36779D01*
X1442000Y37745D01*
Y44015D01*
X1431440Y54575D01*
Y75498D01*
X1427433Y79505D01*
Y89431D01*
X1417188Y99676D01*
Y121188D01*
X1408149Y130227D01*
Y132016D01*
X1400816Y139349D01*
X1318545D01*
X1310668Y131472D01*
Y101068D01*
X1306397Y96797D01*
Y83561D01*
X1302527Y79691D01*
Y68663D01*
X1307967Y63223D01*
Y59132D01*
X1302751Y53916D01*
Y49443D01*
X1298008Y44700D01*
X1293345D01*
X1291112Y42467D01*
X1282254D01*
X1276494Y36707D01*
Y28849D01*
X1271322Y23677D01*
X1034823D01*
X1032200Y26300D01*
Y27245D01*
X1031495Y27950D01*
X1029403D01*
X1020832Y19379D01*
X762944D01*
X756528Y25795D01*
X752283D01*
X750090Y23602D01*
X732283D01*
X725352Y30533D01*
X697599D01*
X693983Y34149D01*
X680947D01*
X675236Y39860D01*
X653350D01*
X651553Y41657D01*
X634141D01*
X628256Y35772D01*
Y34877D01*
X614572Y21193D01*
X391972D01*
X391192Y21973D01*
X384564D01*
X383773Y21182D01*
X377874D01*
X375221Y23835D01*
X111204D01*
X109253Y21884D01*
X56135D01*
X46400Y31619D01*
Y85065D01*
X44084Y87381D01*
Y92821D01*
X40608Y96297D01*
Y120872D01*
X33742Y127738D01*
X5161D01*
X4762Y127339D01*
Y126774D01*
X6693Y124843D01*
G01X1871163Y13186D02*
X1869937Y14412D01*
Y15340D01*
X1867293Y17984D01*
X1856333D01*
X1849341Y10992D01*
X1847556D01*
X1838115Y1551D01*
X1832551D01*
X1821773Y-9227D01*
X1687792D01*
X1679316Y-751D01*
X1664243D01*
X1660800Y-4194D01*
X1617471D01*
X1616065Y-5600D01*
X1599599D01*
X1591048Y2951D01*
X1570852D01*
X1568852Y951D01*
X1506767D01*
X1505301Y2417D01*
Y2836D01*
X1505300Y2837D01*
Y4163D01*
X1505301Y4164D01*
Y15035D01*
X1492230Y28106D01*
X1449565D01*
X1446708Y30963D01*
Y35372D01*
X1443651Y38429D01*
Y44699D01*
X1433091Y55259D01*
Y76182D01*
X1429084Y80189D01*
Y90115D01*
X1418839Y100360D01*
Y121872D01*
X1409800Y130911D01*
Y132700D01*
X1401500Y141000D01*
X1317861D01*
X1309017Y132156D01*
Y101752D01*
X1304746Y97481D01*
Y84245D01*
X1300876Y80375D01*
Y67979D01*
X1306316Y62539D01*
Y59816D01*
X1301100Y54600D01*
Y50127D01*
X1297324Y46351D01*
X1292661D01*
X1290428Y44118D01*
X1281570D01*
X1274843Y37391D01*
Y29533D01*
X1270638Y25328D01*
X1035507D01*
X1033851Y26984D01*
Y27929D01*
X1032179Y29601D01*
X1028719D01*
X1020148Y21030D01*
X763628D01*
X757212Y27446D01*
X751599D01*
X749406Y25253D01*
X732967D01*
X726036Y32184D01*
X698283D01*
X694667Y35800D01*
X681631D01*
X675920Y41511D01*
X654034D01*
X652237Y43308D01*
X633457D01*
X626605Y36456D01*
Y35561D01*
X613888Y22844D01*
X392656D01*
X391876Y23624D01*
X383880D01*
X383089Y22833D01*
X378558D01*
X375905Y25486D01*
X110520D01*
X108569Y23535D01*
X56819D01*
X48051Y32303D01*
Y85749D01*
X45735Y88065D01*
Y93505D01*
X42259Y96981D01*
Y121556D01*
X34426Y129389D01*
X4477D01*
X3111Y128023D01*
Y126772D01*
X1182Y124843D01*
X1181D01*
G01X1574020Y398821D02*
X1580469Y392372D01*
X1581890D01*
X1588030Y386231D01*
X1592263Y381999D01*
Y380174D01*
X1594855Y377582D01*
X1597642D01*
X1598878Y376346D01*
G01X1575188Y399988D02*
X1581153Y394023D01*
X1582574D01*
X1585513Y391084D01*
X1587213D01*
X1588059Y390238D01*
Y388538D01*
X1588797Y387800D01*
X1590400D01*
X1590900Y387300D01*
Y385697D01*
X1593914Y382683D01*
Y380858D01*
X1595539Y379233D01*
X1597767D01*
X1598878Y380344D01*
G01X1575129Y404265D02*
X1579480Y399914D01*
X1587892D01*
X1593722Y394084D01*
Y386410D01*
X1596774Y383358D01*
X1611403D01*
X1616996Y377765D01*
Y358405D01*
X1621977Y353424D01*
Y347937D01*
X1626052Y343862D01*
Y338601D01*
X1627963Y336690D01*
X1632862D01*
X1641190Y328362D01*
Y313543D01*
X1643410Y311323D01*
Y251010D01*
X1645598Y248822D01*
Y239969D01*
X1660803Y224764D01*
X1671595D01*
X1675540Y220819D01*
X1683347D01*
X1690387Y213779D01*
X1713058D01*
X1719166Y219887D01*
X1765291D01*
X1777776Y232372D01*
Y237313D01*
X1778175Y237712D01*
X1779451D01*
G01X1774451D02*
X1775726D01*
X1776125Y237313D01*
Y233056D01*
X1764607Y221538D01*
X1754036D01*
X1752834Y222740D01*
X1751637D01*
X1750435Y221538D01*
X1749018D01*
X1747816Y222740D01*
X1746619D01*
X1745417Y221538D01*
X1744220D01*
X1743018Y222740D01*
X1741821D01*
X1740619Y221538D01*
X1739422D01*
X1738220Y222740D01*
X1737023D01*
X1735821Y221538D01*
X1718482D01*
X1712374Y215430D01*
X1691071D01*
X1684031Y222470D01*
X1676224D01*
X1672279Y226415D01*
X1661487D01*
X1647249Y240653D01*
Y249506D01*
X1645061Y251694D01*
Y312007D01*
X1642841Y314227D01*
Y329046D01*
X1633546Y338341D01*
X1628647D01*
X1627703Y339285D01*
Y344546D01*
X1623628Y348621D01*
Y354108D01*
X1618647Y359089D01*
Y378449D01*
X1612087Y385009D01*
X1597458D01*
X1595373Y387094D01*
Y394768D01*
X1593899Y396242D01*
Y397942D01*
X1593052Y398789D01*
X1591352D01*
X1588576Y401565D01*
X1580164D01*
X1576296Y405433D01*
G01X1575836Y416948D02*
X1576802D01*
X1586125Y407625D01*
X1592190D01*
X1594665Y410100D01*
X1604494D01*
X1611857Y402737D01*
Y402736D01*
X1619126Y395468D01*
Y394374D01*
X1626200Y387300D01*
Y379900D01*
X1624051Y377751D01*
Y360784D01*
X1628026Y356809D01*
Y354793D01*
X1631268Y351551D01*
X1635244D01*
X1639715Y347080D01*
Y339128D01*
X1646991Y331848D01*
Y315993D01*
X1649211Y313773D01*
Y253618D01*
X1651504Y251325D01*
Y242318D01*
X1663221Y230601D01*
X1675324D01*
X1679305Y226620D01*
X1685972D01*
X1692950Y219643D01*
X1710716D01*
X1716761Y225688D01*
X1726825D01*
X1730135Y228998D01*
Y238443D01*
X1734201Y242509D01*
X1756769D01*
X1758880Y240398D01*
Y238111D01*
X1759279Y237712D01*
X1760554D01*
G01X1575553Y415297D02*
X1576118D01*
X1585441Y405974D01*
X1592874D01*
X1595349Y408449D01*
X1603810D01*
X1606518Y405741D01*
Y404084D01*
X1607507Y403095D01*
X1609164D01*
X1610690Y401569D01*
Y399870D01*
X1611536Y399023D01*
X1613236D01*
X1614082Y398177D01*
Y396477D01*
X1614929Y395630D01*
X1616629D01*
X1617475Y394784D01*
Y393690D01*
X1624549Y386616D01*
Y380584D01*
X1622400Y378435D01*
Y367560D01*
X1621500Y366660D01*
Y365261D01*
X1622400Y364361D01*
Y360100D01*
X1626375Y356125D01*
Y354109D01*
X1630584Y349900D01*
X1634560D01*
X1638064Y346396D01*
Y338444D01*
X1645340Y331164D01*
Y315309D01*
X1647560Y313089D01*
Y252934D01*
X1649853Y250641D01*
Y241634D01*
X1662537Y228950D01*
X1674640D01*
X1678621Y224969D01*
X1685288D01*
X1692266Y217992D01*
X1711400D01*
X1717445Y224037D01*
X1727509D01*
X1731786Y228314D01*
Y237759D01*
X1734885Y240858D01*
X1756085D01*
X1757229Y239714D01*
Y238111D01*
X1756830Y237712D01*
X1755554D01*
G01X1640266Y365500D02*
Y364018D01*
X1639867Y363619D01*
X1637525D01*
X1636624Y364520D01*
Y378586D01*
X1633700Y381510D01*
Y385900D01*
X1628042Y391558D01*
Y404682D01*
X1613353Y419371D01*
X1595822D01*
X1594620Y420573D01*
X1593423D01*
X1592221Y419371D01*
X1585178D01*
X1580871Y423678D01*
X1575133D01*
G01X1640266Y360500D02*
Y361569D01*
X1639867Y361968D01*
X1636841D01*
X1634973Y363836D01*
Y377902D01*
X1632049Y380826D01*
Y385216D01*
X1626391Y390874D01*
Y403998D01*
X1612669Y417720D01*
X1584494D01*
X1580187Y422027D01*
X1575133D01*
G01X1608146Y376171D02*
X1609077Y377102D01*
X1611297D01*
X1612846Y375553D01*
Y347771D01*
X1617578Y343039D01*
X1620577D01*
X1621827Y341789D01*
Y336400D01*
X1625697Y332530D01*
X1629448D01*
X1632815Y329163D01*
Y326716D01*
X1631854Y325755D01*
Y317461D01*
X1634649Y314666D01*
Y309966D01*
X1639260Y305355D01*
Y247522D01*
X1640016Y246766D01*
Y239589D01*
X1659014Y220591D01*
X1669707D01*
X1673739Y216559D01*
X1679646D01*
X1686852Y209353D01*
X1715109D01*
X1721240Y215484D01*
X1798979D01*
X1815607Y232112D01*
Y248823D01*
X1817282Y250498D01*
G01X1608146Y380322D02*
X1609715Y378753D01*
X1611981D01*
X1614497Y376237D01*
Y348455D01*
X1618262Y344690D01*
X1621261D01*
X1623478Y342473D01*
Y337084D01*
X1626381Y334181D01*
X1630132D01*
X1634466Y329847D01*
Y326032D01*
X1633505Y325071D01*
Y318145D01*
X1636300Y315350D01*
Y310650D01*
X1640911Y306039D01*
Y248206D01*
X1641667Y247450D01*
Y240273D01*
X1659698Y222242D01*
X1670391D01*
X1674423Y218210D01*
X1680330D01*
X1687536Y211004D01*
X1714425D01*
X1720556Y217135D01*
X1766074D01*
X1767276Y218337D01*
X1768473D01*
X1769675Y217135D01*
X1770872D01*
X1772074Y218337D01*
X1773271D01*
X1774473Y217135D01*
X1798295D01*
X1813956Y232796D01*
Y248824D01*
X1812282Y250498D01*
G01X1798384D02*
X1796709Y248823D01*
Y246767D01*
X1794950Y245008D01*
X1733102D01*
X1727517Y239423D01*
X1715670D01*
X1712603Y236356D01*
Y225189D01*
X1709564Y222150D01*
X1693978D01*
X1687009Y229119D01*
X1680341D01*
X1676341Y233119D01*
X1664287D01*
X1654069Y243337D01*
Y252429D01*
X1651710Y254788D01*
Y314816D01*
X1649490Y317036D01*
Y348757D01*
X1646926Y351321D01*
Y361442D01*
X1649409Y363925D01*
X1651737D01*
X1652186Y364374D01*
Y365600D01*
G01X1793384Y250498D02*
X1795058Y248824D01*
Y247451D01*
X1794266Y246659D01*
X1772519D01*
X1771317Y247861D01*
X1770120D01*
X1768918Y246659D01*
X1767721D01*
X1766519Y247861D01*
X1765322D01*
X1764120Y246659D01*
X1762923D01*
X1761721Y247861D01*
X1760524D01*
X1759322Y246659D01*
X1758125D01*
X1756923Y247861D01*
X1755726D01*
X1754524Y246659D01*
X1732418D01*
X1726833Y241074D01*
X1721431D01*
X1720229Y242276D01*
X1719032D01*
X1717830Y241074D01*
X1714986D01*
X1710952Y237040D01*
Y225873D01*
X1708880Y223801D01*
X1694662D01*
X1687693Y230770D01*
X1681025D01*
X1677025Y234770D01*
X1664971D01*
X1655720Y244021D01*
Y251745D01*
X1655721Y251746D01*
Y253112D01*
X1653361Y255472D01*
Y315500D01*
X1651141Y317720D01*
Y334722D01*
X1652343Y335924D01*
Y337121D01*
X1651141Y338323D01*
Y339520D01*
X1652343Y340722D01*
Y341919D01*
X1651141Y343121D01*
Y344318D01*
X1652343Y345520D01*
Y346717D01*
X1651141Y347919D01*
Y349441D01*
X1648577Y352005D01*
Y360758D01*
X1650093Y362274D01*
X1651787D01*
X1652186Y361875D01*
Y360600D01*
M02*
